(kicad_pcb
	(version 20260206)
	(generator "pcbnew")
	(generator_version "10.0")
	(general
		(thickness 1.21888)
		(legacy_teardrops no)
	)
	(paper "A4")
	(layers
		(0 "F.Cu" signal "TOP")
		(4 "In1.Cu" signal "SGND")
		(6 "In2.Cu" signal "IN1")
		(8 "In3.Cu" signal "IN2")
		(10 "In4.Cu" signal "SGND1")
		(2 "B.Cu" signal "BOTTOM")
		(9 "F.Adhes" user "F.Adhesive")
		(11 "B.Adhes" user "B.Adhesive")
		(13 "F.Paste" user "Top Paste")
		(15 "B.Paste" user "Bottom Paste")
		(5 "F.SilkS" user "Top Overlay")
		(7 "B.SilkS" user "Bottom Overlay")
		(1 "F.Mask" user "Top Solder")
		(3 "B.Mask" user "Bottom Solder")
		(17 "Dwgs.User" user "User.Drawings")
		(19 "Cmts.User" user "User.Comments")
		(21 "Eco1.User" user "User.Eco1")
		(23 "Eco2.User" user "User.Eco2")
		(25 "Edge.Cuts" user)
		(27 "Margin" user)
		(31 "F.CrtYd" user "Top Courtyard")
		(29 "B.CrtYd" user "Bottom Courtyard")
		(35 "F.Fab" user "Top Component Center")
		(33 "B.Fab" user "Bottom Component Center")
	)
	(setup
		(pad_to_mask_clearance 0.1016)
		(allow_soldermask_bridges_in_footprints no)
		(tenting
			(front yes)
			(back yes)
		)
		(covering
			(front no)
			(back no)
		)
		(plugging
			(front no)
			(back no)
		)
		(capping no)
		(filling no)
		(aux_axis_origin -70.8739 262.2786)
		(grid_origin -70.8739 262.2786)
		(pcbplotparams
			(layerselection 0x00000000_00000000_55555555_5755f5ff)
			(plot_on_all_layers_selection 0x00000000_00000000_00000000_00000000)
			(disableapertmacros no)
			(usegerberextensions no)
			(usegerberattributes yes)
			(usegerberadvancedattributes yes)
			(creategerberjobfile yes)
			(dashed_line_dash_ratio 12)
			(dashed_line_gap_ratio 3)
			(svgprecision 4)
			(plotframeref no)
			(mode 1)
			(useauxorigin no)
			(pdf_front_fp_property_popups yes)
			(pdf_back_fp_property_popups yes)
			(pdf_metadata yes)
			(pdf_single_document no)
			(dxfpolygonmode yes)
			(dxfimperialunits yes)
			(dxfusepcbnewfont yes)
			(psnegative no)
			(psa4output no)
			(plot_black_and_white yes)
			(sketchpadsonfab no)
			(plotpadnumbers no)
			(hidednponfab no)
			(sketchdnponfab yes)
			(crossoutdnponfab yes)
			(subtractmaskfromsilk no)
			(outputformat 1)
			(mirror no)
			(drillshape 1)
			(scaleselection 1)
			(outputdirectory "")
		)
	)
	(footprint "Vault:RESC1608X55X30NL15T15"
		(layer "F.Cu")
		(at 82.3761 112.1162 -90)
		(property "Reference" "R30"
			(at 4 -0.593345 90)
			(unlocked yes)
			(layer "F.SilkS")
			(effects
				(font
					(size 0.762 0.762)
					(thickness 0.2286)
				)
				(justify left bottom)
			)
		)
		(property "Value" "4.7K"
			(at 3.72999 0.4445 0)
			(unlocked yes)
			(layer "F.SilkS")
			(hide yes)
			(effects
				(font
					(size 1.524 1.524)
					(thickness 0.254)
				)
				(justify left bottom)
			)
		)
		(sheetname "USER_IO")
		(sheetfile "USER_IO.kicad_sch")
		(duplicate_pad_numbers_are_jumpers no)
		(pad "1" smd rect
			(at -0.75 0)
			(size 0.95 0.95)
			(layers "F.Cu" "F.Mask" "F.Paste")
			(net "ANT2_IO_IN")
		)
		(pad "2" smd rect
			(at 0.75 0)
			(size 0.95 0.95)
			(layers "F.Cu" "F.Mask" "F.Paste")
			(net "+3.3V")
		)
	)
	(footprint "SA53:SA53"
		(locked yes)
		(layer "F.Cu")
		(at 120.49358 116.5662 180)
		(property "Reference" "U10"
			(at -22.46112 27.623069 0)
			(unlocked yes)
			(layer "F.SilkS")
			(effects
				(font
					(size 0.762 0.762)
					(thickness 0.2286)
				)
			)
		)
		(property "Value" "MAC-SA5X"
			(at -18.30259 28.464002 180)
			(unlocked yes)
			(layer "F.SilkS")
			(hide yes)
			(effects
				(font
					(size 1.524 1.524)
					(thickness 0.254)
				)
			)
		)
		(sheetname "MAC")
		(sheetfile "MAC.kicad_sch")
		(duplicate_pad_numbers_are_jumpers no)
		(fp_line
			(start 26.26748 26.75)
			(end -24.53252 26.75)
			(stroke
				(width 0.254)
				(type solid)
			)
			(layer "F.SilkS")
		)
		(fp_line
			(start 26.26748 -24.05)
			(end 26.26748 26.75)
			(stroke
				(width 0.254)
				(type solid)
			)
			(layer "F.SilkS")
		)
		(fp_line
			(start 26.26748 -24.05)
			(end -24.53252 -24.05)
			(stroke
				(width 0.254)
				(type solid)
			)
			(layer "F.SilkS")
		)
		(fp_line
			(start -24.53252 -24.05)
			(end -24.53252 26.75)
			(stroke
				(width 0.254)
				(type solid)
			)
			(layer "F.SilkS")
		)
		(fp_circle
			(center -15.74749 3.64128)
			(end -15.74749 3.76828)
			(stroke
				(width 0.254)
				(type solid)
			)
			(fill no)
			(layer "F.SilkS")
		)
		(pad "1" smd rect
			(at -17.16749 3.64128 270)
			(size 0.25 1.8)
			(layers "F.Cu" "F.Mask" "F.Paste")
			(net "MAC_PPS_IN1+")
		)
		(pad "2" smd rect
			(at -21.16749 3.64128 270)
			(size 0.25 1.8)
			(layers "F.Cu" "F.Mask" "F.Paste")
			(net "MAC_USB+")
		)
		(pad "3" smd rect
			(at -17.16749 3.13328 270)
			(size 0.25 1.8)
			(layers "F.Cu" "F.Mask" "F.Paste")
			(net "MAC_PPS_IN1-")
		)
		(pad "4" smd rect
			(at -21.16749 3.13328 270)
			(size 0.25 1.8)
			(layers "F.Cu" "F.Mask" "F.Paste")
			(net "MAC_USB-")
		)
		(pad "5" smd rect
			(at -17.16749 2.62528 270)
			(size 0.25 1.8)
			(layers "F.Cu" "F.Mask" "F.Paste")
			(net "MAC_PPS_IN0+")
		)
		(pad "6" smd rect
			(at -21.16749 2.62528 270)
			(size 0.25 1.8)
			(layers "F.Cu" "F.Mask" "F.Paste")
			(net "MAC_USB_PWR")
		)
		(pad "7" smd rect
			(at -17.16749 2.11728 270)
			(size 0.25 1.8)
			(layers "F.Cu" "F.Mask" "F.Paste")
			(net "MAC_PPS_IN0-")
		)
		(pad "8" smd rect
			(at -21.16749 2.11728 270)
			(size 0.25 1.8)
			(layers "F.Cu" "F.Mask" "F.Paste")
			(net "GND")
		)
		(pad "9" smd rect
			(at -17.16749 1.60928 270)
			(size 0.25 1.8)
			(layers "F.Cu" "F.Mask" "F.Paste")
			(net "GND")
		)
		(pad "10" smd rect
			(at -21.16749 1.60928 270)
			(size 0.25 1.8)
			(layers "F.Cu" "F.Mask" "F.Paste")
		)
		(pad "11" smd rect
			(at -17.16749 1.10128 270)
			(size 0.25 1.8)
			(layers "F.Cu" "F.Mask" "F.Paste")
		)
		(pad "12" smd rect
			(at -21.16749 1.10128 270)
			(size 0.25 1.8)
			(layers "F.Cu" "F.Mask" "F.Paste")
		)
		(pad "13" smd rect
			(at -17.16749 0.59328 270)
			(size 0.25 1.8)
			(layers "F.Cu" "F.Mask" "F.Paste")
		)
		(pad "14" smd rect
			(at -21.16749 0.59328 270)
			(size 0.25 1.8)
			(layers "F.Cu" "F.Mask" "F.Paste")
		)
		(pad "15" smd rect
			(at -17.16749 0.08528 270)
			(size 0.25 1.8)
			(layers "F.Cu" "F.Mask" "F.Paste")
			(net "GND")
		)
		(pad "16" smd rect
			(at -21.16749 0.08528 270)
			(size 0.25 1.8)
			(layers "F.Cu" "F.Mask" "F.Paste")
		)
		(pad "17" smd rect
			(at -17.16749 -0.42272 270)
			(size 0.25 1.8)
			(layers "F.Cu" "F.Mask" "F.Paste")
			(net "MAC_PPS_OUT+")
		)
		(pad "18" smd rect
			(at -21.16749 -0.42272 270)
			(size 0.25 1.8)
			(layers "F.Cu" "F.Mask" "F.Paste")
		)
		(pad "19" smd rect
			(at -17.16749 -0.93072 270)
			(size 0.25 1.8)
			(layers "F.Cu" "F.Mask" "F.Paste")
			(net "MAC_PPS_OUT-")
		)
		(pad "20" smd rect
			(at -21.16749 -0.93072 270)
			(size 0.25 1.8)
			(layers "F.Cu" "F.Mask" "F.Paste")
			(net "MAC_ALARM")
		)
		(pad "P1" thru_hole circle
			(at 21.16748 21.65 90)
			(size 1.905 1.905)
			(drill 1.27)
			(layers "*.Cu" "*.Mask")
			(remove_unused_layers no)
			(net "MAC_FREQ_CTRL")
			(thermal_bridge_angle 90)
		)
		(pad "P2" thru_hole circle
			(at 21.16748 1.35 90)
			(size 1.905 1.905)
			(drill 1.27)
			(layers "*.Cu" "*.Mask")
			(remove_unused_layers no)
			(net "GND")
			(thermal_bridge_angle 90)
		)
		(pad "P3" thru_hole circle
			(at 21.16748 -18.95 90)
			(size 1.905 1.905)
			(drill 1.27)
			(layers "*.Cu" "*.Mask")
			(remove_unused_layers no)
			(net "MAC_RF_OUT")
			(thermal_bridge_angle 90)
		)
		(pad "P4" thru_hole circle
			(at -19.43252 -18.95 90)
			(size 1.905 1.905)
			(drill 1.27)
			(layers "*.Cu" "*.Mask")
			(remove_unused_layers no)
			(net "GND")
			(thermal_bridge_angle 90)
		)
		(pad "P5" thru_hole circle
			(at -19.43252 21.65 90)
			(size 1.905 1.905)
			(drill 1.27)
			(layers "*.Cu" "*.Mask")
			(remove_unused_layers no)
			(net "MAC_VCC")
			(thermal_bridge_angle 90)
		)
		(pad "P6" thru_hole circle
			(at -17.33252 -21.65 90)
			(size 1.905 1.905)
			(drill 1.27)
			(layers "*.Cu" "*.Mask")
			(remove_unused_layers no)
			(net "MAC_BITE")
			(thermal_bridge_angle 90)
		)
		(pad "P7" thru_hole circle
			(at -14.33252 -21.65 90)
			(size 1.905 1.905)
			(drill 1.27)
			(layers "*.Cu" "*.Mask")
			(remove_unused_layers no)
			(net "MAC_RX")
			(thermal_bridge_angle 90)
		)
		(pad "P8" thru_hole circle
			(at -11.33252 -21.65 90)
			(size 1.905 1.905)
			(drill 1.27)
			(layers "*.Cu" "*.Mask")
			(remove_unused_layers no)
			(net "MAC_TX")
			(thermal_bridge_angle 90)
		)
		(pad "P9" thru_hole circle
			(at -8.28452 -21.65 90)
			(size 1.905 1.905)
			(drill 1.27)
			(layers "*.Cu" "*.Mask")
			(remove_unused_layers no)
			(net "MAC_PPS_IN")
			(thermal_bridge_angle 90)
		)
		(pad "P10" thru_hole circle
			(at -5.23652 -21.65 90)
			(size 1.905 1.905)
			(drill 1.27)
			(layers "*.Cu" "*.Mask")
			(remove_unused_layers no)
			(net "MAC_PPS_OUT")
			(thermal_bridge_angle 90)
		)
		(zone
			(layer "F.Cu")
			(hatch edge 0.5)
			(connect_pads
				(clearance 0)
			)
			(min_thickness 0.25)
			(keepout
				(tracks allowed)
				(vias allowed)
				(pads allowed)
				(copperpour not_allowed)
				(footprints allowed)
			)
			(placement
				(enabled no)
				(sheetname "")
			)
			(fill
				(thermal_gap 0.5)
				(thermal_bridge_width 0.5)
				(island_removal_mode 0)
			)
			(polygon
				(pts
					(xy 123.99358 134.0662) (xy 141.49359 134.0662) (xy 141.49359 140.0662) (xy 123.99358 140.0662)
				)
			)
		)
		(zone
			(layer "F.Cu")
			(hatch edge 0.5)
			(connect_pads
				(clearance 0)
			)
			(min_thickness 0.25)
			(keepout
				(tracks allowed)
				(vias allowed)
				(pads allowed)
				(copperpour not_allowed)
				(footprints allowed)
			)
			(placement
				(enabled no)
				(sheetname "")
			)
			(fill
				(thermal_gap 0.5)
				(thermal_bridge_width 0.5)
				(island_removal_mode 0)
			)
			(polygon
				(pts
					(xy 135.99358 120.0662) (xy 135.99359 110.0662) (xy 143.49359 110.0662) (xy 143.49358 120.0662)
				)
			)
		)
	)
	(footprint "Capacitors:CAPC2012X14N"
		(layer "F.Cu")
		(at 221.3637 90.9662)
		(property "Reference" "C8"
			(at 3 0.393345 0)
			(unlocked yes)
			(layer "F.SilkS")
			(effects
				(font
					(size 0.762 0.762)
					(thickness 0.2286)
				)
				(justify left bottom)
			)
		)
		(property "Value" "CAP_0805_10UF_25V"
			(at -2.6911 12.35119 0)
			(unlocked yes)
			(layer "F.SilkS")
			(hide yes)
			(effects
				(font
					(size 1.524 1.524)
					(thickness 0.254)
				)
				(justify left bottom)
			)
		)
		(sheetname "POWER")
		(sheetfile "POWER.kicad_sch")
		(duplicate_pad_numbers_are_jumpers no)
		(fp_line
			(start -0.762 -0.9652)
			(end 0.762 -0.9652)
			(stroke
				(width 0.1524)
				(type solid)
			)
			(layer "F.SilkS")
		)
		(fp_line
			(start -0.762 0.9652)
			(end 0.762 0.9652)
			(stroke
				(width 0.1524)
				(type solid)
			)
			(layer "F.SilkS")
		)
		(pad "1" smd rect
			(at -0.9 0 90)
			(size 1.45 1.15)
			(layers "F.Cu" "F.Mask" "F.Paste")
			(net "+3.3V")
		)
		(pad "2" smd rect
			(at 0.9 0 90)
			(size 1.45 1.15)
			(layers "F.Cu" "F.Mask" "F.Paste")
			(net "GND")
		)
	)
	(footprint "Passives:SOT65P210X110-3N"
		(layer "F.Cu")
		(at 224.9261 137.6162 -90)
		(property "Reference" "D8"
			(at -1.906655 -1.3 0)
			(unlocked yes)
			(layer "F.SilkS")
			(effects
				(font
					(size 0.762 0.762)
					(thickness 0.2286)
				)
				(justify left bottom)
			)
		)
		(property "Value" "BAT54SW"
			(at 7.49479 -2.7501 0)
			(unlocked yes)
			(layer "F.SilkS")
			(hide yes)
			(effects
				(font
					(size 1.524 1.524)
					(thickness 0.254)
				)
				(justify left bottom)
			)
		)
		(sheetname "PCIe_JTAG")
		(sheetfile "PCIe_JTAG.kicad_sch")
		(duplicate_pad_numbers_are_jumpers no)
		(fp_line
			(start 0.675 1.1)
			(end -0.325 1.1)
			(stroke
				(width 0.2)
				(type solid)
			)
			(layer "F.SilkS")
		)
		(fp_line
			(start 0.675 1.1)
			(end 0.675 0.65)
			(stroke
				(width 0.2)
				(type solid)
			)
			(layer "F.SilkS")
		)
		(fp_line
			(start 0.675 -0.65)
			(end 0.675 -1.1)
			(stroke
				(width 0.2)
				(type solid)
			)
			(layer "F.SilkS")
		)
		(fp_line
			(start 0.675 -1.1)
			(end -0.325 -1.1)
			(stroke
				(width 0.2)
				(type solid)
			)
			(layer "F.SilkS")
		)
		(fp_circle
			(center -1.125 -1.45)
			(end -1.25 -1.45)
			(stroke
				(width 0.25)
				(type solid)
			)
			(fill no)
			(layer "F.SilkS")
		)
		(pad "1" smd rect
			(at -1.125 -0.65)
			(size 0.5 0.9)
			(layers "F.Cu" "F.Mask" "F.Paste")
			(net "GND")
		)
		(pad "2" smd rect
			(at -1.125 0.65)
			(size 0.5 0.9)
			(layers "F.Cu" "F.Mask" "F.Paste")
			(net "+3.3V")
		)
		(pad "3" smd rect
			(at 1.125 0)
			(size 0.5 0.9)
			(layers "F.Cu" "F.Mask" "F.Paste")
			(net "FPGA_TDI")
		)
	)
	(footprint "Vault:RESC1608X55X30NL15T15"
		(layer "F.Cu")
		(at 82.1261 139.6162 -90)
		(property "Reference" "R32"
			(at 2.7714 -0.026921 90)
			(unlocked yes)
			(layer "F.SilkS")
			(effects
				(font
					(size 0.762 0.762)
					(thickness 0.2286)
				)
			)
		)
		(property "Value" "4.7K"
			(at -3.114792 2.39944 180)
			(unlocked yes)
			(layer "F.SilkS")
			(hide yes)
			(effects
				(font
					(size 1.524 1.524)
					(thickness 0.254)
				)
			)
		)
		(sheetname "USER_IO")
		(sheetfile "USER_IO.kicad_sch")
		(duplicate_pad_numbers_are_jumpers no)
		(pad "1" smd rect
			(at -0.75 0)
			(size 0.95 0.95)
			(layers "F.Cu" "F.Mask" "F.Paste")
			(net "ANT4_IO_IN")
		)
		(pad "2" smd rect
			(at 0.75 0)
			(size 0.95 0.95)
			(layers "F.Cu" "F.Mask" "F.Paste")
			(net "+3.3V")
		)
	)
	(footprint "Vault:SOT143-4L"
		(layer "F.Cu")
		(at 71.8761 128.1162 90)
		(property "Reference" "D2"
			(at -2.926921 1.178595 0)
			(unlocked yes)
			(layer "F.SilkS")
			(effects
				(font
					(size 0.762 0.762)
					(thickness 0.2286)
				)
			)
		)
		(property "Value" "8240136"
			(at 2.7035 3.368802 90)
			(unlocked yes)
			(layer "F.SilkS")
			(hide yes)
			(effects
				(font
					(size 1.524 1.524)
					(thickness 0.254)
				)
			)
		)
		(sheetname "USER_IO")
		(sheetfile "USER_IO.kicad_sch")
		(duplicate_pad_numbers_are_jumpers no)
		(fp_line
			(start 2.05 -1.7)
			(end 2.05 1.7)
			(stroke
				(width 0.2)
				(type solid)
			)
			(layer "F.SilkS")
		)
		(fp_line
			(start -2.05 -1.7)
			(end 2.05 -1.7)
			(stroke
				(width 0.2)
				(type solid)
			)
			(layer "F.SilkS")
		)
		(fp_line
			(start -2.05 -1.7)
			(end -2.05 1.675)
			(stroke
				(width 0.2)
				(type solid)
			)
			(layer "F.SilkS")
		)
		(fp_line
			(start -2.05 1.7)
			(end 2.05 1.7)
			(stroke
				(width 0.2)
				(type solid)
			)
			(layer "F.SilkS")
		)
		(fp_circle
			(center -2.404 -1.075)
			(end -2.15 -1.075)
			(stroke
				(width 0.2)
				(type solid)
			)
			(fill no)
			(layer "F.SilkS")
		)
		(pad "1" smd rect
			(at -1.1 -0.75 180)
			(size 1.4 1.4)
			(layers "F.Cu" "F.Mask" "F.Paste")
			(net "GND")
		)
		(pad "2" smd rect
			(at -1.1 0.95 180)
			(size 1 1.4)
			(layers "F.Cu" "F.Mask" "F.Paste")
			(net "NetAN4_1")
		)
		(pad "3" smd rect
			(at 1.1 0.95 180)
			(size 1 1.4)
			(layers "F.Cu" "F.Mask" "F.Paste")
			(net "NetAN3_1")
		)
		(pad "4" smd rect
			(at 1.1 -0.95 180)
			(size 1 1.4)
			(layers "F.Cu" "F.Mask" "F.Paste")
			(net "+3.3V")
		)
	)
	(footprint "Vault:CAPC1608X87X45ML20T05"
		(layer "F.Cu")
		(at 214.7435 116.3062 90)
		(property "Reference" "C16"
			(at 1.74 0.638345 90)
			(unlocked yes)
			(layer "F.SilkS")
			(effects
				(font
					(size 0.762 0.762)
					(thickness 0.2286)
				)
				(justify left bottom)
			)
		)
		(property "Value" "0.1uF"
			(at -6.58639 -2.4645 0)
			(unlocked yes)
			(layer "F.SilkS")
			(hide yes)
			(effects
				(font
					(size 1.524 1.524)
					(thickness 0.254)
				)
				(justify left bottom)
			)
		)
		(sheetname "POWER")
		(sheetfile "POWER.kicad_sch")
		(duplicate_pad_numbers_are_jumpers no)
		(pad "1" smd rect
			(at -0.7 0 180)
			(size 1.1 1.05)
			(layers "F.Cu" "F.Mask" "F.Paste")
			(net "GND")
		)
		(pad "2" smd rect
			(at 0.7 0 180)
			(size 1.1 1.05)
			(layers "F.Cu" "F.Mask" "F.Paste")
			(net "+5.0V")
		)
	)
	(footprint "Vault:FP-BME280-MFG"
		(layer "F.Cu")
		(at 194.1261 86.8286)
		(property "Reference" "U14"
			(at -0.5214 2.776921 0)
			(unlocked yes)
			(layer "F.SilkS")
			(effects
				(font
					(size 0.762 0.762)
					(thickness 0.2286)
				)
			)
		)
		(property "Value" "BME280"
			(at 2.932305 3.470402 0)
			(unlocked yes)
			(layer "F.SilkS")
			(hide yes)
			(effects
				(font
					(size 1.524 1.524)
					(thickness 0.254)
				)
			)
		)
		(sheetname "GPS_IMU_SENSORS")
		(sheetfile "GPS_IMU_SENSORS.kicad_sch")
		(duplicate_pad_numbers_are_jumpers no)
		(fp_line
			(start -1.3 -1.55)
			(end 1.3 -1.55)
			(stroke
				(width 0.2)
				(type solid)
			)
			(layer "F.SilkS")
		)
		(fp_line
			(start -1.3 1.55)
			(end 1.3 1.55)
			(stroke
				(width 0.2)
				(type solid)
			)
			(layer "F.SilkS")
		)
		(fp_circle
			(center 1.85 -0.975)
			(end 1.85 -1.1)
			(stroke
				(width 0.25)
				(type solid)
			)
			(fill no)
			(layer "F.SilkS")
		)
		(fp_line
			(start -1.8 -1.8)
			(end 1.8 -1.8)
			(stroke
				(width 0.2)
				(type solid)
			)
			(layer "F.CrtYd")
		)
		(fp_line
			(start -1.8 1.8)
			(end -1.8 -1.8)
			(stroke
				(width 0.2)
				(type solid)
			)
			(layer "F.CrtYd")
		)
		(fp_line
			(start -1.8 1.8)
			(end 1.8 1.8)
			(stroke
				(width 0.2)
				(type solid)
			)
			(layer "F.CrtYd")
		)
		(fp_line
			(start 1.8 1.8)
			(end 1.8 -1.8)
			(stroke
				(width 0.2)
				(type solid)
			)
			(layer "F.CrtYd")
		)
		(fp_line
			(start -1.8 -1.8)
			(end 1.8 -1.8)
			(stroke
				(width 0.2)
				(type solid)
			)
			(layer "F.Fab")
		)
		(fp_line
			(start -1.8 1.8)
			(end -1.8 -1.8)
			(stroke
				(width 0.2)
				(type solid)
			)
			(layer "F.Fab")
		)
		(fp_line
			(start -1.8 1.8)
			(end 1.8 1.8)
			(stroke
				(width 0.2)
				(type solid)
			)
			(layer "F.Fab")
		)
		(fp_line
			(start -0.5 0)
			(end 0.5 0)
			(stroke
				(width 0.1)
				(type solid)
			)
			(layer "F.Fab")
		)
		(fp_line
			(start 0 0.5)
			(end 0 -0.5)
			(stroke
				(width 0.1)
				(type solid)
			)
			(layer "F.Fab")
		)
		(fp_line
			(start 1.8 1.8)
			(end 1.8 -1.8)
			(stroke
				(width 0.2)
				(type solid)
			)
			(layer "F.Fab")
		)
		(fp_text user "${REFERENCE}"
			(at 0 0.28425 0)
			(unlocked yes)
			(layer "F.Fab")
			(effects
				(font
					(face "Arial")
					(size 0.63 0.63)
					(thickness 0.1)
				)
				(justify left bottom)
			)
		)
		(pad "1" smd rect
			(at 1.025 -0.975)
			(size 0.5 0.35)
			(layers "F.Cu" "F.Mask" "F.Paste")
			(net "GND")
			(solder_mask_margin 0)
			(solder_paste_margin 0)
		)
		(pad "2" smd rect
			(at 1.025 -0.325)
			(size 0.5 0.35)
			(layers "F.Cu" "F.Mask" "F.Paste")
			(net "+3.3V")
			(solder_mask_margin 0)
			(solder_paste_margin 0)
		)
		(pad "3" smd rect
			(at 1.025 0.325)
			(size 0.5 0.35)
			(layers "F.Cu" "F.Mask" "F.Paste")
			(net "SDA")
			(solder_mask_margin 0)
			(solder_paste_margin 0)
		)
		(pad "4" smd rect
			(at 1.025 0.975)
			(size 0.5 0.35)
			(layers "F.Cu" "F.Mask" "F.Paste")
			(net "SCL")
			(solder_mask_margin 0)
			(solder_paste_margin 0)
		)
		(pad "5" smd rect
			(at -1.025 0.975)
			(size 0.5 0.35)
			(layers "F.Cu" "F.Mask" "F.Paste")
			(net "GND")
			(solder_mask_margin 0)
			(solder_paste_margin 0)
		)
		(pad "6" smd rect
			(at -1.025 0.325)
			(size 0.5 0.35)
			(layers "F.Cu" "F.Mask" "F.Paste")
			(net "+3.3V")
			(solder_mask_margin 0)
			(solder_paste_margin 0)
		)
		(pad "7" smd rect
			(at -1.025 -0.325)
			(size 0.5 0.35)
			(layers "F.Cu" "F.Mask" "F.Paste")
			(net "GND")
			(solder_mask_margin 0)
			(solder_paste_margin 0)
		)
		(pad "8" smd rect
			(at -1.025 -0.975)
			(size 0.5 0.35)
			(layers "F.Cu" "F.Mask" "F.Paste")
			(net "+3.3V")
			(solder_mask_margin 0)
			(solder_paste_margin 0)
		)
	)
	(footprint "Resistors:RESC1608X50N"
		(layer "F.Cu")
		(at 211.0605 110.9722 90)
		(property "Reference" "R4"
			(at -0.619 1.771345 90)
			(unlocked yes)
			(layer "F.SilkS")
			(effects
				(font
					(size 0.762 0.762)
					(thickness 0.2286)
				)
				(justify left bottom)
			)
		)
		(property "Value" "ERJ-3EKF4702V"
			(at -4.12259 1.7773 0)
			(unlocked yes)
			(layer "F.SilkS")
			(hide yes)
			(effects
				(font
					(size 1.524 1.524)
					(thickness 0.254)
				)
				(justify left bottom)
			)
		)
		(sheetname "POWER")
		(sheetfile "POWER.kicad_sch")
		(duplicate_pad_numbers_are_jumpers no)
		(fp_line
			(start 0 -0.5)
			(end 0 0.5)
			(stroke
				(width 0.1524)
				(type solid)
			)
			(layer "F.SilkS")
		)
		(pad "1" smd rect
			(at -0.69 0 180)
			(size 1 0.72)
			(layers "F.Cu" "F.Mask" "F.Paste")
			(net "+5.0V")
		)
		(pad "2" smd rect
			(at 0.69 0 180)
			(size 1 0.72)
			(layers "F.Cu" "F.Mask" "F.Paste")
			(net "NetR4_2")
		)
	)
	(footprint "Connectors:39-30-1060"
		(layer "F.Cu")
		(at 221.6261 96.1162 90)
		(property "Reference" "J38"
			(at -11.2 -2.006655 90)
			(unlocked yes)
			(layer "F.SilkS")
			(effects
				(font
					(size 0.762 0.762)
					(thickness 0.2286)
				)
				(justify left bottom)
			)
		)
		(property "Value" "39-30-1060"
			(at -20.89579 -1.5141 0)
			(unlocked yes)
			(layer "F.SilkS")
			(hide yes)
			(effects
				(font
					(size 1.524 1.524)
					(thickness 0.254)
				)
				(justify left bottom)
			)
		)
		(sheetname "POWER")
		(sheetfile "POWER.kicad_sch")
		(duplicate_pad_numbers_are_jumpers no)
		(fp_line
			(start 3.175 -1.524)
			(end 3.175 19.49249)
			(stroke
				(width 0.2032)
				(type solid)
			)
			(layer "F.SilkS")
		)
		(fp_line
			(start -11.02502 -1.524)
			(end 3.175 -1.524)
			(stroke
				(width 0.2032)
				(type solid)
			)
			(layer "F.SilkS")
		)
		(fp_line
			(start -11.02502 -1.51445)
			(end -11.02502 -0.44249)
			(stroke
				(width 0.203)
				(type solid)
			)
			(layer "F.SilkS")
		)
		(fp_line
			(start -11.02502 -0.44249)
			(end -11.02502 19.49249)
			(stroke
				(width 0.2032)
				(type solid)
			)
			(layer "F.SilkS")
		)
		(pad "" np_thru_hole circle
			(at -8.4 12.8 90)
			(size 1.27 1.27)
			(drill 3)
			(layers "*.Cu" "*.Mask")
			(thermal_bridge_angle 90)
		)
		(pad "" np_thru_hole circle
			(at 0 12.8 90)
			(size 1.27 1.27)
			(drill 3)
			(layers "*.Cu" "*.Mask")
			(thermal_bridge_angle 90)
			(padstack
				(mode front_inner_back)
				(layer "Inner"
					(shape circle)
					(size 1.27 1.27)
				)
				(layer "B.Cu"
					(shape circle)
					(size 1.27 1.27)
				)
			)
		)
		(pad "1" thru_hole circle
			(at 0 5.5 180)
			(size 2.5 2.5)
			(drill 1.8)
			(layers "*.Cu" "*.Mask")
			(remove_unused_layers no)
			(net "NetD12_2")
			(thermal_bridge_angle 90)
		)
		(pad "2" thru_hole circle
			(at -4.2 5.5 180)
			(size 2.5 2.5)
			(drill 1.8)
			(layers "*.Cu" "*.Mask")
			(remove_unused_layers no)
			(net "NetD12_2")
			(thermal_bridge_angle 90)
		)
		(pad "3" thru_hole circle
			(at -8.4 5.5 180)
			(size 2.5 2.5)
			(drill 1.8)
			(layers "*.Cu" "*.Mask")
			(remove_unused_layers no)
			(net "NetD12_2")
			(thermal_bridge_angle 90)
		)
		(pad "4" thru_hole circle
			(at 0 0 180)
			(size 2.5 2.5)
			(drill 1.8)
			(layers "*.Cu" "*.Mask")
			(remove_unused_layers no)
			(net "GND")
			(thermal_bridge_angle 90)
		)
		(pad "5" thru_hole circle
			(at -4.2 0 180)
			(size 2.5 2.5)
			(drill 1.8)
			(layers "*.Cu" "*.Mask")
			(remove_unused_layers no)
			(net "GND")
			(thermal_bridge_angle 90)
		)
		(pad "6" thru_hole circle
			(at -8.4 0 180)
			(size 2.5 2.5)
			(drill 1.8)
			(layers "*.Cu" "*.Mask")
			(remove_unused_layers no)
			(net "GND")
			(thermal_bridge_angle 90)
		)
	)
	(footprint "IntegratedCircuits:SOIC127P600X175-8N"
		(layer "F.Cu")
		(at 205.1917 88.2392 90)
		(property "Reference" "U2"
			(at 6.13379 -2.264865 270)
			(unlocked yes)
			(layer "F.SilkS")
			(effects
				(font
					(size 0.762 0.762)
					(thickness 0.2286)
				)
				(justify left bottom)
			)
		)
		(property "Value" "MP1482DS-LF"
			(at -9.52079 10.9955 0)
			(unlocked yes)
			(layer "F.SilkS")
			(hide yes)
			(effects
				(font
					(size 1.524 1.524)
					(thickness 0.254)
				)
				(justify left bottom)
			)
		)
		(sheetname "POWER")
		(sheetfile "POWER.kicad_sch")
		(duplicate_pad_numbers_are_jumpers no)
		(fp_line
			(start -3.4 -2.5)
			(end 2 -2.5)
			(stroke
				(width 0.12)
				(type solid)
			)
			(layer "F.SilkS")
		)
		(fp_line
			(start -2 2.5)
			(end 2 2.5)
			(stroke
				(width 0.12)
				(type solid)
			)
			(layer "F.SilkS")
		)
		(pad "1" smd rect
			(at -2.475 -1.905 90)
			(size 1.97 0.57)
			(layers "F.Cu" "F.Mask" "F.Paste")
			(net "NetC3_1")
		)
		(pad "2" smd rect
			(at -2.475 -0.635 90)
			(size 1.97 0.57)
			(layers "F.Cu" "F.Mask" "F.Paste")
			(net "+12V")
		)
		(pad "3" smd rect
			(at -2.475 0.635 90)
			(size 1.97 0.57)
			(layers "F.Cu" "F.Mask" "F.Paste")
			(net "NetC3_2")
		)
		(pad "4" smd rect
			(at -2.475 1.905 90)
			(size 1.97 0.57)
			(layers "F.Cu" "F.Mask" "F.Paste")
			(net "GND")
		)
		(pad "5" smd rect
			(at 2.475 1.905 90)
			(size 1.97 0.57)
			(layers "F.Cu" "F.Mask" "F.Paste")
			(net "NetR5_1")
		)
		(pad "6" smd rect
			(at 2.475 0.635 90)
			(size 1.97 0.57)
			(layers "F.Cu" "F.Mask" "F.Paste")
			(net "NetC22_2")
		)
		(pad "7" smd rect
			(at 2.475 -0.635 90)
			(size 1.97 0.57)
			(layers "F.Cu" "F.Mask" "F.Paste")
			(net "NetR3_1")
		)
		(pad "8" smd rect
			(at 2.475 -1.905 90)
			(size 1.97 0.57)
			(layers "F.Cu" "F.Mask" "F.Paste")
			(net "NetC21_2")
		)
	)
	(footprint "Vault:RESC1608X55X30NL15T15"
		(layer "F.Cu")
		(at 73.3761 55.6162 90)
		(property "Reference" "R38"
			(at -5.7714 0.026921 90)
			(unlocked yes)
			(layer "F.SilkS")
			(effects
				(font
					(size 0.762 0.762)
					(thickness 0.2286)
				)
			)
		)
		(property "Value" "200 OHM"
			(at -2.962402 4.81166 0)
			(unlocked yes)
			(layer "F.SilkS")
			(hide yes)
			(effects
				(font
					(size 1.524 1.524)
					(thickness 0.254)
				)
			)
		)
		(sheetname "USER_IO_STATUS")
		(sheetfile "USER_IO_STATUS.kicad_sch")
		(duplicate_pad_numbers_are_jumpers no)
		(pad "1" smd rect
			(at -0.675 0 180)
			(size 0.95 0.8)
			(layers "F.Cu" "F.Mask" "F.Paste")
			(net "LED3")
		)
		(pad "2" smd rect
			(at 0.675 0 180)
			(size 0.95 0.8)
			(layers "F.Cu" "F.Mask" "F.Paste")
			(net "NetD10_1")
		)
	)
	(footprint "Vault:RESC1609X50X30NL10T20"
		(layer "F.Cu")
		(at 113.8761 84.8286 -90)
		(property "Reference" "R12"
			(at 2.2714 -0.026931 90)
			(unlocked yes)
			(layer "F.SilkS")
			(effects
				(font
					(size 0.762 0.762)
					(thickness 0.2286)
				)
			)
		)
		(property "Value" "110R"
			(at -2.911602 2.27248 180)
			(unlocked yes)
			(layer "F.SilkS")
			(hide yes)
			(effects
				(font
					(size 1.524 1.524)
					(thickness 0.254)
				)
			)
		)
		(sheetname "MAC")
		(sheetfile "MAC.kicad_sch")
		(duplicate_pad_numbers_are_jumpers no)
		(pad "1" smd rect
			(at -0.625 0)
			(size 0.95 0.8)
			(layers "F.Cu" "F.Mask" "F.Paste")
			(net "MAC_PPS_OUT-")
		)
		(pad "2" smd rect
			(at 0.625 0)
			(size 0.95 0.8)
			(layers "F.Cu" "F.Mask" "F.Paste")
			(net "MAC_PPS_OUT+")
		)
	)
	(footprint "Capacitors:CAPC2012X14N"
		(layer "F.Cu")
		(at 200.8737 90.2712 180)
		(property "Reference" "C5"
			(at 3.41 -0.488345 0)
			(unlocked yes)
			(layer "F.SilkS")
			(effects
				(font
					(size 0.762 0.762)
					(thickness 0.2286)
				)
				(justify left bottom)
			)
		)
		(property "Value" "CAP_0805_10UF_25V"
			(at -15.2119 -1.41819 0)
			(unlocked yes)
			(layer "F.SilkS")
			(hide yes)
			(effects
				(font
					(size 1.524 1.524)
					(thickness 0.254)
				)
				(justify left bottom)
			)
		)
		(sheetname "POWER")
		(sheetfile "POWER.kicad_sch")
		(duplicate_pad_numbers_are_jumpers no)
		(fp_line
			(start 0.762 0.9652)
			(end -0.762 0.9652)
			(stroke
				(width 0.1524)
				(type solid)
			)
			(layer "F.SilkS")
		)
		(fp_line
			(start 0.762 -0.9652)
			(end -0.762 -0.9652)
			(stroke
				(width 0.1524)
				(type solid)
			)
			(layer "F.SilkS")
		)
		(pad "1" smd rect
			(at -0.9 0 270)
			(size 1.45 1.15)
			(layers "F.Cu" "F.Mask" "F.Paste")
			(net "+12V")
		)
		(pad "2" smd rect
			(at 0.9 0 270)
			(size 1.45 1.15)
			(layers "F.Cu" "F.Mask" "F.Paste")
			(net "GND")
		)
	)
	(footprint "Capacitors:CAPC2012X14N"
		(layer "F.Cu")
		(at 218.2995 116.1792 -90)
		(property "Reference" "C14"
			(at -1.97531 -1.604455 90)
			(unlocked yes)
			(layer "F.SilkS")
			(effects
				(font
					(size 0.762 0.762)
					(thickness 0.2286)
				)
				(justify left bottom)
			)
		)
		(property "Value" "CAP_0805_10UF_25V"
			(at 6.89119 10.8719 0)
			(unlocked yes)
			(layer "F.SilkS")
			(hide yes)
			(effects
				(font
					(size 1.524 1.524)
					(thickness 0.254)
				)
				(justify left bottom)
			)
		)
		(sheetname "POWER")
		(sheetfile "POWER.kicad_sch")
		(duplicate_pad_numbers_are_jumpers no)
		(fp_line
			(start 0.762 0.9652)
			(end -0.762 0.9652)
			(stroke
				(width 0.1524)
				(type solid)
			)
			(layer "F.SilkS")
		)
		(fp_line
			(start 0.762 -0.9652)
			(end -0.762 -0.9652)
			(stroke
				(width 0.1524)
				(type solid)
			)
			(layer "F.SilkS")
		)
		(pad "1" smd rect
			(at -0.9 0)
			(size 1.45 1.15)
			(layers "F.Cu" "F.Mask" "F.Paste")
			(net "+5.0V")
		)
		(pad "2" smd rect
			(at 0.9 0)
			(size 1.45 1.15)
			(layers "F.Cu" "F.Mask" "F.Paste")
			(net "GND")
		)
	)
	(footprint "Vault:CAPC1608X87X45ML20T05"
		(layer "F.Cu")
		(at 212.5637 90.4662 90)
		(property "Reference" "C11"
			(at 4.1 0.606655 270)
			(unlocked yes)
			(layer "F.SilkS")
			(effects
				(font
					(size 0.762 0.762)
					(thickness 0.2286)
				)
				(justify left bottom)
			)
		)
		(property "Value" "0.1uF"
			(at -10.31039 4.5043 0)
			(unlocked yes)
			(layer "F.SilkS")
			(hide yes)
			(effects
				(font
					(size 1.524 1.524)
					(thickness 0.254)
				)
				(justify left bottom)
			)
		)
		(sheetname "POWER")
		(sheetfile "POWER.kicad_sch")
		(duplicate_pad_numbers_are_jumpers no)
		(pad "1" smd rect
			(at -0.7 0 180)
			(size 1.1 1.05)
			(layers "F.Cu" "F.Mask" "F.Paste")
			(net "GND")
		)
		(pad "2" smd rect
			(at 0.7 0 180)
			(size 1.1 1.05)
			(layers "F.Cu" "F.Mask" "F.Paste")
			(net "+3.3V")
		)
	)
	(footprint "Vault:RESC1608X55X30NL15T15"
		(layer "F.Cu")
		(at 71.6261 55.6162 90)
		(property "Reference" "R36"
			(at -5.7714 -0.223079 90)
			(unlocked yes)
			(layer "F.SilkS")
			(effects
				(font
					(size 0.762 0.762)
					(thickness 0.2286)
				)
			)
		)
		(property "Value" "200 OHM"
			(at -2.962402 4.81166 0)
			(unlocked yes)
			(layer "F.SilkS")
			(hide yes)
			(effects
				(font
					(size 1.524 1.524)
					(thickness 0.254)
				)
			)
		)
		(sheetname "USER_IO_STATUS")
		(sheetfile "USER_IO_STATUS.kicad_sch")
		(duplicate_pad_numbers_are_jumpers no)
		(pad "1" smd rect
			(at -0.675 0 180)
			(size 0.95 0.8)
			(layers "F.Cu" "F.Mask" "F.Paste")
			(net "LED2")
		)
		(pad "2" smd rect
			(at 0.675 0 180)
			(size 0.95 0.8)
			(layers "F.Cu" "F.Mask" "F.Paste")
			(net "NetD9_1")
		)
	)
	(footprint "Vault:AMPH-901-143-6RFX_V"
		(layer "F.Cu")
		(at 60.9761 122.0782 180)
		(property "Reference" "AN3"
			(at -5.917345 2.516 90)
			(unlocked yes)
			(layer "F.SilkS")
			(effects
				(font
					(size 0.762 0.762)
					(thickness 0.2286)
				)
				(justify left bottom)
			)
		)
		(property "Value" "901-143-6RFX"
			(at 4.6101 -2.05359 0)
			(unlocked yes)
			(layer "F.SilkS")
			(hide yes)
			(effects
				(font
					(size 1.524 1.524)
					(thickness 0.254)
				)
				(justify left bottom)
			)
		)
		(sheetname "USER_IO")
		(sheetfile "USER_IO.kicad_sch")
		(duplicate_pad_numbers_are_jumpers no)
		(fp_line
			(start 3.5 -1.38)
			(end 3.5 1.38)
			(stroke
				(width 0.2)
				(type solid)
			)
			(layer "F.SilkS")
		)
		(fp_line
			(start 1.38 3.5)
			(end -1.38 3.5)
			(stroke
				(width 0.2)
				(type solid)
			)
			(layer "F.SilkS")
		)
		(fp_line
			(start 1.38 -3.5)
			(end -1.38 -3.5)
			(stroke
				(width 0.2)
				(type solid)
			)
			(layer "F.SilkS")
		)
		(fp_line
			(start -3.5 -1.38)
			(end -3.5 1.38)
			(stroke
				(width 0.2)
				(type solid)
			)
			(layer "F.SilkS")
		)
		(pad "1" thru_hole rect
			(at 0 0 180)
			(size 2 2)
			(drill 1.5)
			(layers "*.Cu" "*.Mask")
			(remove_unused_layers no)
			(net "NetAN3_1")
		)
		(pad "2" thru_hole circle
			(at -2.54 -2.54 180)
			(size 2.2 2.2)
			(drill 1.7)
			(layers "*.Cu" "*.Mask")
			(remove_unused_layers no)
			(net "GND")
			(thermal_bridge_angle 90)
		)
		(pad "3" thru_hole circle
			(at -2.54 2.54 180)
			(size 2.2 2.2)
			(drill 1.7)
			(layers "*.Cu" "*.Mask")
			(remove_unused_layers no)
			(net "GND")
			(thermal_bridge_angle 90)
		)
		(pad "4" thru_hole circle
			(at 2.54 2.54 180)
			(size 2.2 2.2)
			(drill 1.7)
			(layers "*.Cu" "*.Mask")
			(remove_unused_layers no)
			(net "GND")
			(thermal_bridge_angle 90)
		)
		(pad "5" thru_hole circle
			(at 2.54 -2.54 180)
			(size 2.2 2.2)
			(drill 1.7)
			(layers "*.Cu" "*.Mask")
			(remove_unused_layers no)
			(net "GND")
			(thermal_bridge_angle 90)
		)
	)
	(footprint "Vault:RESC1608X55X30NL15T15"
		(layer "F.Cu")
		(at 84.1261 112.1162 -90)
		(property "Reference" "R29"
			(at 4 -0.593345 90)
			(unlocked yes)
			(layer "F.SilkS")
			(effects
				(font
					(size 0.762 0.762)
					(thickness 0.2286)
				)
				(justify left bottom)
			)
		)
		(property "Value" "4.7K"
			(at 3.72999 0.4445 0)
			(unlocked yes)
			(layer "F.SilkS")
			(hide yes)
			(effects
				(font
					(size 1.524 1.524)
					(thickness 0.254)
				)
				(justify left bottom)
			)
		)
		(sheetname "USER_IO")
		(sheetfile "USER_IO.kicad_sch")
		(duplicate_pad_numbers_are_jumpers no)
		(pad "1" smd rect
			(at -0.75 0)
			(size 0.95 0.95)
			(layers "F.Cu" "F.Mask" "F.Paste")
			(net "ANT2_IO_OUT")
		)
		(pad "2" smd rect
			(at 0.75 0)
			(size 0.95 0.95)
			(layers "F.Cu" "F.Mask" "F.Paste")
			(net "+3.3V")
		)
	)
	(footprint "GNSS:GNSS"
		(locked yes)
		(layer "F.Cu")
		(at 225.8486 61.6786 180)
		(property "Reference" "U15"
			(at 62.698119 -18.19972 90)
			(unlocked yes)
			(layer "F.SilkS")
			(effects
				(font
					(size 0.762 0.762)
					(thickness 0.2286)
				)
			)
		)
		(property "Value" "RCB-F9T-1"
			(at -7.813802 -13.730755 90)
			(unlocked yes)
			(layer "F.SilkS")
			(hide yes)
			(effects
				(font
					(size 1.524 1.524)
					(thickness 0.254)
				)
			)
		)
		(sheetname "GPS_IMU_SENSORS")
		(sheetfile "GPS_IMU_SENSORS.kicad_sch")
		(duplicate_pad_numbers_are_jumpers no)
		(fp_line
			(start 61.07 11.28)
			(end -6.11 11.28)
			(stroke
				(width 0.254)
				(type solid)
			)
			(layer "F.SilkS")
		)
		(fp_line
			(start 61.07 -20.47)
			(end 61.07 11.28)
			(stroke
				(width 0.254)
				(type solid)
			)
			(layer "F.SilkS")
		)
		(fp_line
			(start 61.07 -20.47)
			(end -6.11 -20.47)
			(stroke
				(width 0.254)
				(type solid)
			)
			(layer "F.SilkS")
		)
		(fp_line
			(start -6.11 -20.47)
			(end -6.11 11.28)
			(stroke
				(width 0.254)
				(type solid)
			)
			(layer "F.SilkS")
		)
		(pad "0" thru_hole circle
			(at 0 -2 90)
			(size 0 0)
			(drill 0.76)
			(layers "*.Cu" "*.Mask")
			(remove_unused_layers no)
			(thermal_bridge_angle 90)
		)
		(pad "0" thru_hole circle
			(at 0 2 90)
			(size 0 0)
			(drill 0.76)
			(layers "*.Cu" "*.Mask")
			(remove_unused_layers no)
			(thermal_bridge_angle 90)
		)
		(pad "1" smd rect
			(at -2.2225 3 90)
			(size 1.12 2.105)
			(layers "F.Cu" "F.Mask" "F.Paste")
			(net "+5.0V")
		)
		(pad "2" smd rect
			(at 2.2225 3 90)
			(size 1.12 2.105)
			(layers "F.Cu" "F.Mask" "F.Paste")
			(net "+3.3V")
		)
		(pad "3" smd rect
			(at -2.2225 1 90)
			(size 1.12 2.105)
			(layers "F.Cu" "F.Mask" "F.Paste")
			(net "GPS2_TX")
		)
		(pad "4" smd rect
			(at 2.2225 1 90)
			(size 1.12 2.105)
			(layers "F.Cu" "F.Mask" "F.Paste")
			(net "GPS2_RST")
		)
		(pad "5" smd rect
			(at -2.2225 -1 90)
			(size 1.12 2.105)
			(layers "F.Cu" "F.Mask" "F.Paste")
			(net "GPS2_RX")
		)
		(pad "6" smd rect
			(at 2.2225 -1 90)
			(size 1.12 2.105)
			(layers "F.Cu" "F.Mask" "F.Paste")
			(net "GPS2_TP1")
		)
		(pad "7" smd rect
			(at -2.2225 -3 90)
			(size 1.12 2.105)
			(layers "F.Cu" "F.Mask" "F.Paste")
			(net "GPS2_TP2")
		)
		(pad "8" smd rect
			(at 2.2225 -3 90)
			(size 1.12 2.105)
			(layers "F.Cu" "F.Mask" "F.Paste")
			(net "GND")
		)
	)
	(footprint "Resistors:RESC1608X50N"
		(layer "F.Cu")
		(at 208.8747 84.8864)
		(property "Reference" "R5"
			(at 1.639 0.398145 0)
			(unlocked yes)
			(layer "F.SilkS")
			(effects
				(font
					(size 0.762 0.762)
					(thickness 0.2286)
				)
				(justify left bottom)
			)
		)
		(property "Value" "ERJ-3EKF2612V"
			(at -9.7817 21.05239 0)
			(unlocked yes)
			(layer "F.SilkS")
			(hide yes)
			(effects
				(font
					(size 1.524 1.524)
					(thickness 0.254)
				)
				(justify left bottom)
			)
		)
		(sheetname "POWER")
		(sheetfile "POWER.kicad_sch")
		(duplicate_pad_numbers_are_jumpers no)
		(fp_line
			(start 0 0.5)
			(end 0 -0.5)
			(stroke
				(width 0.1524)
				(type solid)
			)
			(layer "F.SilkS")
		)
		(pad "1" smd rect
			(at -0.69 0 90)
			(size 1 0.72)
			(layers "F.Cu" "F.Mask" "F.Paste")
			(net "NetR5_1")
		)
		(pad "2" smd rect
			(at 0.69 0 90)
			(size 1 0.72)
			(layers "F.Cu" "F.Mask" "F.Paste")
			(net "+3.3V")
		)
	)
	(footprint "Miscellaneous Connectors:HDR1X4"
		(layer "F.Cu")
		(at 106.9061 85.6162 180)
		(property "Reference" "P1"
			(at 10.448798 0.16477 90)
			(unlocked yes)
			(layer "F.SilkS")
			(effects
				(font
					(size 1.524 1.524)
					(thickness 0.254)
				)
			)
		)
		(property "Value" "AUX Sensor"
			(at -2.937002 6.38576 90)
			(unlocked yes)
			(layer "F.SilkS")
			(hide yes)
			(effects
				(font
					(size 1.524 1.524)
					(thickness 0.254)
				)
			)
		)
		(sheetname "GPS_IMU_SENSORS")
		(sheetfile "GPS_IMU_SENSORS.kicad_sch")
		(duplicate_pad_numbers_are_jumpers no)
		(fp_line
			(start 8.89 1.27)
			(end -1.27 1.27)
			(stroke
				(width 0.2)
				(type solid)
			)
			(layer "F.SilkS")
		)
		(fp_line
			(start 8.89 -1.27)
			(end 8.89 1.27)
			(stroke
				(width 0.2)
				(type solid)
			)
			(layer "F.SilkS")
		)
		(fp_line
			(start 8.89 -1.27)
			(end -1.27 -1.27)
			(stroke
				(width 0.2)
				(type solid)
			)
			(layer "F.SilkS")
		)
		(fp_line
			(start -1.27 -1.27)
			(end -1.27 1.27)
			(stroke
				(width 0.2)
				(type solid)
			)
			(layer "F.SilkS")
		)
		(pad "1" thru_hole rect
			(at 0 0 180)
			(size 1.5 1.5)
			(drill 0.9)
			(layers "*.Cu" "*.Mask")
			(remove_unused_layers no)
			(net "+3.3V")
		)
		(pad "2" thru_hole circle
			(at 2.54 0 180)
			(size 1.5 1.5)
			(drill 0.9)
			(layers "*.Cu" "*.Mask")
			(remove_unused_layers no)
			(net "GND")
			(thermal_bridge_angle 90)
		)
		(pad "3" thru_hole circle
			(at 5.08 0 180)
			(size 1.5 1.5)
			(drill 0.9)
			(layers "*.Cu" "*.Mask")
			(remove_unused_layers no)
			(net "SCL")
			(thermal_bridge_angle 90)
		)
		(pad "4" thru_hole circle
			(at 7.62 0 180)
			(size 1.5 1.5)
			(drill 0.9)
			(layers "*.Cu" "*.Mask")
			(remove_unused_layers no)
			(net "SDA")
			(thermal_bridge_angle 90)
		)
	)
	(footprint "SamacSys:155124M173200"
		(layer "F.Cu")
		(at 58.4511 101.4162 90)
		(property "Reference" "D15"
			(at -0.4714 1.701931 90)
			(unlocked yes)
			(layer "F.SilkS")
			(effects
				(font
					(size 0.762 0.762)
					(thickness 0.2286)
				)
			)
		)
		(property "Value" "155124M173200"
			(at 7.1725 2.632202 90)
			(unlocked yes)
			(layer "F.SilkS")
			(hide yes)
			(effects
				(font
					(size 1.524 1.524)
					(thickness 0.254)
				)
			)
		)
		(sheetname "USER_IO_STATUS")
		(sheetfile "USER_IO_STATUS.kicad_sch")
		(duplicate_pad_numbers_are_jumpers no)
		(fp_line
			(start -0.8 0.5)
			(end 0.8 0.5)
			(stroke
				(width 0.1)
				(type solid)
			)
			(layer "F.SilkS")
		)
		(fp_arc
			(start -2 -0.1)
			(mid -1.95 -0.05)
			(end -2 0)
			(stroke
				(width 0.1)
				(type solid)
			)
			(layer "F.SilkS")
		)
		(fp_arc
			(start -2 0)
			(mid -2.05 -0.05)
			(end -2 -0.1)
			(stroke
				(width 0.1)
				(type solid)
			)
			(layer "F.SilkS")
		)
		(pad "1" smd rect
			(at -1.4 0 180)
			(size 0.9 0.6)
			(layers "F.Cu" "F.Mask" "F.Paste")
			(net "+3.3V")
		)
		(pad "2" smd rect
			(at -0.45 -0.325 90)
			(size 0.6 0.55)
			(layers "F.Cu" "F.Mask" "F.Paste")
			(net "NetD15_2")
		)
		(pad "3" smd rect
			(at 0.45 -0.325 90)
			(size 0.6 0.55)
			(layers "F.Cu" "F.Mask" "F.Paste")
			(net "NetD15_3")
		)
		(pad "4" smd rect
			(at 1.4 0 180)
			(size 0.9 0.6)
			(layers "F.Cu" "F.Mask" "F.Paste")
			(net "NetD15_4")
		)
	)
	(footprint "Vault:RESC1608X55X25NL10T15"
		(layer "F.Cu")
		(at 77.6261 95.1162 180)
		(property "Reference" "R25"
			(at -0.2286 1.223079 0)
			(unlocked yes)
			(layer "F.SilkS")
			(effects
				(font
					(size 0.762 0.762)
					(thickness 0.2286)
				)
			)
		)
		(property "Value" "49.9R"
			(at -2.911602 3.21199 90)
			(unlocked yes)
			(layer "F.SilkS")
			(hide yes)
			(effects
				(font
					(size 1.524 1.524)
					(thickness 0.254)
				)
			)
		)
		(sheetname "USER_IO")
		(sheetfile "USER_IO.kicad_sch")
		(duplicate_pad_numbers_are_jumpers no)
		(pad "1" smd rect
			(at -0.7 0 270)
			(size 0.9 0.7)
			(layers "F.Cu" "F.Mask" "F.Paste")
			(net "NetR25_1")
		)
		(pad "2" smd rect
			(at 0.7 0 270)
			(size 0.9 0.7)
			(layers "F.Cu" "F.Mask" "F.Paste")
			(net "NetAN1_1")
		)
	)
	(footprint "Vault:RESC1608X55X25NL10T15"
		(layer "F.Cu")
		(at 129.17888 88.71463 180)
		(property "Reference" "R42"
			(at -2.87582 -0.328501 0)
			(unlocked yes)
			(layer "F.SilkS")
			(effects
				(font
					(size 0.762 0.762)
					(thickness 0.2286)
				)
			)
		)
		(property "Value" "DNI_49.9R"
			(at -2.911602 6.132045 90)
			(unlocked yes)
			(layer "F.SilkS")
			(hide yes)
			(effects
				(font
					(size 1.524 1.524)
					(thickness 0.254)
				)
			)
		)
		(sheetname "MAC")
		(sheetfile "MAC.kicad_sch")
		(duplicate_pad_numbers_are_jumpers no)
		(pad "1" smd rect
			(at -0.7 0 270)
			(size 0.9 0.7)
			(layers "F.Cu" "F.Mask" "F.Paste")
			(net "FPGA_MAC_PPS_IN0-")
		)
		(pad "2" smd rect
			(at 0.7 0 270)
			(size 0.9 0.7)
			(layers "F.Cu" "F.Mask" "F.Paste")
			(net "MAC_PPS_IN")
		)
	)
	(footprint "Resistors:RESC1608X50N"
		(layer "F.Cu")
		(at 201.1277 87.7312 180)
		(property "Reference" "R3"
			(at 2.864 -0.428345 0)
			(unlocked yes)
			(layer "F.SilkS")
			(effects
				(font
					(size 0.762 0.762)
					(thickness 0.2286)
				)
				(justify left bottom)
			)
		)
		(property "Value" "ERJ-3EKF4702V"
			(at -18.0821 -3.85659 0)
			(unlocked yes)
			(layer "F.SilkS")
			(hide yes)
			(effects
				(font
					(size 1.524 1.524)
					(thickness 0.254)
				)
				(justify left bottom)
			)
		)
		(sheetname "POWER")
		(sheetfile "POWER.kicad_sch")
		(duplicate_pad_numbers_are_jumpers no)
		(fp_line
			(start 0 -0.5)
			(end 0 0.5)
			(stroke
				(width 0.1524)
				(type solid)
			)
			(layer "F.SilkS")
		)
		(pad "1" smd rect
			(at -0.69 0 270)
			(size 1 0.72)
			(layers "F.Cu" "F.Mask" "F.Paste")
			(net "NetR3_1")
		)
		(pad "2" smd rect
			(at 0.69 0 270)
			(size 1 0.72)
			(layers "F.Cu" "F.Mask" "F.Paste")
			(net "+12V")
		)
	)
	(footprint "Vault:FP-BMX160-MFG"
		(layer "F.Cu")
		(at 186.6261 86.8286)
		(property "Reference" "U13"
			(at -0.7714 -2.723079 0)
			(unlocked yes)
			(layer "F.SilkS")
			(effects
				(font
					(size 0.762 0.762)
					(thickness 0.2286)
				)
			)
		)
		(property "Value" "BMX160"
			(at 1.967145 3.521202 0)
			(unlocked yes)
			(layer "F.SilkS")
			(hide yes)
			(effects
				(font
					(size 1.524 1.524)
					(thickness 0.254)
				)
			)
		)
		(sheetname "GPS_IMU_SENSORS")
		(sheetfile "GPS_IMU_SENSORS.kicad_sch")
		(duplicate_pad_numbers_are_jumpers no)
		(fp_line
			(start -2.1 -1.85)
			(end 2.1 -1.85)
			(stroke
				(width 0.2)
				(type solid)
			)
			(layer "F.SilkS")
		)
		(fp_line
			(start -2.1 1.85)
			(end -2.1 -1.85)
			(stroke
				(width 0.2)
				(type solid)
			)
			(layer "F.SilkS")
		)
		(fp_line
			(start -2.1 1.85)
			(end 2.1 1.85)
			(stroke
				(width 0.2)
				(type solid)
			)
			(layer "F.SilkS")
		)
		(fp_line
			(start 2.1 1.85)
			(end 2.1 -1.85)
			(stroke
				(width 0.2)
				(type solid)
			)
			(layer "F.SilkS")
		)
		(fp_circle
			(center -2.475 -0.75)
			(end -2.475 -0.875)
			(stroke
				(width 0.25)
				(type solid)
			)
			(fill no)
			(layer "F.SilkS")
		)
		(fp_line
			(start -2.1 -1.85)
			(end 2.1 -1.85)
			(stroke
				(width 0.2)
				(type solid)
			)
			(layer "F.CrtYd")
		)
		(fp_line
			(start -2.1 1.85)
			(end -2.1 -1.85)
			(stroke
				(width 0.2)
				(type solid)
			)
			(layer "F.CrtYd")
		)
		(fp_line
			(start -2.1 1.85)
			(end 2.1 1.85)
			(stroke
				(width 0.2)
				(type solid)
			)
			(layer "F.CrtYd")
		)
		(fp_line
			(start 2.1 1.85)
			(end 2.1 -1.85)
			(stroke
				(width 0.2)
				(type solid)
			)
			(layer "F.CrtYd")
		)
		(fp_line
			(start -2.1 -1.85)
			(end 2.1 -1.85)
			(stroke
				(width 0.2)
				(type solid)
			)
			(layer "F.Fab")
		)
		(fp_line
			(start -2.1 1.85)
			(end -2.1 -1.85)
			(stroke
				(width 0.2)
				(type solid)
			)
			(layer "F.Fab")
		)
		(fp_line
			(start -2.1 1.85)
			(end 2.1 1.85)
			(stroke
				(width 0.2)
				(type solid)
			)
			(layer "F.Fab")
		)
		(fp_line
			(start -0.5 0)
			(end 0.5 0)
			(stroke
				(width 0.1)
				(type solid)
			)
			(layer "F.Fab")
		)
		(fp_line
			(start 0 0.5)
			(end 0 -0.5)
			(stroke
				(width 0.1)
				(type solid)
			)
			(layer "F.Fab")
		)
		(fp_line
			(start 2.1 1.85)
			(end 2.1 -1.85)
			(stroke
				(width 0.2)
				(type solid)
			)
			(layer "F.Fab")
		)
		(fp_text user "${REFERENCE}"
			(at -0.00001 0.09602 0)
			(unlocked yes)
			(layer "F.Fab")
			(effects
				(font
					(face "Arial")
					(size 0.63 0.63)
					(thickness 0.1)
				)
				(justify left bottom)
			)
		)
		(pad "1" smd rect
			(at -1.2625 -0.75)
			(size 0.675 0.25)
			(layers "F.Cu" "F.Mask" "F.Paste")
			(net "GND")
			(solder_mask_margin 0)
			(solder_paste_margin 0)
		)
		(pad "2" smd rect
			(at -1.2625 -0.25)
			(size 0.675 0.25)
			(layers "F.Cu" "F.Mask" "F.Paste")
			(net "GND")
			(solder_mask_margin 0)
			(solder_paste_margin 0)
		)
		(pad "3" smd rect
			(at -1.2625 0.25)
			(size 0.675 0.25)
			(layers "F.Cu" "F.Mask" "F.Paste")
			(net "GND")
			(solder_mask_margin 0)
			(solder_paste_margin 0)
		)
		(pad "4" smd rect
			(at -1.2625 0.75)
			(size 0.675 0.25)
			(layers "F.Cu" "F.Mask" "F.Paste")
			(solder_mask_margin 0)
			(solder_paste_margin 0)
		)
		(pad "5" smd rect
			(at -0.5 1.0125)
			(size 0.25 0.675)
			(layers "F.Cu" "F.Mask" "F.Paste")
			(net "+3.3V")
			(solder_mask_margin 0)
			(solder_paste_margin 0)
		)
		(pad "6" smd rect
			(at 0 1.0125)
			(size 0.25 0.675)
			(layers "F.Cu" "F.Mask" "F.Paste")
			(net "GND")
			(solder_mask_margin 0)
			(solder_paste_margin 0)
		)
		(pad "7" smd rect
			(at 0.5 1.0125)
			(size 0.25 0.675)
			(layers "F.Cu" "F.Mask" "F.Paste")
			(net "GND")
			(solder_mask_margin 0)
			(solder_paste_margin 0)
		)
		(pad "8" smd rect
			(at 1.2625 0.75)
			(size 0.675 0.25)
			(layers "F.Cu" "F.Mask" "F.Paste")
			(net "+3.3V")
			(solder_mask_margin 0)
			(solder_paste_margin 0)
		)
		(pad "9" smd rect
			(at 1.2625 0.25)
			(size 0.675 0.25)
			(layers "F.Cu" "F.Mask" "F.Paste")
			(solder_mask_margin 0)
			(solder_paste_margin 0)
		)
		(pad "10" smd rect
			(at 1.2625 -0.25)
			(size 0.675 0.25)
			(layers "F.Cu" "F.Mask" "F.Paste")
			(solder_mask_margin 0)
			(solder_paste_margin 0)
		)
		(pad "11" smd rect
			(at 1.2625 -0.75)
			(size 0.675 0.25)
			(layers "F.Cu" "F.Mask" "F.Paste")
			(solder_mask_margin 0)
			(solder_paste_margin 0)
		)
		(pad "12" smd rect
			(at 0.5 -1.0125)
			(size 0.25 0.675)
			(layers "F.Cu" "F.Mask" "F.Paste")
			(net "+3.3V")
			(solder_mask_margin 0)
			(solder_paste_margin 0)
		)
		(pad "13" smd rect
			(at 0 -1.0125)
			(size 0.25 0.675)
			(layers "F.Cu" "F.Mask" "F.Paste")
			(net "SCL")
			(solder_mask_margin 0)
			(solder_paste_margin 0)
		)
		(pad "14" smd rect
			(at -0.5 -1.0125)
			(size 0.25 0.675)
			(layers "F.Cu" "F.Mask" "F.Paste")
			(net "SDA")
			(solder_mask_margin 0)
			(solder_paste_margin 0)
		)
	)
	(footprint "Vault:TECO-1909763-1_V"
		(layer "F.Cu")
		(at 74.3761 135.6162 -90)
		(property "Reference" "J4"
			(at -2.723079 1.021395 0)
			(unlocked yes)
			(layer "F.SilkS")
			(effects
				(font
					(size 0.762 0.762)
					(thickness 0.2286)
				)
			)
		)
		(property "Value" "1909763-1"
			(at 4.608085 3.749802 270)
			(unlocked yes)
			(layer "F.SilkS")
			(hide yes)
			(effects
				(font
					(size 1.524 1.524)
					(thickness 0.254)
				)
			)
		)
		(sheetname "USER_IO")
		(sheetfile "USER_IO.kicad_sch")
		(duplicate_pad_numbers_are_jumpers no)
		(fp_line
			(start 0.55 -1.3)
			(end -0.55 -1.3)
			(stroke
				(width 0.2)
				(type solid)
			)
			(layer "F.SilkS")
		)
		(fp_circle
			(center -1.778 1.65)
			(end -1.903 1.65)
			(stroke
				(width 0.25)
				(type solid)
			)
			(fill no)
			(layer "F.SilkS")
		)
		(pad "1" smd rect
			(at -1.475 0 270)
			(size 1.05 2.2)
			(layers "F.Cu" "F.Mask" "F.Paste")
			(net "GND")
		)
		(pad "2" smd rect
			(at 0 1.525 270)
			(size 1 1.05)
			(layers "F.Cu" "F.Mask" "F.Paste")
			(net "NetAN4_1")
		)
		(pad "3" smd rect
			(at 1.475 0 270)
			(size 1.05 2.2)
			(layers "F.Cu" "F.Mask" "F.Paste")
			(net "GND")
		)
	)
	(footprint "Vault:CAPC1608X87X45ML20T05"
		(layer "F.Cu")
		(at 186.1761 90.0786 180)
		(property "Reference" "C32"
			(at 3.0714 -0.026921 0)
			(unlocked yes)
			(layer "F.SilkS")
			(effects
				(font
					(size 0.762 0.762)
					(thickness 0.2286)
				)
			)
		)
		(property "Value" "0.1uF"
			(at 2.09443 2.657602 180)
			(unlocked yes)
			(layer "F.SilkS")
			(hide yes)
			(effects
				(font
					(size 1.524 1.524)
					(thickness 0.254)
				)
			)
		)
		(sheetname "GPS_IMU_SENSORS")
		(sheetfile "GPS_IMU_SENSORS.kicad_sch")
		(duplicate_pad_numbers_are_jumpers no)
		(pad "1" smd rect
			(at -0.7 0 270)
			(size 1.1 1.05)
			(layers "F.Cu" "F.Mask" "F.Paste")
			(net "GND")
		)
		(pad "2" smd rect
			(at 0.7 0 270)
			(size 1.1 1.05)
			(layers "F.Cu" "F.Mask" "F.Paste")
			(net "+3.3V")
		)
	)
	(footprint "Vault:CAPC1608X87X45ML20T05"
		(layer "F.Cu")
		(at 212.0765 116.3062 90)
		(property "Reference" "C18"
			(at 1.74 0.905345 90)
			(unlocked yes)
			(layer "F.SilkS")
			(effects
				(font
					(size 0.762 0.762)
					(thickness 0.2286)
				)
				(justify left bottom)
			)
		)
		(property "Value" "0.1uF"
			(at -6.58639 2.8695 0)
			(unlocked yes)
			(layer "F.SilkS")
			(hide yes)
			(effects
				(font
					(size 1.524 1.524)
					(thickness 0.254)
				)
				(justify left bottom)
			)
		)
		(sheetname "POWER")
		(sheetfile "POWER.kicad_sch")
		(duplicate_pad_numbers_are_jumpers no)
		(pad "1" smd rect
			(at -0.7 0 180)
			(size 1.1 1.05)
			(layers "F.Cu" "F.Mask" "F.Paste")
			(net "GND")
		)
		(pad "2" smd rect
			(at 0.7 0 180)
			(size 1.1 1.05)
			(layers "F.Cu" "F.Mask" "F.Paste")
			(net "+5.0V")
		)
	)
	(footprint "Vault:CAPC1608X87X45ML20T05"
		(layer "F.Cu")
		(at 82.39059 84.0062 -90)
		(property "Reference" "C39"
			(at -0.1186 2.987559 90)
			(unlocked yes)
			(layer "F.SilkS")
			(effects
				(font
					(size 0.762 0.762)
					(thickness 0.2286)
				)
			)
		)
		(property "Value" "0.1uF"
			(at 2.09443 2.657592 270)
			(unlocked yes)
			(layer "F.SilkS")
			(hide yes)
			(effects
				(font
					(size 1.524 1.524)
					(thickness 0.254)
				)
			)
		)
		(sheetname "USER_IO_STATUS")
		(sheetfile "USER_IO_STATUS.kicad_sch")
		(duplicate_pad_numbers_are_jumpers no)
		(pad "1" smd rect
			(at -0.7 0)
			(size 1.1 1.05)
			(layers "F.Cu" "F.Mask" "F.Paste")
			(net "GND")
		)
		(pad "2" smd rect
			(at 0.7 0)
			(size 1.1 1.05)
			(layers "F.Cu" "F.Mask" "F.Paste")
			(net "NetC39_2")
		)
	)
	(footprint "Resistors:RESC1608X50N"
		(layer "F.Cu")
		(at 208.8637 90.3662 90)
		(property "Reference" "R7"
			(at 3.982 -0.350345 270)
			(unlocked yes)
			(layer "F.SilkS")
			(effects
				(font
					(size 0.762 0.762)
					(thickness 0.2286)
				)
				(justify left bottom)
			)
		)
		(property "Value" "ERJ-3EKF1002V"
			(at -8.47159 7.6471 0)
			(unlocked yes)
			(layer "F.SilkS")
			(hide yes)
			(effects
				(font
					(size 1.524 1.524)
					(thickness 0.254)
				)
				(justify left bottom)
			)
		)
		(sheetname "POWER")
		(sheetfile "POWER.kicad_sch")
		(duplicate_pad_numbers_are_jumpers no)
		(fp_line
			(start 0 -0.5)
			(end 0 0.5)
			(stroke
				(width 0.1524)
				(type solid)
			)
			(layer "F.SilkS")
		)
		(pad "1" smd rect
			(at -0.69 0 180)
			(size 1 0.72)
			(layers "F.Cu" "F.Mask" "F.Paste")
			(net "GND")
		)
		(pad "2" smd rect
			(at 0.69 0 180)
			(size 1 0.72)
			(layers "F.Cu" "F.Mask" "F.Paste")
			(net "NetR5_1")
		)
	)
	(footprint "Vault:RESC3116X65X50ML20T20"
		(layer "F.Cu")
		(at 155.8261 86.8162)
		(property "Reference" "R45"
			(at 2.7286 -2.273079 0)
			(unlocked yes)
			(layer "F.SilkS")
			(effects
				(font
					(size 0.762 0.762)
					(thickness 0.2286)
				)
			)
		)
		(property "Value" "0_5%_1206"
			(at 4.379365 3.318002 0)
			(unlocked yes)
			(layer "F.SilkS")
			(hide yes)
			(effects
				(font
					(size 1.524 1.524)
					(thickness 0.254)
				)
			)
		)
		(sheetname "MAC")
		(sheetfile "MAC.kicad_sch")
		(duplicate_pad_numbers_are_jumpers no)
		(fp_line
			(start -0.35001 -0.85)
			(end 0.35 -0.85)
			(stroke
				(width 0.2)
				(type solid)
			)
			(layer "F.SilkS")
		)
		(fp_line
			(start -0.35001 0.85)
			(end 0.35 0.85)
			(stroke
				(width 0.2)
				(type solid)
			)
			(layer "F.SilkS")
		)
		(pad "1" smd rect
			(at -1.475 0 90)
			(size 1.9 1.45)
			(layers "F.Cu" "F.Mask" "F.Paste")
			(net "MAC_VCC")
		)
		(pad "2" smd rect
			(at 1.475 0 90)
			(size 1.9 1.45)
			(layers "F.Cu" "F.Mask" "F.Paste")
			(net "+5.0V")
		)
	)
	(footprint "Capacitors:CAPC1608X10N"
		(layer "F.Cu")
		(at 206.7425 119.8622)
		(property "Reference" "C4"
			(at 0.4836 1.360655 180)
			(unlocked yes)
			(layer "F.SilkS")
			(effects
				(font
					(size 0.762 0.762)
					(thickness 0.2286)
				)
				(justify left bottom)
			)
		)
		(property "Value" "CAP_0603_0.01UF_50V"
			(at -3.1503 -8.98381 0)
			(unlocked yes)
			(layer "F.SilkS")
			(hide yes)
			(effects
				(font
					(size 1.524 1.524)
					(thickness 0.254)
				)
				(justify left bottom)
			)
		)
		(sheetname "POWER")
		(sheetfile "POWER.kicad_sch")
		(duplicate_pad_numbers_are_jumpers no)
		(fp_line
			(start -0.635 -0.7112)
			(end 0.635 -0.7112)
			(stroke
				(width 0.1524)
				(type solid)
			)
			(layer "F.SilkS")
		)
		(fp_line
			(start -0.635 0.7112)
			(end 0.635 0.7112)
			(stroke
				(width 0.1524)
				(type solid)
			)
			(layer "F.SilkS")
		)
		(pad "1" smd rect
			(at -0.8 0 90)
			(size 0.95 1)
			(layers "F.Cu" "F.Mask" "F.Paste")
			(net "NetC4_1")
		)
		(pad "2" smd rect
			(at 0.8 0 90)
			(size 0.95 1)
			(layers "F.Cu" "F.Mask" "F.Paste")
			(net "NetC4_2")
		)
	)
	(footprint "SamacSys:SOP50P310X90-8N"
		(layer "F.Cu")
		(at 82.1261 95.6162 180)
		(property "Reference" "U8"
			(at 0.228605 2.026931 180)
			(unlocked yes)
			(layer "F.SilkS")
			(effects
				(font
					(size 0.762 0.762)
					(thickness 0.2286)
				)
			)
		)
		(property "Value" "NC7WV125K8X"
			(at 6.233115 2.911602 180)
			(unlocked yes)
			(layer "F.SilkS")
			(hide yes)
			(effects
				(font
					(size 1.524 1.524)
					(thickness 0.254)
				)
			)
		)
		(sheetname "USER_IO")
		(sheetfile "USER_IO.kicad_sch")
		(duplicate_pad_numbers_are_jumpers no)
		(fp_line
			(start 0.8 1)
			(end -0.8 1)
			(stroke
				(width 0.2)
				(type solid)
			)
			(layer "F.SilkS")
		)
		(fp_line
			(start 0.8 -1)
			(end 0.8 1)
			(stroke
				(width 0.2)
				(type solid)
			)
			(layer "F.SilkS")
		)
		(fp_line
			(start 0.8 -1)
			(end -0.8 -1)
			(stroke
				(width 0.2)
				(type solid)
			)
			(layer "F.SilkS")
		)
		(fp_line
			(start -0.8 -1)
			(end -0.8 1)
			(stroke
				(width 0.2)
				(type solid)
			)
			(layer "F.SilkS")
		)
		(fp_line
			(start -1.15 -1.25)
			(end -2 -1.25)
			(stroke
				(width 0.2)
				(type solid)
			)
			(layer "F.SilkS")
		)
		(pad "1" smd rect
			(at -1.575 -0.75 180)
			(size 0.85 0.3)
			(layers "F.Cu" "F.Mask" "F.Paste")
			(net "ANT1_IO_OUT")
		)
		(pad "2" smd rect
			(at -1.575 -0.25 180)
			(size 0.85 0.3)
			(layers "F.Cu" "F.Mask" "F.Paste")
			(net "ANT1_OUT")
		)
		(pad "3" smd rect
			(at -1.575 0.25 180)
			(size 0.85 0.3)
			(layers "F.Cu" "F.Mask" "F.Paste")
			(net "ANT1_IN")
		)
		(pad "4" smd rect
			(at -1.575 0.75 180)
			(size 0.85 0.3)
			(layers "F.Cu" "F.Mask" "F.Paste")
			(net "GND")
		)
		(pad "5" smd rect
			(at 1.575 0.75 180)
			(size 0.85 0.3)
			(layers "F.Cu" "F.Mask" "F.Paste")
			(net "NetR25_1")
		)
		(pad "6" smd rect
			(at 1.575 0.25 180)
			(size 0.85 0.3)
			(layers "F.Cu" "F.Mask" "F.Paste")
			(net "NetR25_1")
		)
		(pad "7" smd rect
			(at 1.575 -0.25 180)
			(size 0.85 0.3)
			(layers "F.Cu" "F.Mask" "F.Paste")
			(net "ANT1_IO_IN")
		)
		(pad "8" smd rect
			(at 1.575 -0.75 180)
			(size 0.85 0.3)
			(layers "F.Cu" "F.Mask" "F.Paste")
			(net "+3.3V")
		)
	)
	(footprint "Resistors:RESC1608X50N"
		(layer "F.Cu")
		(at 203.4405 114.0202 180)
		(property "Reference" "R2"
			(at 1.2144 0.710655 0)
			(unlocked yes)
			(layer "F.SilkS")
			(effects
				(font
					(size 0.762 0.762)
					(thickness 0.2286)
				)
				(justify left bottom)
			)
		)
		(property "Value" "ERJ-3EKF4702V"
			(at -6.3493 6.54541 0)
			(unlocked yes)
			(layer "F.SilkS")
			(hide yes)
			(effects
				(font
					(size 1.524 1.524)
					(thickness 0.254)
				)
				(justify left bottom)
			)
		)
		(sheetname "POWER")
		(sheetfile "POWER.kicad_sch")
		(duplicate_pad_numbers_are_jumpers no)
		(fp_line
			(start 0 -0.5)
			(end 0 0.5)
			(stroke
				(width 0.1524)
				(type solid)
			)
			(layer "F.SilkS")
		)
		(pad "1" smd rect
			(at -0.69 0 270)
			(size 1 0.72)
			(layers "F.Cu" "F.Mask" "F.Paste")
			(net "NetR2_1")
		)
		(pad "2" smd rect
			(at 0.69 0 270)
			(size 1 0.72)
			(layers "F.Cu" "F.Mask" "F.Paste")
			(net "+12V")
		)
	)
	(footprint "Vault:FP-MK212BG-MFG"
		(layer "F.Cu")
		(at 218.8761 60.5786 180)
		(property "Reference" "C34"
			(at 3.0214 -0.026921 0)
			(unlocked yes)
			(layer "F.SilkS")
			(effects
				(font
					(size 0.762 0.762)
					(thickness 0.2286)
				)
			)
		)
		(property "Value" "10uF"
			(at -3.267202 2.24704 90)
			(unlocked yes)
			(layer "F.SilkS")
			(hide yes)
			(effects
				(font
					(size 1.524 1.524)
					(thickness 0.254)
				)
			)
		)
		(sheetname "GPS_IMU_SENSORS")
		(sheetfile "GPS_IMU_SENSORS.kicad_sch")
		(duplicate_pad_numbers_are_jumpers no)
		(fp_line
			(start 0.125 0.725)
			(end -0.125 0.725)
			(stroke
				(width 0.2)
				(type solid)
			)
			(layer "F.SilkS")
		)
		(fp_line
			(start 0.125 -0.725)
			(end -0.125 -0.725)
			(stroke
				(width 0.2)
				(type solid)
			)
			(layer "F.SilkS")
		)
		(fp_line
			(start 1.6 0.825)
			(end -1.6 0.825)
			(stroke
				(width 0.2)
				(type solid)
			)
			(layer "F.CrtYd")
		)
		(fp_line
			(start 1.6 -0.825)
			(end 1.6 0.825)
			(stroke
				(width 0.2)
				(type solid)
			)
			(layer "F.CrtYd")
		)
		(fp_line
			(start 1.6 -0.825)
			(end -1.6 -0.825)
			(stroke
				(width 0.2)
				(type solid)
			)
			(layer "F.CrtYd")
		)
		(fp_line
			(start -1.6 -0.825)
			(end -1.6 0.825)
			(stroke
				(width 0.2)
				(type solid)
			)
			(layer "F.CrtYd")
		)
		(fp_line
			(start 1.6 0.825)
			(end -1.6 0.825)
			(stroke
				(width 0.2)
				(type solid)
			)
			(layer "F.Fab")
		)
		(fp_line
			(start 1.6 -0.825)
			(end 1.6 0.825)
			(stroke
				(width 0.2)
				(type solid)
			)
			(layer "F.Fab")
		)
		(fp_line
			(start 1.6 -0.825)
			(end -1.6 -0.825)
			(stroke
				(width 0.2)
				(type solid)
			)
			(layer "F.Fab")
		)
		(fp_line
			(start 0.5 0)
			(end -0.5 0)
			(stroke
				(width 0.1)
				(type solid)
			)
			(layer "F.Fab")
		)
		(fp_line
			(start 0 -0.5)
			(end 0 0.5)
			(stroke
				(width 0.1)
				(type solid)
			)
			(layer "F.Fab")
		)
		(fp_line
			(start -1.6 -0.825)
			(end -1.6 0.825)
			(stroke
				(width 0.2)
				(type solid)
			)
			(layer "F.Fab")
		)
		(fp_text user "${REFERENCE}"
			(at -0.00001 0.09602 180)
			(unlocked yes)
			(layer "F.Fab")
			(effects
				(font
					(face "Arial")
					(size 0.63 0.63)
					(thickness 0.1)
				)
				(justify left bottom)
			)
		)
		(pad "1" smd rect
			(at -1 0 180)
			(size 1 1.25)
			(layers "F.Cu" "F.Mask" "F.Paste")
			(net "+3.3V")
			(solder_mask_margin 0)
			(solder_paste_margin 0)
		)
		(pad "2" smd rect
			(at 1 0 180)
			(size 1 1.25)
			(layers "F.Cu" "F.Mask" "F.Paste")
			(net "GND")
			(solder_mask_margin 0)
			(solder_paste_margin 0)
		)
	)
	(footprint "IntegratedCircuits:SOIC127P600X175-8N"
		(layer "F.Cu")
		(at 207.5045 114.4012 90)
		(property "Reference" "U1"
			(at -4.215 -2.785055 90)
			(unlocked yes)
			(layer "F.SilkS")
			(effects
				(font
					(size 0.762 0.762)
					(thickness 0.2286)
				)
				(justify left bottom)
			)
		)
		(property "Value" "MP1482DS-LF"
			(at 0.75421 -0.6103 0)
			(unlocked yes)
			(layer "F.SilkS")
			(hide yes)
			(effects
				(font
					(size 1.524 1.524)
					(thickness 0.254)
				)
				(justify left bottom)
			)
		)
		(sheetname "POWER")
		(sheetfile "POWER.kicad_sch")
		(duplicate_pad_numbers_are_jumpers no)
		(fp_line
			(start -3.4 -2.5)
			(end 2 -2.5)
			(stroke
				(width 0.12)
				(type solid)
			)
			(layer "F.SilkS")
		)
		(fp_line
			(start -2 2.5)
			(end 2 2.5)
			(stroke
				(width 0.12)
				(type solid)
			)
			(layer "F.SilkS")
		)
		(pad "1" smd rect
			(at -2.475 -1.905 90)
			(size 1.97 0.57)
			(layers "F.Cu" "F.Mask" "F.Paste")
			(net "NetC4_1")
		)
		(pad "2" smd rect
			(at -2.475 -0.635 90)
			(size 1.97 0.57)
			(layers "F.Cu" "F.Mask" "F.Paste")
			(net "+12V")
		)
		(pad "3" smd rect
			(at -2.475 0.635 90)
			(size 1.97 0.57)
			(layers "F.Cu" "F.Mask" "F.Paste")
			(net "NetC4_2")
		)
		(pad "4" smd rect
			(at -2.475 1.905 90)
			(size 1.97 0.57)
			(layers "F.Cu" "F.Mask" "F.Paste")
			(net "GND")
		)
		(pad "5" smd rect
			(at 2.475 1.905 90)
			(size 1.97 0.57)
			(layers "F.Cu" "F.Mask" "F.Paste")
			(net "NetR4_2")
		)
		(pad "6" smd rect
			(at 2.475 0.635 90)
			(size 1.97 0.57)
			(layers "F.Cu" "F.Mask" "F.Paste")
			(net "NetC20_2")
		)
		(pad "7" smd rect
			(at 2.475 -0.635 90)
			(size 1.97 0.57)
			(layers "F.Cu" "F.Mask" "F.Paste")
			(net "NetR2_1")
		)
		(pad "8" smd rect
			(at 2.475 -1.905 90)
			(size 1.97 0.57)
			(layers "F.Cu" "F.Mask" "F.Paste")
			(net "NetC19_2")
		)
	)
	(footprint "Vault:CAPC1608X87X45ML20T05"
		(layer "F.Cu")
		(at 218.76876 58.67651)
		(property "Reference" "C36"
			(at -2.91406 -0.070979 0)
			(unlocked yes)
			(layer "F.SilkS")
			(effects
				(font
					(size 0.762 0.762)
					(thickness 0.2286)
				)
			)
		)
		(property "Value" "0.1uF"
			(at 2.09443 2.657602 0)
			(unlocked yes)
			(layer "F.SilkS")
			(hide yes)
			(effects
				(font
					(size 1.524 1.524)
					(thickness 0.254)
				)
			)
		)
		(sheetname "GPS_IMU_SENSORS")
		(sheetfile "GPS_IMU_SENSORS.kicad_sch")
		(duplicate_pad_numbers_are_jumpers no)
		(pad "1" smd rect
			(at -0.7 0 90)
			(size 1.1 1.05)
			(layers "F.Cu" "F.Mask" "F.Paste")
			(net "GND")
		)
		(pad "2" smd rect
			(at 0.7 0 90)
			(size 1.1 1.05)
			(layers "F.Cu" "F.Mask" "F.Paste")
			(net "+3.3V")
		)
	)
	(footprint "Vault:RESC3116X65X50ML20T20"
		(layer "F.Cu")
		(at 227.7261 121.2162 180)
		(property "Reference" "R44"
			(at 0.654005 -2.646148 180)
			(unlocked yes)
			(layer "F.SilkS")
			(effects
				(font
					(size 1.524 1.524)
					(thickness 0.254)
				)
			)
		)
		(property "Value" "DNI_0_5%_1206"
			(at 7.29942 3.318002 180)
			(unlocked yes)
			(layer "F.SilkS")
			(hide yes)
			(effects
				(font
					(size 1.524 1.524)
					(thickness 0.254)
				)
			)
		)
		(sheetname "POWER")
		(sheetfile "POWER.kicad_sch")
		(duplicate_pad_numbers_are_jumpers no)
		(fp_line
			(start 0.35 0.85)
			(end -0.35 0.85)
			(stroke
				(width 0.2)
				(type solid)
			)
			(layer "F.SilkS")
		)
		(fp_line
			(start 0.35 -0.85)
			(end -0.35 -0.85)
			(stroke
				(width 0.2)
				(type solid)
			)
			(layer "F.SilkS")
		)
		(pad "1" smd rect
			(at -1.475 0 270)
			(size 1.9 1.45)
			(layers "F.Cu" "F.Mask" "F.Paste")
			(net "NetD12_1")
		)
		(pad "2" smd rect
			(at 1.475 0 270)
			(size 1.9 1.45)
			(layers "F.Cu" "F.Mask" "F.Paste")
			(net "+12V")
		)
	)
	(footprint "Vault:FP-MK212BG-MFG"
		(layer "F.Cu")
		(at 227.6261 70.0786 180)
		(property "Reference" "C35"
			(at 3.0214 -0.026931 0)
			(unlocked yes)
			(layer "F.SilkS")
			(effects
				(font
					(size 0.762 0.762)
					(thickness 0.2286)
				)
			)
		)
		(property "Value" "10uF"
			(at -3.267202 2.24704 90)
			(unlocked yes)
			(layer "F.SilkS")
			(hide yes)
			(effects
				(font
					(size 1.524 1.524)
					(thickness 0.254)
				)
			)
		)
		(sheetname "GPS_IMU_SENSORS")
		(sheetfile "GPS_IMU_SENSORS.kicad_sch")
		(duplicate_pad_numbers_are_jumpers no)
		(fp_line
			(start 0.125 0.725)
			(end -0.125 0.725)
			(stroke
				(width 0.2)
				(type solid)
			)
			(layer "F.SilkS")
		)
		(fp_line
			(start 0.125 -0.725)
			(end -0.125 -0.725)
			(stroke
				(width 0.2)
				(type solid)
			)
			(layer "F.SilkS")
		)
		(fp_line
			(start 1.6 0.825)
			(end -1.6 0.825)
			(stroke
				(width 0.2)
				(type solid)
			)
			(layer "F.CrtYd")
		)
		(fp_line
			(start 1.6 -0.825)
			(end 1.6 0.825)
			(stroke
				(width 0.2)
				(type solid)
			)
			(layer "F.CrtYd")
		)
		(fp_line
			(start 1.6 -0.825)
			(end -1.6 -0.825)
			(stroke
				(width 0.2)
				(type solid)
			)
			(layer "F.CrtYd")
		)
		(fp_line
			(start -1.6 -0.825)
			(end -1.6 0.825)
			(stroke
				(width 0.2)
				(type solid)
			)
			(layer "F.CrtYd")
		)
		(fp_line
			(start 1.6 0.825)
			(end -1.6 0.825)
			(stroke
				(width 0.2)
				(type solid)
			)
			(layer "F.Fab")
		)
		(fp_line
			(start 1.6 -0.825)
			(end 1.6 0.825)
			(stroke
				(width 0.2)
				(type solid)
			)
			(layer "F.Fab")
		)
		(fp_line
			(start 1.6 -0.825)
			(end -1.6 -0.825)
			(stroke
				(width 0.2)
				(type solid)
			)
			(layer "F.Fab")
		)
		(fp_line
			(start 0.5 0)
			(end -0.5 0)
			(stroke
				(width 0.1)
				(type solid)
			)
			(layer "F.Fab")
		)
		(fp_line
			(start 0 -0.5)
			(end 0 0.5)
			(stroke
				(width 0.1)
				(type solid)
			)
			(layer "F.Fab")
		)
		(fp_line
			(start -1.6 -0.825)
			(end -1.6 0.825)
			(stroke
				(width 0.2)
				(type solid)
			)
			(layer "F.Fab")
		)
		(fp_text user "${REFERENCE}"
			(at -0.00001 0.09602 180)
			(unlocked yes)
			(layer "F.Fab")
			(effects
				(font
					(face "Arial")
					(size 0.63 0.63)
					(thickness 0.1)
				)
				(justify left bottom)
			)
		)
		(pad "1" smd rect
			(at -1 0 180)
			(size 1 1.25)
			(layers "F.Cu" "F.Mask" "F.Paste")
			(net "+5.0V")
			(solder_mask_margin 0)
			(solder_paste_margin 0)
		)
		(pad "2" smd rect
			(at 1 0 180)
			(size 1 1.25)
			(layers "F.Cu" "F.Mask" "F.Paste")
			(net "GND")
			(solder_mask_margin 0)
			(solder_paste_margin 0)
		)
	)
	(footprint "Connectors:PCIE_4LANE_EDGE"
		(layer "F.Cu")
		(at 118.02597 154.3547)
		(property "Reference" "P2"
			(at -12.64987 -0.282755 0)
			(unlocked yes)
			(layer "F.SilkS")
			(hide yes)
			(effects
				(font
					(size 0.762 0.762)
					(thickness 0.2286)
				)
				(justify left bottom)
			)
		)
		(property "Value" "PCIex4"
			(at -5.44907 18.65122 0)
			(unlocked yes)
			(layer "F.SilkS")
			(hide yes)
			(effects
				(font
					(size 1.524 1.524)
					(thickness 0.254)
				)
				(justify left bottom)
			)
		)
		(sheetname "PCIe_JTAG")
		(sheetfile "PCIe_JTAG.kicad_sch")
		(duplicate_pad_numbers_are_jumpers no)
		(pad "A1" smd rect
			(at -16.49984 2.2286)
			(size 0.7112 3.2004)
			(layers "B.Cu" "B.Mask" "B.Paste")
			(net "PRSNT")
		)
		(pad "A2" smd rect
			(at -15.49985 2.7239)
			(size 0.7112 4.191)
			(layers "B.Cu" "B.Mask" "B.Paste")
			(net "+12V_PCIE")
		)
		(pad "A3" smd rect
			(at -14.49985 2.7239)
			(size 0.7112 4.191)
			(layers "B.Cu" "B.Mask" "B.Paste")
			(net "+12V_PCIE")
		)
		(pad "A4" smd rect
			(at -13.49985 2.7239)
			(size 0.7112 4.191)
			(layers "B.Cu" "B.Mask" "B.Paste")
			(net "GND")
		)
		(pad "A5" smd rect
			(at -12.49985 2.7239)
			(size 0.7112 4.191)
			(layers "B.Cu" "B.Mask" "B.Paste")
		)
		(pad "A6" smd rect
			(at -11.49985 2.7239)
			(size 0.7112 4.191)
			(layers "B.Cu" "B.Mask" "B.Paste")
		)
		(pad "A7" smd rect
			(at -10.49986 2.7239)
			(size 0.7112 4.191)
			(layers "B.Cu" "B.Mask" "B.Paste")
		)
		(pad "A8" smd rect
			(at -9.49986 2.7239)
			(size 0.7112 4.191)
			(layers "B.Cu" "B.Mask" "B.Paste")
		)
		(pad "A9" smd rect
			(at -8.49986 2.7239)
			(size 0.7112 4.191)
			(layers "B.Cu" "B.Mask" "B.Paste")
			(net "+3.3V_PCIE")
		)
		(pad "A10" smd rect
			(at -7.49986 2.7239)
			(size 0.7112 4.191)
			(layers "B.Cu" "B.Mask" "B.Paste")
			(net "+3.3V_PCIE")
		)
		(pad "A11" smd rect
			(at -6.49986 2.7239)
			(size 0.7112 4.191)
			(layers "B.Cu" "B.Mask" "B.Paste")
			(net "PCIE_PERST")
		)
		(pad "A12" smd rect
			(at -3.49987 2.7239)
			(size 0.7112 4.191)
			(layers "B.Cu" "B.Mask" "B.Paste")
			(net "GND")
		)
		(pad "A13" smd rect
			(at -2.49987 2.7239)
			(size 0.7112 4.191)
			(layers "B.Cu" "B.Mask" "B.Paste")
			(net "NetC44_1")
		)
		(pad "A14" smd rect
			(at -1.49987 2.7239)
			(size 0.7112 4.191)
			(layers "B.Cu" "B.Mask" "B.Paste")
			(net "NetC45_1")
		)
		(pad "A15" smd rect
			(at -0.49988 2.7239)
			(size 0.7112 4.191)
			(layers "B.Cu" "B.Mask" "B.Paste")
			(net "GND")
		)
		(pad "A16" smd rect
			(at 0.50012 2.7239)
			(size 0.7112 4.191)
			(layers "B.Cu" "B.Mask" "B.Paste")
			(net "NetC46_1")
		)
		(pad "A17" smd rect
			(at 1.50012 2.7239)
			(size 0.7112 4.191)
			(layers "B.Cu" "B.Mask" "B.Paste")
			(net "NetC47_1")
		)
		(pad "A18" smd rect
			(at 2.50012 2.7239)
			(size 0.7112 4.191)
			(layers "B.Cu" "B.Mask" "B.Paste")
			(net "GND")
		)
		(pad "A19" smd rect
			(at 3.50012 2.7239)
			(size 0.7112 4.191)
			(layers "B.Cu" "B.Mask" "B.Paste")
		)
		(pad "A20" smd rect
			(at 4.50011 2.7239)
			(size 0.7112 4.191)
			(layers "B.Cu" "B.Mask" "B.Paste")
			(net "GND")
		)
		(pad "A21" smd rect
			(at 5.50011 2.7239)
			(size 0.7112 4.191)
			(layers "B.Cu" "B.Mask" "B.Paste")
			(net "NetC48_1")
		)
		(pad "A22" smd rect
			(at 6.50011 2.7239)
			(size 0.7112 4.191)
			(layers "B.Cu" "B.Mask" "B.Paste")
			(net "NetC49_1")
		)
		(pad "A23" smd rect
			(at 7.50011 2.7239)
			(size 0.7112 4.191)
			(layers "B.Cu" "B.Mask" "B.Paste")
			(net "GND")
		)
		(pad "A24" smd rect
			(at 8.50011 2.7239)
			(size 0.7112 4.191)
			(layers "B.Cu" "B.Mask" "B.Paste")
			(net "GND")
		)
		(pad "A25" smd rect
			(at 9.5001 2.7239)
			(size 0.7112 4.191)
			(layers "B.Cu" "B.Mask" "B.Paste")
			(net "NetC50_1")
		)
		(pad "A26" smd rect
			(at 10.5001 2.7239)
			(size 0.7112 4.191)
			(layers "B.Cu" "B.Mask" "B.Paste")
			(net "NetC51_1")
		)
		(pad "A27" smd rect
			(at 11.5001 2.7239)
			(size 0.7112 4.191)
			(layers "B.Cu" "B.Mask" "B.Paste")
			(net "GND")
		)
		(pad "A28" smd rect
			(at 12.5001 2.7239)
			(size 0.7112 4.191)
			(layers "B.Cu" "B.Mask" "B.Paste")
			(net "GND")
		)
		(pad "A29" smd rect
			(at 13.5001 2.7239)
			(size 0.7112 4.191)
			(layers "B.Cu" "B.Mask" "B.Paste")
			(net "NetC52_1")
		)
		(pad "A30" smd rect
			(at 14.50009 2.7239)
			(size 0.7112 4.191)
			(layers "B.Cu" "B.Mask" "B.Paste")
			(net "NetC53_1")
		)
		(pad "A31" smd rect
			(at 15.50009 2.7239)
			(size 0.7112 4.191)
			(layers "B.Cu" "B.Mask" "B.Paste")
			(net "GND")
		)
		(pad "A32" smd rect
			(at 16.50009 2.7239)
			(size 0.7112 4.191)
			(layers "B.Cu" "B.Mask" "B.Paste")
		)
		(pad "B1" smd rect
			(at -16.49984 2.7239)
			(size 0.7112 4.191)
			(layers "F.Cu" "F.Mask" "F.Paste")
			(net "+12V_PCIE")
		)
		(pad "B2" smd rect
			(at -15.49985 2.7239)
			(size 0.7112 4.191)
			(layers "F.Cu" "F.Mask" "F.Paste")
			(net "+12V_PCIE")
		)
		(pad "B3" smd rect
			(at -14.49985 2.7239)
			(size 0.7112 4.191)
			(layers "F.Cu" "F.Mask" "F.Paste")
			(net "+12V_PCIE")
		)
		(pad "B4" smd rect
			(at -13.49985 2.7239)
			(size 0.7112 4.191)
			(layers "F.Cu" "F.Mask" "F.Paste")
			(net "GND")
		)
		(pad "B5" smd rect
			(at -12.49985 2.7239)
			(size 0.7112 4.191)
			(layers "F.Cu" "F.Mask" "F.Paste")
		)
		(pad "B6" smd rect
			(at -11.49985 2.7239)
			(size 0.7112 4.191)
			(layers "F.Cu" "F.Mask" "F.Paste")
		)
		(pad "B7" smd rect
			(at -10.49986 2.7239)
			(size 0.7112 4.191)
			(layers "F.Cu" "F.Mask" "F.Paste")
			(net "GND")
		)
		(pad "B8" smd rect
			(at -9.49986 2.7239)
			(size 0.7112 4.191)
			(layers "F.Cu" "F.Mask" "F.Paste")
			(net "+3.3V_PCIE")
		)
		(pad "B9" smd rect
			(at -8.49986 2.7239)
			(size 0.7112 4.191)
			(layers "F.Cu" "F.Mask" "F.Paste")
		)
		(pad "B10" smd rect
			(at -7.49986 2.7239)
			(size 0.7112 4.191)
			(layers "F.Cu" "F.Mask" "F.Paste")
		)
		(pad "B11" smd rect
			(at -6.49986 2.7239)
			(size 0.7112 4.191)
			(layers "F.Cu" "F.Mask" "F.Paste")
		)
		(pad "B12" smd rect
			(at -3.49987 2.7239)
			(size 0.7112 4.191)
			(layers "F.Cu" "F.Mask" "F.Paste")
		)
		(pad "B13" smd rect
			(at -2.49987 2.7239)
			(size 0.7112 4.191)
			(layers "F.Cu" "F.Mask" "F.Paste")
			(net "GND")
		)
		(pad "B14" smd rect
			(at -1.49987 2.7239)
			(size 0.7112 4.191)
			(layers "F.Cu" "F.Mask" "F.Paste")
			(net "PCIE_RX0_P")
		)
		(pad "B15" smd rect
			(at -0.49988 2.7239)
			(size 0.7112 4.191)
			(layers "F.Cu" "F.Mask" "F.Paste")
			(net "PCIE_RX0_N")
		)
		(pad "B16" smd rect
			(at 0.50012 2.7239)
			(size 0.7112 4.191)
			(layers "F.Cu" "F.Mask" "F.Paste")
			(net "GND")
		)
		(pad "B17" smd rect
			(at 1.50012 2.7239)
			(size 0.7112 4.191)
			(layers "F.Cu" "F.Mask" "F.Paste")
			(net "NetP2_B17")
		)
		(pad "B18" smd rect
			(at 2.50012 2.7239)
			(size 0.7112 4.191)
			(layers "F.Cu" "F.Mask" "F.Paste")
			(net "GND")
		)
		(pad "B19" smd rect
			(at 3.50012 2.7239)
			(size 0.7112 4.191)
			(layers "F.Cu" "F.Mask" "F.Paste")
			(net "PCIE_RX1_P")
		)
		(pad "B20" smd rect
			(at 4.50011 2.7239)
			(size 0.7112 4.191)
			(layers "F.Cu" "F.Mask" "F.Paste")
			(net "PCIE_RX1_N")
		)
		(pad "B21" smd rect
			(at 5.50011 2.7239)
			(size 0.7112 4.191)
			(layers "F.Cu" "F.Mask" "F.Paste")
			(net "GND")
		)
		(pad "B22" smd rect
			(at 6.50011 2.7239)
			(size 0.7112 4.191)
			(layers "F.Cu" "F.Mask" "F.Paste")
			(net "GND")
		)
		(pad "B23" smd rect
			(at 7.50011 2.7239)
			(size 0.7112 4.191)
			(layers "F.Cu" "F.Mask" "F.Paste")
			(net "PCIE_RX2_P")
		)
		(pad "B24" smd rect
			(at 8.50011 2.7239)
			(size 0.7112 4.191)
			(layers "F.Cu" "F.Mask" "F.Paste")
			(net "PCIE_RX2_N")
		)
		(pad "B25" smd rect
			(at 9.5001 2.7239)
			(size 0.7112 4.191)
			(layers "F.Cu" "F.Mask" "F.Paste")
			(net "GND")
		)
		(pad "B26" smd rect
			(at 10.5001 2.7239)
			(size 0.7112 4.191)
			(layers "F.Cu" "F.Mask" "F.Paste")
			(net "GND")
		)
		(pad "B27" smd rect
			(at 11.5001 2.7239)
			(size 0.7112 4.191)
			(layers "F.Cu" "F.Mask" "F.Paste")
			(net "PCIE_RX3_P")
		)
		(pad "B28" smd rect
			(at 12.5001 2.7239)
			(size 0.7112 4.191)
			(layers "F.Cu" "F.Mask" "F.Paste")
			(net "PCIE_RX3_N")
		)
		(pad "B29" smd rect
			(at 13.5001 2.7239)
			(size 0.7112 4.191)
			(layers "F.Cu" "F.Mask" "F.Paste")
			(net "GND")
		)
		(pad "B30" smd rect
			(at 14.50009 2.7239)
			(size 0.7112 4.191)
			(layers "F.Cu" "F.Mask" "F.Paste")
		)
		(pad "B31" smd rect
			(at 15.50009 2.2286)
			(size 0.7112 3.2004)
			(layers "F.Cu" "F.Mask" "F.Paste")
			(net "NetP2_B31")
		)
		(pad "B32" smd rect
			(at 16.50009 2.7239)
			(size 0.7112 4.191)
			(layers "F.Cu" "F.Mask" "F.Paste")
			(net "GND")
		)
	)
	(footprint "Vault:RESC3116X65X50ML20T20"
		(layer "F.Cu")
		(at 156.0261 89.7162)
		(property "Reference" "R47"
			(at 4.6286 -0.373069 0)
			(unlocked yes)
			(layer "F.SilkS")
			(effects
				(font
					(size 0.762 0.762)
					(thickness 0.2286)
				)
			)
		)
		(property "Value" "DNI_0_5%_1206"
			(at 7.29942 3.318002 0)
			(unlocked yes)
			(layer "F.SilkS")
			(hide yes)
			(effects
				(font
					(size 1.524 1.524)
					(thickness 0.254)
				)
			)
		)
		(sheetname "MAC")
		(sheetfile "MAC.kicad_sch")
		(duplicate_pad_numbers_are_jumpers no)
		(fp_line
			(start -0.35 -0.85)
			(end 0.35 -0.85)
			(stroke
				(width 0.2)
				(type solid)
			)
			(layer "F.SilkS")
		)
		(fp_line
			(start -0.35 0.85)
			(end 0.35 0.85)
			(stroke
				(width 0.2)
				(type solid)
			)
			(layer "F.SilkS")
		)
		(pad "1" smd rect
			(at -1.475 0 90)
			(size 1.9 1.45)
			(layers "F.Cu" "F.Mask" "F.Paste")
			(net "MAC_VCC")
		)
		(pad "2" smd rect
			(at 1.475 0 90)
			(size 1.9 1.45)
			(layers "F.Cu" "F.Mask" "F.Paste")
			(net "+3.3V")
		)
	)
	(footprint "Capacitors:CAPC2012X14N"
		(layer "F.Cu")
		(at 227.8261 115.5162 90)
		(property "Reference" "C1"
			(at 2.25 0.343345 90)
			(unlocked yes)
			(layer "F.SilkS")
			(effects
				(font
					(size 0.762 0.762)
					(thickness 0.2286)
				)
				(justify left bottom)
			)
		)
		(property "Value" "CAP_0805_10UF_25V"
			(at -3.52679 -1.5875 0)
			(unlocked yes)
			(layer "F.SilkS")
			(hide yes)
			(effects
				(font
					(size 1.524 1.524)
					(thickness 0.254)
				)
				(justify left bottom)
			)
		)
		(sheetname "POWER")
		(sheetfile "POWER.kicad_sch")
		(duplicate_pad_numbers_are_jumpers no)
		(fp_line
			(start -0.762 -0.9652)
			(end 0.762 -0.9652)
			(stroke
				(width 0.1524)
				(type solid)
			)
			(layer "F.SilkS")
		)
		(fp_line
			(start -0.762 0.9652)
			(end 0.762 0.9652)
			(stroke
				(width 0.1524)
				(type solid)
			)
			(layer "F.SilkS")
		)
		(pad "1" smd rect
			(at -0.9 0 180)
			(size 1.45 1.15)
			(layers "F.Cu" "F.Mask" "F.Paste")
			(net "+12V")
		)
		(pad "2" smd rect
			(at 0.9 0 180)
			(size 1.45 1.15)
			(layers "F.Cu" "F.Mask" "F.Paste")
			(net "GND")
		)
	)
	(footprint "Vault:CAPC1608X87X45ML20T05"
		(layer "F.Cu")
		(at 125.1261 85.0786 -90)
		(property "Reference" "C24"
			(at -0.3338 -1.273069 270)
			(unlocked yes)
			(layer "F.SilkS")
			(effects
				(font
					(size 0.762 0.762)
					(thickness 0.2286)
				)
			)
		)
		(property "Value" "0.1uF"
			(at 2.09443 2.657602 270)
			(unlocked yes)
			(layer "F.SilkS")
			(hide yes)
			(effects
				(font
					(size 1.524 1.524)
					(thickness 0.254)
				)
			)
		)
		(sheetname "MAC")
		(sheetfile "MAC.kicad_sch")
		(duplicate_pad_numbers_are_jumpers no)
		(pad "1" smd rect
			(at -0.7 0)
			(size 1.1 1.05)
			(layers "F.Cu" "F.Mask" "F.Paste")
			(net "+3.3V")
		)
		(pad "2" smd rect
			(at 0.7 0)
			(size 1.1 1.05)
			(layers "F.Cu" "F.Mask" "F.Paste")
			(net "GND")
		)
	)
	(footprint "Vault:FP-STPS5L60S-MFG"
		(layer "F.Cu")
		(at 234.0261 125.4162 -90)
		(property "Reference" "D19"
			(at 0.454005 -4.446148 270)
			(unlocked yes)
			(layer "F.SilkS")
			(effects
				(font
					(size 1.524 1.524)
					(thickness 0.254)
				)
			)
		)
		(property "Value" "STPS5L60S"
			(at -6.518402 3.795165 180)
			(unlocked yes)
			(layer "F.SilkS")
			(hide yes)
			(effects
				(font
					(size 1.524 1.524)
					(thickness 0.254)
				)
			)
		)
		(sheetname "POWER")
		(sheetfile "POWER.kicad_sch")
		(duplicate_pad_numbers_are_jumpers no)
		(fp_line
			(start -3.575 3.125)
			(end -3.575 2.025)
			(stroke
				(width 0.2)
				(type solid)
			)
			(layer "F.SilkS")
		)
		(fp_line
			(start 3.575 3.125)
			(end -3.575 3.125)
			(stroke
				(width 0.2)
				(type solid)
			)
			(layer "F.SilkS")
		)
		(fp_line
			(start 3.575 3.125)
			(end 3.575 2.025)
			(stroke
				(width 0.2)
				(type solid)
			)
			(layer "F.SilkS")
		)
		(fp_line
			(start -3.575 -2.025)
			(end -3.575 -3.125)
			(stroke
				(width 0.2)
				(type solid)
			)
			(layer "F.SilkS")
		)
		(fp_line
			(start 3.575 -2.025)
			(end 3.575 -3.125)
			(stroke
				(width 0.2)
				(type solid)
			)
			(layer "F.SilkS")
		)
		(fp_line
			(start 3.575 -3.125)
			(end -3.575 -3.125)
			(stroke
				(width 0.2)
				(type solid)
			)
			(layer "F.SilkS")
		)
		(fp_circle
			(center -4.7 -0.025)
			(end -4.825 -0.025)
			(stroke
				(width 0.25)
				(type solid)
			)
			(fill no)
			(layer "F.SilkS")
		)
		(fp_line
			(start -4.195 3.225)
			(end -4.195 -3.225)
			(stroke
				(width 0.2)
				(type solid)
			)
			(layer "F.CrtYd")
		)
		(fp_line
			(start 4.195 3.225)
			(end -4.195 3.225)
			(stroke
				(width 0.2)
				(type solid)
			)
			(layer "F.CrtYd")
		)
		(fp_line
			(start 4.195 3.225)
			(end 4.195 -3.225)
			(stroke
				(width 0.2)
				(type solid)
			)
			(layer "F.CrtYd")
		)
		(fp_line
			(start 4.195 -3.225)
			(end -4.195 -3.225)
			(stroke
				(width 0.2)
				(type solid)
			)
			(layer "F.CrtYd")
		)
		(fp_line
			(start -4.195 3.225)
			(end -4.195 -3.225)
			(stroke
				(width 0.2)
				(type solid)
			)
			(layer "F.Fab")
		)
		(fp_line
			(start 4.195 3.225)
			(end -4.195 3.225)
			(stroke
				(width 0.2)
				(type solid)
			)
			(layer "F.Fab")
		)
		(fp_line
			(start 4.195 3.225)
			(end 4.195 -3.225)
			(stroke
				(width 0.2)
				(type solid)
			)
			(layer "F.Fab")
		)
		(fp_line
			(start 0 0.5)
			(end 0 -0.5)
			(stroke
				(width 0.1)
				(type solid)
			)
			(layer "F.Fab")
		)
		(fp_line
			(start 0.5 0)
			(end -0.5 0)
			(stroke
				(width 0.1)
				(type solid)
			)
			(layer "F.Fab")
		)
		(fp_line
			(start 4.195 -3.225)
			(end -4.195 -3.225)
			(stroke
				(width 0.2)
				(type solid)
			)
			(layer "F.Fab")
		)
		(fp_text user "${REFERENCE}"
			(at -0.00001 0.09602 270)
			(unlocked yes)
			(layer "F.Fab")
			(effects
				(font
					(face "Arial")
					(size 0.63 0.63)
					(thickness 0.1)
				)
				(justify left bottom)
			)
		)
		(pad "1" smd rect
			(at -3.325 0 270)
			(size 1.54 3.14)
			(layers "F.Cu" "F.Mask" "F.Paste")
			(net "NetD12_1")
			(solder_mask_margin 0)
			(solder_paste_margin 0)
		)
		(pad "2" smd rect
			(at 3.325 0 270)
			(size 1.54 3.14)
			(layers "F.Cu" "F.Mask" "F.Paste")
			(net "+12V_PCIE")
			(solder_mask_margin 0)
			(solder_paste_margin 0)
		)
	)
	(footprint "SamacSys:SOP50P310X90-8N"
		(layer "F.Cu")
		(at 82.1261 136.1162 180)
		(property "Reference" "U16"
			(at 0.2286 2.026931 180)
			(unlocked yes)
			(layer "F.SilkS")
			(effects
				(font
					(size 0.762 0.762)
					(thickness 0.2286)
				)
			)
		)
		(property "Value" "NC7WV125K8X"
			(at 6.233115 2.911602 180)
			(unlocked yes)
			(layer "F.SilkS")
			(hide yes)
			(effects
				(font
					(size 1.524 1.524)
					(thickness 0.254)
				)
			)
		)
		(sheetname "USER_IO")
		(sheetfile "USER_IO.kicad_sch")
		(duplicate_pad_numbers_are_jumpers no)
		(fp_line
			(start 0.8 1)
			(end -0.8 1)
			(stroke
				(width 0.2)
				(type solid)
			)
			(layer "F.SilkS")
		)
		(fp_line
			(start 0.8 -1)
			(end 0.8 1)
			(stroke
				(width 0.2)
				(type solid)
			)
			(layer "F.SilkS")
		)
		(fp_line
			(start 0.8 -1)
			(end -0.8 -1)
			(stroke
				(width 0.2)
				(type solid)
			)
			(layer "F.SilkS")
		)
		(fp_line
			(start -0.8 -1)
			(end -0.8 1)
			(stroke
				(width 0.2)
				(type solid)
			)
			(layer "F.SilkS")
		)
		(fp_line
			(start -1.15 -1.25)
			(end -2 -1.25)
			(stroke
				(width 0.2)
				(type solid)
			)
			(layer "F.SilkS")
		)
		(pad "1" smd rect
			(at -1.575 -0.75 180)
			(size 0.85 0.3)
			(layers "F.Cu" "F.Mask" "F.Paste")
			(net "ANT4_IO_OUT")
		)
		(pad "2" smd rect
			(at -1.575 -0.25 180)
			(size 0.85 0.3)
			(layers "F.Cu" "F.Mask" "F.Paste")
			(net "ANT4_OUT")
		)
		(pad "3" smd rect
			(at -1.575 0.25 180)
			(size 0.85 0.3)
			(layers "F.Cu" "F.Mask" "F.Paste")
			(net "ANT4_IN")
		)
		(pad "4" smd rect
			(at -1.575 0.75 180)
			(size 0.85 0.3)
			(layers "F.Cu" "F.Mask" "F.Paste")
			(net "GND")
		)
		(pad "5" smd rect
			(at 1.575 0.75 180)
			(size 0.85 0.3)
			(layers "F.Cu" "F.Mask" "F.Paste")
			(net "NetR34_1")
		)
		(pad "6" smd rect
			(at 1.575 0.25 180)
			(size 0.85 0.3)
			(layers "F.Cu" "F.Mask" "F.Paste")
			(net "NetR34_1")
		)
		(pad "7" smd rect
			(at 1.575 -0.25 180)
			(size 0.85 0.3)
			(layers "F.Cu" "F.Mask" "F.Paste")
			(net "ANT4_IO_IN")
		)
		(pad "8" smd rect
			(at 1.575 -0.75 180)
			(size 0.85 0.3)
			(layers "F.Cu" "F.Mask" "F.Paste")
			(net "+3.3V")
		)
	)
	(footprint "Resistors:RESC2012X50N"
		(layer "F.Cu")
		(at 229.5261 142.1162 -90)
		(property "Reference" "R20"
			(at -1.2 -1.506655 270)
			(unlocked yes)
			(layer "F.SilkS")
			(effects
				(font
					(size 0.762 0.762)
					(thickness 0.2286)
				)
				(justify left bottom)
			)
		)
		(property "Value" "CRCW080533R0FKEA"
			(at -7.93582 -4.5751 0)
			(unlocked yes)
			(layer "F.SilkS")
			(hide yes)
			(effects
				(font
					(size 1.524 1.524)
					(thickness 0.254)
				)
				(justify left bottom)
			)
		)
		(sheetname "PCIe_JTAG")
		(sheetfile "PCIe_JTAG.kicad_sch")
		(duplicate_pad_numbers_are_jumpers no)
		(fp_line
			(start 0 0.762)
			(end 0 -0.762)
			(stroke
				(width 0.1524)
				(type solid)
			)
			(layer "F.SilkS")
		)
		(pad "1" smd rect
			(at -1 0)
			(size 1.45 0.95)
			(layers "F.Cu" "F.Mask" "F.Paste")
			(net "FPGA_TMS")
		)
		(pad "2" smd rect
			(at 1 0)
			(size 1.45 0.95)
			(layers "F.Cu" "F.Mask" "F.Paste")
			(net "NetR20_2")
		)
	)
	(footprint "Vault:RESC1608X55X25NL10T15"
		(layer "F.Cu")
		(at 77.8761 121.8662 180)
		(property "Reference" "R28"
			(at 0.81672 1.068825 0)
			(unlocked yes)
			(layer "F.SilkS")
			(effects
				(font
					(size 0.762 0.762)
					(thickness 0.2286)
				)
				(justify left bottom)
			)
		)
		(property "Value" "49.9R"
			(at 1.1445 -4.42999 0)
			(unlocked yes)
			(layer "F.SilkS")
			(hide yes)
			(effects
				(font
					(size 1.524 1.524)
					(thickness 0.254)
				)
				(justify left bottom)
			)
		)
		(sheetname "USER_IO")
		(sheetfile "USER_IO.kicad_sch")
		(duplicate_pad_numbers_are_jumpers no)
		(pad "1" smd rect
			(at -0.7 0 270)
			(size 0.9 0.7)
			(layers "F.Cu" "F.Mask" "F.Paste")
			(net "NetR28_1")
		)
		(pad "2" smd rect
			(at 0.7 0 270)
			(size 0.9 0.7)
			(layers "F.Cu" "F.Mask" "F.Paste")
			(net "NetAN3_1")
		)
	)
	(footprint "Vault:TECO-1909763-1_V"
		(layer "F.Cu")
		(at 74.3761 121.8662 -90)
		(property "Reference" "J3"
			(at -2.973069 1.271395 0)
			(unlocked yes)
			(layer "F.SilkS")
			(effects
				(font
					(size 0.762 0.762)
					(thickness 0.2286)
				)
			)
		)
		(property "Value" "1909763-1"
			(at 4.608085 3.749802 270)
			(unlocked yes)
			(layer "F.SilkS")
			(hide yes)
			(effects
				(font
					(size 1.524 1.524)
					(thickness 0.254)
				)
			)
		)
		(sheetname "USER_IO")
		(sheetfile "USER_IO.kicad_sch")
		(duplicate_pad_numbers_are_jumpers no)
		(fp_line
			(start 0.55 -1.3)
			(end -0.55 -1.3)
			(stroke
				(width 0.2)
				(type solid)
			)
			(layer "F.SilkS")
		)
		(fp_circle
			(center -1.778 1.65)
			(end -1.903 1.65)
			(stroke
				(width 0.25)
				(type solid)
			)
			(fill no)
			(layer "F.SilkS")
		)
		(pad "1" smd rect
			(at -1.475 0 270)
			(size 1.05 2.2)
			(layers "F.Cu" "F.Mask" "F.Paste")
			(net "GND")
		)
		(pad "2" smd rect
			(at 0 1.525 270)
			(size 1 1.05)
			(layers "F.Cu" "F.Mask" "F.Paste")
			(net "NetAN3_1")
		)
		(pad "3" smd rect
			(at 1.475 0 270)
			(size 1.05 2.2)
			(layers "F.Cu" "F.Mask" "F.Paste")
			(net "GND")
		)
	)
	(footprint "Vault:CAPC1608X87X45ML20T05"
		(layer "F.Cu")
		(at 92.1261 74.5786 90)
		(property "Reference" "C59"
			(at -4.25 1.343345 90)
			(unlocked yes)
			(layer "F.SilkS")
			(effects
				(font
					(size 0.762 0.762)
					(thickness 0.2286)
				)
				(justify left bottom)
			)
		)
		(property "Value" "0.1uF"
			(at -3.47599 -0.2921 0)
			(unlocked yes)
			(layer "F.SilkS")
			(hide yes)
			(effects
				(font
					(size 1.524 1.524)
					(thickness 0.254)
				)
				(justify left bottom)
			)
		)
		(sheetname "GPS_IMU_SENSORS")
		(sheetfile "GPS_IMU_SENSORS.kicad_sch")
		(duplicate_pad_numbers_are_jumpers no)
		(pad "1" smd rect
			(at -0.7 0 180)
			(size 1.1 1.05)
			(layers "F.Cu" "F.Mask" "F.Paste")
			(net "GND")
		)
		(pad "2" smd rect
			(at 0.7 0 180)
			(size 1.1 1.05)
			(layers "F.Cu" "F.Mask" "F.Paste")
			(net "+3.3V")
		)
	)
	(footprint "Vault:CAPC1608X87X45ML20T05"
		(layer "F.Cu")
		(at 80.6261 112.1162 -90)
		(property "Reference" "C28"
			(at 2.7714 -0.026931 90)
			(unlocked yes)
			(layer "F.SilkS")
			(effects
				(font
					(size 0.762 0.762)
					(thickness 0.2286)
				)
			)
		)
		(property "Value" "0.1uF"
			(at 2.09443 2.657602 270)
			(unlocked yes)
			(layer "F.SilkS")
			(hide yes)
			(effects
				(font
					(size 1.524 1.524)
					(thickness 0.254)
				)
			)
		)
		(sheetname "USER_IO")
		(sheetfile "USER_IO.kicad_sch")
		(duplicate_pad_numbers_are_jumpers no)
		(pad "1" smd rect
			(at -0.7 0)
			(size 1.1 1.05)
			(layers "F.Cu" "F.Mask" "F.Paste")
			(net "+3.3V")
		)
		(pad "2" smd rect
			(at 0.7 0)
			(size 1.1 1.05)
			(layers "F.Cu" "F.Mask" "F.Paste")
			(net "GND")
		)
	)
	(footprint "Vault:CAPC1608X87X45ML20T05"
		(layer "F.Cu")
		(at 197.3761 84.2786 -90)
		(property "Reference" "C31"
			(at 2.721395 -0.026921 90)
			(unlocked yes)
			(layer "F.SilkS")
			(effects
				(font
					(size 0.762 0.762)
					(thickness 0.2286)
				)
			)
		)
		(property "Value" "0.1uF"
			(at 2.09443 2.657602 270)
			(unlocked yes)
			(layer "F.SilkS")
			(hide yes)
			(effects
				(font
					(size 1.524 1.524)
					(thickness 0.254)
				)
			)
		)
		(sheetname "GPS_IMU_SENSORS")
		(sheetfile "GPS_IMU_SENSORS.kicad_sch")
		(duplicate_pad_numbers_are_jumpers no)
		(pad "1" smd rect
			(at -0.7 0)
			(size 1.1 1.05)
			(layers "F.Cu" "F.Mask" "F.Paste")
			(net "GND")
		)
		(pad "2" smd rect
			(at 0.7 0)
			(size 1.1 1.05)
			(layers "F.Cu" "F.Mask" "F.Paste")
			(net "+3.3V")
		)
	)
	(footprint "Vault:CAPC1608X90X35NL10T15"
		(layer "F.Cu")
		(at 206.3347 83.4132)
		(property "Reference" "C22"
			(at 1.479 0.396345 0)
			(unlocked yes)
			(layer "F.SilkS")
			(effects
				(font
					(size 0.762 0.762)
					(thickness 0.2286)
				)
				(justify left bottom)
			)
		)
		(property "Value" "0.033uF"
			(at 17.9043 13.68639 0)
			(unlocked yes)
			(layer "F.SilkS")
			(hide yes)
			(effects
				(font
					(size 1.524 1.524)
					(thickness 0.254)
				)
				(justify left bottom)
			)
		)
		(sheetname "POWER")
		(sheetfile "POWER.kicad_sch")
		(duplicate_pad_numbers_are_jumpers no)
		(pad "1" smd rect
			(at -0.675 0 90)
			(size 0.95 0.85)
			(layers "F.Cu" "F.Mask" "F.Paste")
			(net "NetC22_1")
		)
		(pad "2" smd rect
			(at 0.675 0 90)
			(size 0.95 0.85)
			(layers "F.Cu" "F.Mask" "F.Paste")
			(net "NetC22_2")
		)
	)
	(footprint "Vault:FP-LTST-C191TBKT-MFG"
		(layer "F.Cu")
		(at 69.8761 52.1162 90)
		(property "Reference" "D3"
			(at -6.771395 0.026921 90)
			(unlocked yes)
			(layer "F.SilkS")
			(effects
				(font
					(size 0.762 0.762)
					(thickness 0.2286)
				)
			)
		)
		(property "Value" "BLUE"
			(at 1.307195 2.479802 90)
			(unlocked yes)
			(layer "F.SilkS")
			(hide yes)
			(effects
				(font
					(size 1.524 1.524)
					(thickness 0.254)
				)
			)
		)
		(sheetname "USER_IO_STATUS")
		(sheetfile "USER_IO_STATUS.kicad_sch")
		(duplicate_pad_numbers_are_jumpers no)
		(fp_line
			(start -0.85 -0.8)
			(end 0.85 -0.8)
			(stroke
				(width 0.2)
				(type solid)
			)
			(layer "F.SilkS")
		)
		(fp_line
			(start -0.85 0.8)
			(end 0.85 0.8)
			(stroke
				(width 0.2)
				(type solid)
			)
			(layer "F.SilkS")
		)
		(fp_circle
			(center -1.75 0)
			(end -1.625 0)
			(stroke
				(width 0.25)
				(type solid)
			)
			(fill no)
			(layer "F.SilkS")
		)
		(fp_line
			(start 1.25 -0.55)
			(end 1.25 0.55)
			(stroke
				(width 0.2)
				(type solid)
			)
			(layer "F.CrtYd")
		)
		(fp_line
			(start -1.25 -0.55)
			(end 1.25 -0.55)
			(stroke
				(width 0.2)
				(type solid)
			)
			(layer "F.CrtYd")
		)
		(fp_line
			(start -1.25 -0.55)
			(end -1.25 0.55)
			(stroke
				(width 0.2)
				(type solid)
			)
			(layer "F.CrtYd")
		)
		(fp_line
			(start -1.25 0.55)
			(end 1.25 0.55)
			(stroke
				(width 0.2)
				(type solid)
			)
			(layer "F.CrtYd")
		)
		(fp_line
			(start 1.25 -0.55)
			(end 1.25 0.55)
			(stroke
				(width 0.2)
				(type solid)
			)
			(layer "F.Fab")
		)
		(fp_line
			(start -1.25 -0.55)
			(end 1.25 -0.55)
			(stroke
				(width 0.2)
				(type solid)
			)
			(layer "F.Fab")
		)
		(fp_line
			(start -1.25 -0.55)
			(end -1.25 0.55)
			(stroke
				(width 0.2)
				(type solid)
			)
			(layer "F.Fab")
		)
		(fp_line
			(start 0 -0.5)
			(end 0 0.5)
			(stroke
				(width 0.1)
				(type solid)
			)
			(layer "F.Fab")
		)
		(fp_line
			(start -0.5 0)
			(end 0.5 0)
			(stroke
				(width 0.1)
				(type solid)
			)
			(layer "F.Fab")
		)
		(fp_line
			(start -1.25 0.55)
			(end 1.25 0.55)
			(stroke
				(width 0.2)
				(type solid)
			)
			(layer "F.Fab")
		)
		(fp_text user "${REFERENCE}"
			(at 0 0.28424 90)
			(unlocked yes)
			(layer "F.Fab")
			(effects
				(font
					(face "Arial")
					(size 0.63 0.63)
					(thickness 0.1)
				)
				(justify left bottom)
			)
		)
		(pad "1" smd rect
			(at -0.75 0 90)
			(size 0.8 0.8)
			(layers "F.Cu" "F.Mask" "F.Paste")
			(net "NetD3_1")
			(solder_mask_margin 0)
			(solder_paste_margin 0)
		)
		(pad "2" smd rect
			(at 0.75 0 90)
			(size 0.8 0.8)
			(layers "F.Cu" "F.Mask" "F.Paste")
			(net "+3.3V")
			(solder_mask_margin 0)
			(solder_paste_margin 0)
		)
	)
	(footprint "FPGA_CONN:SingleFPGAConn"
		(layer "F.Cu")
		(at 162.57841 95.87725 -90)
		(property "Reference" "J35"
			(at -0.368955 -23.428208 270)
			(unlocked yes)
			(layer "F.SilkS")
			(effects
				(font
					(size 1.524 1.524)
					(thickness 0.254)
				)
			)
		)
		(property "Value" "Single FPGA Conn"
			(at 9.27992 3.521202 270)
			(unlocked yes)
			(layer "F.SilkS")
			(hide yes)
			(effects
				(font
					(size 1.524 1.524)
					(thickness 0.254)
				)
			)
		)
		(sheetname "FPGA")
		(sheetfile "FPGA.kicad_sch")
		(duplicate_pad_numbers_are_jumpers no)
		(fp_line
			(start -1.40005 1.24993)
			(end -1.40005 0.70002)
			(stroke
				(width 0.15011)
				(type solid)
			)
			(layer "F.SilkS")
		)
		(fp_line
			(start 1.40004 1.24993)
			(end -1.40005 1.24993)
			(stroke
				(width 0.15011)
				(type solid)
			)
			(layer "F.SilkS")
		)
		(fp_line
			(start 1.40004 1.24993)
			(end 1.40004 0.70002)
			(stroke
				(width 0.15011)
				(type solid)
			)
			(layer "F.SilkS")
		)
		(fp_line
			(start -2 0.70002)
			(end -2 0.03302)
			(stroke
				(width 0.15011)
				(type solid)
			)
			(layer "F.SilkS")
		)
		(fp_line
			(start -1.40005 0.70002)
			(end -2 0.70002)
			(stroke
				(width 0.15011)
				(type solid)
			)
			(layer "F.SilkS")
		)
		(fp_line
			(start 1.99999 0.70002)
			(end 1.40004 0.70002)
			(stroke
				(width 0.15011)
				(type solid)
			)
			(layer "F.SilkS")
		)
		(fp_line
			(start 1.99999 0.70002)
			(end 1.99999 0.03302)
			(stroke
				(width 0.15011)
				(type solid)
			)
			(layer "F.SilkS")
		)
		(fp_line
			(start -2 -20.03298)
			(end -2 -20.69999)
			(stroke
				(width 0.15011)
				(type solid)
			)
			(layer "F.SilkS")
		)
		(fp_line
			(start 1.99999 -20.03298)
			(end 1.99999 -20.69999)
			(stroke
				(width 0.15011)
				(type solid)
			)
			(layer "F.SilkS")
		)
		(fp_line
			(start -1.40005 -20.69999)
			(end -2 -20.69999)
			(stroke
				(width 0.15011)
				(type solid)
			)
			(layer "F.SilkS")
		)
		(fp_line
			(start -1.40005 -20.69999)
			(end -1.40005 -21.2499)
			(stroke
				(width 0.15011)
				(type solid)
			)
			(layer "F.SilkS")
		)
		(fp_line
			(start 1.40004 -20.69999)
			(end 1.40004 -21.2499)
			(stroke
				(width 0.15011)
				(type solid)
			)
			(layer "F.SilkS")
		)
		(fp_line
			(start 1.99999 -20.69999)
			(end 1.40004 -20.69999)
			(stroke
				(width 0.15011)
				(type solid)
			)
			(layer "F.SilkS")
		)
		(fp_line
			(start 1.40004 -21.2499)
			(end -1.40005 -21.2499)
			(stroke
				(width 0.15011)
				(type solid)
			)
			(layer "F.SilkS")
		)
		(fp_circle
			(center 3.5052 -0.22454)
			(end 3.30505 -0.22454)
			(stroke
				(width 0.40005)
				(type solid)
			)
			(fill no)
			(layer "F.SilkS")
		)
		(pad "1" smd rect
			(at 2.02488 -0.24994 270)
			(size 1.54991 0.24994)
			(layers "F.Cu" "F.Mask" "F.Paste")
		)
		(pad "2" smd rect
			(at -2.02489 -0.24994 270)
			(size 1.54991 0.24994)
			(layers "F.Cu" "F.Mask" "F.Paste")
		)
		(pad "3" smd rect
			(at 2.02488 -0.75007 270)
			(size 1.54991 0.24994)
			(layers "F.Cu" "F.Mask" "F.Paste")
		)
		(pad "4" smd rect
			(at -2.02489 -0.75007 270)
			(size 1.54991 0.24994)
			(layers "F.Cu" "F.Mask" "F.Paste")
		)
		(pad "5" smd rect
			(at 2.02488 -1.24994 270)
			(size 1.54991 0.24994)
			(layers "F.Cu" "F.Mask" "F.Paste")
		)
		(pad "6" smd rect
			(at -2.02489 -1.24994 270)
			(size 1.54991 0.24994)
			(layers "F.Cu" "F.Mask" "F.Paste")
		)
		(pad "7" smd rect
			(at 2.02488 -1.75006 270)
			(size 1.54991 0.24994)
			(layers "F.Cu" "F.Mask" "F.Paste")
		)
		(pad "8" smd rect
			(at -2.02489 -1.75006 270)
			(size 1.54991 0.24994)
			(layers "F.Cu" "F.Mask" "F.Paste")
			(net "MAC_USB_PWR")
		)
		(pad "9" smd rect
			(at 2.02488 -2.24994 270)
			(size 1.54991 0.24994)
			(layers "F.Cu" "F.Mask" "F.Paste")
			(net "GND")
		)
		(pad "10" smd rect
			(at -2.02489 -2.24994 270)
			(size 1.54991 0.24994)
			(layers "F.Cu" "F.Mask" "F.Paste")
			(net "GND")
		)
		(pad "11" smd rect
			(at 2.02488 -2.75006 270)
			(size 1.54991 0.24994)
			(layers "F.Cu" "F.Mask" "F.Paste")
			(net "MAC_RF_OUT")
		)
		(pad "12" smd rect
			(at -2.02489 -2.75006 270)
			(size 1.54991 0.24994)
			(layers "F.Cu" "F.Mask" "F.Paste")
		)
		(pad "13" smd rect
			(at 2.02488 -3.24993 270)
			(size 1.54991 0.24994)
			(layers "F.Cu" "F.Mask" "F.Paste")
			(net "MAC_RF_OUT")
		)
		(pad "14" smd rect
			(at -2.02489 -3.24993 270)
			(size 1.54991 0.24994)
			(layers "F.Cu" "F.Mask" "F.Paste")
		)
		(pad "15" smd rect
			(at 2.02488 -3.75006 270)
			(size 1.54991 0.24994)
			(layers "F.Cu" "F.Mask" "F.Paste")
			(net "ANT1_OUT")
		)
		(pad "16" smd rect
			(at -2.02489 -3.75006 270)
			(size 1.54991 0.24994)
			(layers "F.Cu" "F.Mask" "F.Paste")
			(net "ANT3_IN")
		)
		(pad "17" smd rect
			(at 2.02488 -4.24993 270)
			(size 1.54991 0.24994)
			(layers "F.Cu" "F.Mask" "F.Paste")
			(net "ANT2_OUT")
		)
		(pad "18" smd rect
			(at -2.02489 -4.24993 270)
			(size 1.54991 0.24994)
			(layers "F.Cu" "F.Mask" "F.Paste")
			(net "ANT4_IN")
		)
		(pad "19" smd rect
			(at 2.02488 -4.75006 270)
			(size 1.54991 0.24994)
			(layers "F.Cu" "F.Mask" "F.Paste")
			(net "GND")
		)
		(pad "20" smd rect
			(at -2.02489 -4.75006 270)
			(size 1.54991 0.24994)
			(layers "F.Cu" "F.Mask" "F.Paste")
			(net "GND")
		)
		(pad "21" smd rect
			(at 2.02488 -5.24993 270)
			(size 1.54991 0.24994)
			(layers "F.Cu" "F.Mask" "F.Paste")
			(net "ANT1_IN")
		)
		(pad "22" smd rect
			(at -2.02489 -5.24993 270)
			(size 1.54991 0.24994)
			(layers "F.Cu" "F.Mask" "F.Paste")
		)
		(pad "23" smd rect
			(at 2.02488 -5.75006 270)
			(size 1.54991 0.24994)
			(layers "F.Cu" "F.Mask" "F.Paste")
			(net "ANT2_IN")
		)
		(pad "24" smd rect
			(at -2.02489 -5.75006 270)
			(size 1.54991 0.24994)
			(layers "F.Cu" "F.Mask" "F.Paste")
		)
		(pad "25" smd rect
			(at 2.02488 -6.24993 270)
			(size 1.54991 0.24994)
			(layers "F.Cu" "F.Mask" "F.Paste")
			(net "ANT3_OUT")
		)
		(pad "26" smd rect
			(at -2.02489 -6.24993 270)
			(size 1.54991 0.24994)
			(layers "F.Cu" "F.Mask" "F.Paste")
			(net "MAC_TX")
		)
		(pad "27" smd rect
			(at 2.02488 -6.75005 270)
			(size 1.54991 0.24994)
			(layers "F.Cu" "F.Mask" "F.Paste")
			(net "ANT4_OUT")
		)
		(pad "28" smd rect
			(at -2.02489 -6.75005 270)
			(size 1.54991 0.24994)
			(layers "F.Cu" "F.Mask" "F.Paste")
			(net "MAC_RX")
		)
		(pad "29" smd rect
			(at 2.02488 -7.24993 270)
			(size 1.54991 0.24994)
			(layers "F.Cu" "F.Mask" "F.Paste")
			(net "GND")
		)
		(pad "30" smd rect
			(at -2.02489 -7.24993 270)
			(size 1.54991 0.24994)
			(layers "F.Cu" "F.Mask" "F.Paste")
			(net "GND")
		)
		(pad "31" smd rect
			(at 2.02488 -7.75005 270)
			(size 1.54991 0.24994)
			(layers "F.Cu" "F.Mask" "F.Paste")
		)
		(pad "32" smd rect
			(at -2.02489 -7.75005 270)
			(size 1.54991 0.24994)
			(layers "F.Cu" "F.Mask" "F.Paste")
		)
		(pad "33" smd rect
			(at 2.02488 -8.24992 270)
			(size 1.54991 0.24994)
			(layers "F.Cu" "F.Mask" "F.Paste")
			(net "MAC_FREQ_CTRL")
		)
		(pad "34" smd rect
			(at -2.02489 -8.24992 270)
			(size 1.54991 0.24994)
			(layers "F.Cu" "F.Mask" "F.Paste")
		)
		(pad "35" smd rect
			(at 2.02488 -8.75005 270)
			(size 1.54991 0.24994)
			(layers "F.Cu" "F.Mask" "F.Paste")
			(net "MAC_ALARM")
		)
		(pad "36" smd rect
			(at -2.02489 -8.75005 270)
			(size 1.54991 0.24994)
			(layers "F.Cu" "F.Mask" "F.Paste")
		)
		(pad "37" smd rect
			(at 2.02488 -9.24992 270)
			(size 1.54991 0.24994)
			(layers "F.Cu" "F.Mask" "F.Paste")
			(net "MAC_BITE")
		)
		(pad "38" smd rect
			(at -2.02489 -9.24992 270)
			(size 1.54991 0.24994)
			(layers "F.Cu" "F.Mask" "F.Paste")
		)
		(pad "39" smd rect
			(at 2.02488 -9.75005 270)
			(size 1.54991 0.24994)
			(layers "F.Cu" "F.Mask" "F.Paste")
			(net "GND")
		)
		(pad "40" smd rect
			(at -2.02489 -9.75005 270)
			(size 1.54991 0.24994)
			(layers "F.Cu" "F.Mask" "F.Paste")
			(net "GND")
		)
		(pad "41" smd rect
			(at 2.02488 -10.24992 270)
			(size 1.54991 0.24994)
			(layers "F.Cu" "F.Mask" "F.Paste")
		)
		(pad "42" smd rect
			(at -2.02489 -10.24992 270)
			(size 1.54991 0.24994)
			(layers "F.Cu" "F.Mask" "F.Paste")
		)
		(pad "43" smd rect
			(at 2.02488 -10.75005 270)
			(size 1.54991 0.24994)
			(layers "F.Cu" "F.Mask" "F.Paste")
			(net "FPGA_MAC_PPS_OUT-")
		)
		(pad "44" smd rect
			(at -2.02489 -10.75005 270)
			(size 1.54991 0.24994)
			(layers "F.Cu" "F.Mask" "F.Paste")
		)
		(pad "45" smd rect
			(at 2.02488 -11.24992 270)
			(size 1.54991 0.24994)
			(layers "F.Cu" "F.Mask" "F.Paste")
		)
		(pad "46" smd rect
			(at -2.02489 -11.24992 270)
			(size 1.54991 0.24994)
			(layers "F.Cu" "F.Mask" "F.Paste")
		)
		(pad "47" smd rect
			(at 2.02488 -11.75004 270)
			(size 1.54991 0.24994)
			(layers "F.Cu" "F.Mask" "F.Paste")
			(net "FPGA_MAC_PPS_IN0-")
		)
		(pad "48" smd rect
			(at -2.02489 -11.75004 270)
			(size 1.54991 0.24994)
			(layers "F.Cu" "F.Mask" "F.Paste")
		)
		(pad "49" smd rect
			(at 2.02488 -12.24992 270)
			(size 1.54991 0.24994)
			(layers "F.Cu" "F.Mask" "F.Paste")
			(net "GND")
		)
		(pad "50" smd rect
			(at -2.02489 -12.24992 270)
			(size 1.54991 0.24994)
			(layers "F.Cu" "F.Mask" "F.Paste")
			(net "GND")
		)
		(pad "51" smd rect
			(at 2.02488 -12.75004 270)
			(size 1.54991 0.24994)
			(layers "F.Cu" "F.Mask" "F.Paste")
		)
		(pad "52" smd rect
			(at -2.02489 -12.75004 270)
			(size 1.54991 0.24994)
			(layers "F.Cu" "F.Mask" "F.Paste")
		)
		(pad "53" smd rect
			(at 2.02488 -13.24991 270)
			(size 1.54991 0.24994)
			(layers "F.Cu" "F.Mask" "F.Paste")
			(net "FPGA_MAC_PPS_IN1-")
		)
		(pad "54" smd rect
			(at -2.02489 -13.24991 270)
			(size 1.54991 0.24994)
			(layers "F.Cu" "F.Mask" "F.Paste")
		)
		(pad "55" smd rect
			(at 2.02488 -13.75004 270)
			(size 1.54991 0.24994)
			(layers "F.Cu" "F.Mask" "F.Paste")
		)
		(pad "56" smd rect
			(at -2.02489 -13.75004 270)
			(size 1.54991 0.24994)
			(layers "F.Cu" "F.Mask" "F.Paste")
		)
		(pad "57" smd rect
			(at 2.02488 -14.24991 270)
			(size 1.54991 0.24994)
			(layers "F.Cu" "F.Mask" "F.Paste")
		)
		(pad "58" smd rect
			(at -2.02489 -14.24991 270)
			(size 1.54991 0.24994)
			(layers "F.Cu" "F.Mask" "F.Paste")
		)
		(pad "59" smd rect
			(at 2.02488 -14.75004 270)
			(size 1.54991 0.24994)
			(layers "F.Cu" "F.Mask" "F.Paste")
			(net "GND")
		)
		(pad "60" smd rect
			(at -2.02489 -14.75004 270)
			(size 1.54991 0.24994)
			(layers "F.Cu" "F.Mask" "F.Paste")
			(net "GND")
		)
		(pad "61" smd rect
			(at 2.02488 -15.24991 270)
			(size 1.54991 0.24994)
			(layers "F.Cu" "F.Mask" "F.Paste")
			(net "SDA")
		)
		(pad "62" smd rect
			(at -2.02489 -15.24991 270)
			(size 1.54991 0.24994)
			(layers "F.Cu" "F.Mask" "F.Paste")
		)
		(pad "63" smd rect
			(at 2.02488 -15.75004 270)
			(size 1.54991 0.24994)
			(layers "F.Cu" "F.Mask" "F.Paste")
		)
		(pad "64" smd rect
			(at -2.02489 -15.75004 270)
			(size 1.54991 0.24994)
			(layers "F.Cu" "F.Mask" "F.Paste")
		)
		(pad "65" smd rect
			(at 2.02488 -16.24991 270)
			(size 1.54991 0.24994)
			(layers "F.Cu" "F.Mask" "F.Paste")
		)
		(pad "66" smd rect
			(at -2.02489 -16.24991 270)
			(size 1.54991 0.24994)
			(layers "F.Cu" "F.Mask" "F.Paste")
		)
		(pad "67" smd rect
			(at 2.02488 -16.75003 270)
			(size 1.54991 0.24994)
			(layers "F.Cu" "F.Mask" "F.Paste")
			(net "SCL")
		)
		(pad "68" smd rect
			(at -2.02489 -16.75003 270)
			(size 1.54991 0.24994)
			(layers "F.Cu" "F.Mask" "F.Paste")
		)
		(pad "69" smd rect
			(at 2.02488 -17.24991 270)
			(size 1.54991 0.24994)
			(layers "F.Cu" "F.Mask" "F.Paste")
			(net "GND")
		)
		(pad "70" smd rect
			(at -2.02489 -17.24991 270)
			(size 1.54991 0.24994)
			(layers "F.Cu" "F.Mask" "F.Paste")
			(net "GND")
		)
		(pad "71" smd rect
			(at 2.02488 -17.75003 270)
			(size 1.54991 0.24994)
			(layers "F.Cu" "F.Mask" "F.Paste")
			(net "UART1_TXD")
		)
		(pad "72" smd rect
			(at -2.02489 -17.75003 270)
			(size 1.54991 0.24994)
			(layers "F.Cu" "F.Mask" "F.Paste")
			(net "MAC_USB+")
		)
		(pad "73" smd rect
			(at 2.02488 -18.2499 270)
			(size 1.54991 0.24994)
			(layers "F.Cu" "F.Mask" "F.Paste")
		)
		(pad "74" smd rect
			(at -2.02489 -18.2499 270)
			(size 1.54991 0.24994)
			(layers "F.Cu" "F.Mask" "F.Paste")
			(net "MAC_USB-")
		)
		(pad "75" smd rect
			(at 2.02488 -18.75003 270)
			(size 1.54991 0.24994)
			(layers "F.Cu" "F.Mask" "F.Paste")
		)
		(pad "76" smd rect
			(at -2.02489 -18.75003 270)
			(size 1.54991 0.24994)
			(layers "F.Cu" "F.Mask" "F.Paste")
		)
		(pad "77" smd rect
			(at 2.02488 -19.2499 270)
			(size 1.54991 0.24994)
			(layers "F.Cu" "F.Mask" "F.Paste")
			(net "UART1_RXD")
		)
		(pad "78" smd rect
			(at -2.02489 -19.2499 270)
			(size 1.54991 0.24994)
			(layers "F.Cu" "F.Mask" "F.Paste")
		)
		(pad "79" smd rect
			(at 2.02488 -19.75003 270)
			(size 1.54991 0.24994)
			(layers "F.Cu" "F.Mask" "F.Paste")
			(net "GPS1_RX")
		)
		(pad "80" smd rect
			(at -2.02489 -19.75003 270)
			(size 1.54991 0.24994)
			(layers "F.Cu" "F.Mask" "F.Paste")
			(net "GPS1_TX")
		)
		(pad "81" smd rect
			(at 0.01135 1.17625 270)
			(size 1.70002 1.35001)
			(layers "F.Cu" "F.Mask" "F.Paste")
		)
		(pad "82" thru_hole circle
			(at 0 0 270)
			(size 0.55016 0.55016)
			(drill 0.55016)
			(layers "*.Cu" "*.Mask")
			(remove_unused_layers no)
			(thermal_bridge_angle 90)
		)
		(pad "83" thru_hole circle
			(at 0 -19.99996 270)
			(size 0.55016 0.55016)
			(drill 0.55016)
			(layers "*.Cu" "*.Mask")
			(remove_unused_layers no)
			(thermal_bridge_angle 90)
		)
		(pad "84" smd rect
			(at 0.01135 -21.17375 270)
			(size 1.70002 1.35001)
			(layers "F.Cu" "F.Mask" "F.Paste")
		)
	)
	(footprint "Resistors:RESC1608X50N"
		(layer "F.Cu")
		(at 206.3637 81.8662 180)
		(property "Reference" "R9"
			(at -2.427 -0.395345 0)
			(unlocked yes)
			(layer "F.SilkS")
			(effects
				(font
					(size 0.762 0.762)
					(thickness 0.2286)
				)
				(justify left bottom)
			)
		)
		(property "Value" "ERJ-3EKF2201V"
			(at -18.6651 -15.15359 0)
			(unlocked yes)
			(layer "F.SilkS")
			(hide yes)
			(effects
				(font
					(size 1.524 1.524)
					(thickness 0.254)
				)
				(justify left bottom)
			)
		)
		(sheetname "POWER")
		(sheetfile "POWER.kicad_sch")
		(duplicate_pad_numbers_are_jumpers no)
		(fp_line
			(start 0 -0.5)
			(end 0 0.5)
			(stroke
				(width 0.1524)
				(type solid)
			)
			(layer "F.SilkS")
		)
		(pad "1" smd rect
			(at -0.69 0 270)
			(size 1 0.72)
			(layers "F.Cu" "F.Mask" "F.Paste")
			(net "GND")
		)
		(pad "2" smd rect
			(at 0.69 0 270)
			(size 1 0.72)
			(layers "F.Cu" "F.Mask" "F.Paste")
			(net "NetC22_1")
		)
	)
	(footprint "Vault:CAPC1608X87X45ML20T05"
		(layer "F.Cu")
		(at 210.7637 90.4662 90)
		(property "Reference" "C10"
			(at 4.1 1.006655 270)
			(unlocked yes)
			(layer "F.SilkS")
			(effects
				(font
					(size 0.762 0.762)
					(thickness 0.2286)
				)
				(justify left bottom)
			)
		)
		(property "Value" "0.1uF"
			(at -10.71339 4.9073 0)
			(unlocked yes)
			(layer "F.SilkS")
			(hide yes)
			(effects
				(font
					(size 1.524 1.524)
					(thickness 0.254)
				)
				(justify left bottom)
			)
		)
		(sheetname "POWER")
		(sheetfile "POWER.kicad_sch")
		(duplicate_pad_numbers_are_jumpers no)
		(pad "1" smd rect
			(at -0.7 0 180)
			(size 1.1 1.05)
			(layers "F.Cu" "F.Mask" "F.Paste")
			(net "GND")
		)
		(pad "2" smd rect
			(at 0.7 0 180)
			(size 1.1 1.05)
			(layers "F.Cu" "F.Mask" "F.Paste")
			(net "+3.3V")
		)
	)
	(footprint "SamacSys:SOP50P310X90-8N"
		(layer "F.Cu")
		(at 82.3761 109.1162 180)
		(property "Reference" "U12"
			(at 0.2286 2.026931 180)
			(unlocked yes)
			(layer "F.SilkS")
			(effects
				(font
					(size 0.762 0.762)
					(thickness 0.2286)
				)
			)
		)
		(property "Value" "NC7WV125K8X"
			(at 6.233115 2.911602 180)
			(unlocked yes)
			(layer "F.SilkS")
			(hide yes)
			(effects
				(font
					(size 1.524 1.524)
					(thickness 0.254)
				)
			)
		)
		(sheetname "USER_IO")
		(sheetfile "USER_IO.kicad_sch")
		(duplicate_pad_numbers_are_jumpers no)
		(fp_line
			(start 0.8 1)
			(end -0.8 1)
			(stroke
				(width 0.2)
				(type solid)
			)
			(layer "F.SilkS")
		)
		(fp_line
			(start 0.8 -1)
			(end 0.8 1)
			(stroke
				(width 0.2)
				(type solid)
			)
			(layer "F.SilkS")
		)
		(fp_line
			(start 0.8 -1)
			(end -0.8 -1)
			(stroke
				(width 0.2)
				(type solid)
			)
			(layer "F.SilkS")
		)
		(fp_line
			(start -0.8 -1)
			(end -0.8 1)
			(stroke
				(width 0.2)
				(type solid)
			)
			(layer "F.SilkS")
		)
		(fp_line
			(start -1.15 -1.25)
			(end -2 -1.25)
			(stroke
				(width 0.2)
				(type solid)
			)
			(layer "F.SilkS")
		)
		(pad "1" smd rect
			(at -1.575 -0.75 180)
			(size 0.85 0.3)
			(layers "F.Cu" "F.Mask" "F.Paste")
			(net "ANT2_IO_OUT")
		)
		(pad "2" smd rect
			(at -1.575 -0.25 180)
			(size 0.85 0.3)
			(layers "F.Cu" "F.Mask" "F.Paste")
			(net "ANT2_OUT")
		)
		(pad "3" smd rect
			(at -1.575 0.25 180)
			(size 0.85 0.3)
			(layers "F.Cu" "F.Mask" "F.Paste")
			(net "ANT2_IN")
		)
		(pad "4" smd rect
			(at -1.575 0.75 180)
			(size 0.85 0.3)
			(layers "F.Cu" "F.Mask" "F.Paste")
			(net "GND")
		)
		(pad "5" smd rect
			(at 1.575 0.75 180)
			(size 0.85 0.3)
			(layers "F.Cu" "F.Mask" "F.Paste")
			(net "NetR33_1")
		)
		(pad "6" smd rect
			(at 1.575 0.25 180)
			(size 0.85 0.3)
			(layers "F.Cu" "F.Mask" "F.Paste")
			(net "NetR33_1")
		)
		(pad "7" smd rect
			(at 1.575 -0.25 180)
			(size 0.85 0.3)
			(layers "F.Cu" "F.Mask" "F.Paste")
			(net "ANT2_IO_IN")
		)
		(pad "8" smd rect
			(at 1.575 -0.75 180)
			(size 0.85 0.3)
			(layers "F.Cu" "F.Mask" "F.Paste")
			(net "+3.3V")
		)
	)
	(footprint "Passives:SOT65P210X110-3N"
		(layer "F.Cu")
		(at 195.11136 139.37763)
		(property "Reference" "D5"
			(at -3.38526 -0.968085 0)
			(unlocked yes)
			(layer "F.SilkS")
			(effects
				(font
					(size 0.762 0.762)
					(thickness 0.2286)
				)
				(justify left bottom)
			)
		)
		(property "Value" "BAT54SW"
			(at -10.7749 -6.23021 0)
			(unlocked yes)
			(layer "F.SilkS")
			(hide yes)
			(effects
				(font
					(size 1.524 1.524)
					(thickness 0.254)
				)
				(justify left bottom)
			)
		)
		(sheetname "PCIe_JTAG")
		(sheetfile "PCIe_JTAG.kicad_sch")
		(duplicate_pad_numbers_are_jumpers no)
		(fp_line
			(start -0.325 -1.1)
			(end 0.675 -1.1)
			(stroke
				(width 0.2)
				(type solid)
			)
			(layer "F.SilkS")
		)
		(fp_line
			(start -0.325 1.1)
			(end 0.675 1.1)
			(stroke
				(width 0.2)
				(type solid)
			)
			(layer "F.SilkS")
		)
		(fp_line
			(start 0.675 -0.65)
			(end 0.675 -1.1)
			(stroke
				(width 0.2)
				(type solid)
			)
			(layer "F.SilkS")
		)
		(fp_line
			(start 0.675 1.1)
			(end 0.675 0.65)
			(stroke
				(width 0.2)
				(type solid)
			)
			(layer "F.SilkS")
		)
		(fp_circle
			(center -1.125 -1.45)
			(end -1.125 -1.575)
			(stroke
				(width 0.25)
				(type solid)
			)
			(fill no)
			(layer "F.SilkS")
		)
		(pad "1" smd rect
			(at -1.125 -0.65 90)
			(size 0.5 0.9)
			(layers "F.Cu" "F.Mask" "F.Paste")
			(net "GND")
		)
		(pad "2" smd rect
			(at -1.125 0.65 90)
			(size 0.5 0.9)
			(layers "F.Cu" "F.Mask" "F.Paste")
			(net "+3.3V")
		)
		(pad "3" smd rect
			(at 1.125 0 90)
			(size 0.5 0.9)
			(layers "F.Cu" "F.Mask" "F.Paste")
			(net "FPGA_TCK")
		)
	)
	(footprint "Vault:CAPC1608X87X45ML20T05"
		(layer "F.Cu")
		(at 213.4735 116.3062 90)
		(property "Reference" "C17"
			(at 1.74 0.708345 90)
			(unlocked yes)
			(layer "F.SilkS")
			(effects
				(font
					(size 0.762 0.762)
					(thickness 0.2286)
				)
				(justify left bottom)
			)
		)
		(property "Value" "0.1uF"
			(at -6.58639 0.0755 0)
			(unlocked yes)
			(layer "F.SilkS")
			(hide yes)
			(effects
				(font
					(size 1.524 1.524)
					(thickness 0.254)
				)
				(justify left bottom)
			)
		)
		(sheetname "POWER")
		(sheetfile "POWER.kicad_sch")
		(duplicate_pad_numbers_are_jumpers no)
		(pad "1" smd rect
			(at -0.7 0 180)
			(size 1.1 1.05)
			(layers "F.Cu" "F.Mask" "F.Paste")
			(net "GND")
		)
		(pad "2" smd rect
			(at 0.7 0 180)
			(size 1.1 1.05)
			(layers "F.Cu" "F.Mask" "F.Paste")
			(net "+5.0V")
		)
	)
	(footprint "FPGA_CONN:SingleFPGAConn"
		(layer "F.Cu")
		(at 149.7158 124.56234)
		(property "Reference" "J36"
			(at -0.368955 -23.428198 0)
			(unlocked yes)
			(layer "F.SilkS")
			(effects
				(font
					(size 1.524 1.524)
					(thickness 0.254)
				)
			)
		)
		(property "Value" "Single FPGA Conn"
			(at 9.27992 3.521202 0)
			(unlocked yes)
			(layer "F.SilkS")
			(hide yes)
			(effects
				(font
					(size 1.524 1.524)
					(thickness 0.254)
				)
			)
		)
		(sheetname "FPGA")
		(sheetfile "FPGA.kicad_sch")
		(duplicate_pad_numbers_are_jumpers no)
		(fp_line
			(start -1.99999 -20.69998)
			(end -1.40005 -20.69998)
			(stroke
				(width 0.15011)
				(type solid)
			)
			(layer "F.SilkS")
		)
		(fp_line
			(start -1.99999 -20.03298)
			(end -1.99999 -20.69998)
			(stroke
				(width 0.15011)
				(type solid)
			)
			(layer "F.SilkS")
		)
		(fp_line
			(start -1.99999 0.70003)
			(end -1.99999 0.03302)
			(stroke
				(width 0.15011)
				(type solid)
			)
			(layer "F.SilkS")
		)
		(fp_line
			(start -1.99999 0.70003)
			(end -1.40005 0.70003)
			(stroke
				(width 0.15011)
				(type solid)
			)
			(layer "F.SilkS")
		)
		(fp_line
			(start -1.40005 -21.24989)
			(end 1.40005 -21.24989)
			(stroke
				(width 0.15011)
				(type solid)
			)
			(layer "F.SilkS")
		)
		(fp_line
			(start -1.40005 -20.69998)
			(end -1.40005 -21.24989)
			(stroke
				(width 0.15011)
				(type solid)
			)
			(layer "F.SilkS")
		)
		(fp_line
			(start -1.40005 1.24994)
			(end -1.40005 0.70003)
			(stroke
				(width 0.15011)
				(type solid)
			)
			(layer "F.SilkS")
		)
		(fp_line
			(start -1.40005 1.24994)
			(end 1.40005 1.24994)
			(stroke
				(width 0.15011)
				(type solid)
			)
			(layer "F.SilkS")
		)
		(fp_line
			(start 1.40005 -20.69998)
			(end 1.40005 -21.24989)
			(stroke
				(width 0.15011)
				(type solid)
			)
			(layer "F.SilkS")
		)
		(fp_line
			(start 1.40005 -20.69998)
			(end 2 -20.69998)
			(stroke
				(width 0.15011)
				(type solid)
			)
			(layer "F.SilkS")
		)
		(fp_line
			(start 1.40005 0.70003)
			(end 2 0.70003)
			(stroke
				(width 0.15011)
				(type solid)
			)
			(layer "F.SilkS")
		)
		(fp_line
			(start 1.40005 1.24994)
			(end 1.40005 0.70003)
			(stroke
				(width 0.15011)
				(type solid)
			)
			(layer "F.SilkS")
		)
		(fp_line
			(start 2 -20.03298)
			(end 2 -20.69998)
			(stroke
				(width 0.15011)
				(type solid)
			)
			(layer "F.SilkS")
		)
		(fp_line
			(start 2 0.70003)
			(end 2 0.03302)
			(stroke
				(width 0.15011)
				(type solid)
			)
			(layer "F.SilkS")
		)
		(fp_circle
			(center 3.5052 -0.22453)
			(end 3.5052 -0.42468)
			(stroke
				(width 0.40005)
				(type solid)
			)
			(fill no)
			(layer "F.SilkS")
		)
		(pad "1" smd rect
			(at 2.02489 -0.24993)
			(size 1.54991 0.24994)
			(layers "F.Cu" "F.Mask" "F.Paste")
			(net "GPS2_TX")
		)
		(pad "2" smd rect
			(at -2.02489 -0.24993)
			(size 1.54991 0.24994)
			(layers "F.Cu" "F.Mask" "F.Paste")
			(net "GPS2_RX")
		)
		(pad "3" smd rect
			(at 2.02489 -0.75006)
			(size 1.54991 0.24994)
			(layers "F.Cu" "F.Mask" "F.Paste")
		)
		(pad "4" smd rect
			(at -2.02489 -0.75006)
			(size 1.54991 0.24994)
			(layers "F.Cu" "F.Mask" "F.Paste")
		)
		(pad "5" smd rect
			(at 2.02489 -1.24993)
			(size 1.54991 0.24994)
			(layers "F.Cu" "F.Mask" "F.Paste")
			(net "GPS2_TP1")
		)
		(pad "6" smd rect
			(at -2.02489 -1.24993)
			(size 1.54991 0.24994)
			(layers "F.Cu" "F.Mask" "F.Paste")
		)
		(pad "7" smd rect
			(at 2.02489 -1.75006)
			(size 1.54991 0.24994)
			(layers "F.Cu" "F.Mask" "F.Paste")
			(net "GPS2_TP2")
		)
		(pad "8" smd rect
			(at -2.02489 -1.75006)
			(size 1.54991 0.24994)
			(layers "F.Cu" "F.Mask" "F.Paste")
		)
		(pad "9" smd rect
			(at 2.02489 -2.24993)
			(size 1.54991 0.24994)
			(layers "F.Cu" "F.Mask" "F.Paste")
			(net "GND")
		)
		(pad "10" smd rect
			(at -2.02489 -2.24993)
			(size 1.54991 0.24994)
			(layers "F.Cu" "F.Mask" "F.Paste")
			(net "GND")
		)
		(pad "11" smd rect
			(at 2.02489 -2.75006)
			(size 1.54991 0.24994)
			(layers "F.Cu" "F.Mask" "F.Paste")
			(net "GPS2_RST")
		)
		(pad "12" smd rect
			(at -2.02489 -2.75006)
			(size 1.54991 0.24994)
			(layers "F.Cu" "F.Mask" "F.Paste")
			(net "IO_LED1")
		)
		(pad "13" smd rect
			(at 2.02489 -3.24993)
			(size 1.54991 0.24994)
			(layers "F.Cu" "F.Mask" "F.Paste")
		)
		(pad "14" smd rect
			(at -2.02489 -3.24993)
			(size 1.54991 0.24994)
			(layers "F.Cu" "F.Mask" "F.Paste")
			(net "IO_LED2")
		)
		(pad "15" smd rect
			(at 2.02489 -3.75005)
			(size 1.54991 0.24994)
			(layers "F.Cu" "F.Mask" "F.Paste")
		)
		(pad "16" smd rect
			(at -2.02489 -3.75005)
			(size 1.54991 0.24994)
			(layers "F.Cu" "F.Mask" "F.Paste")
			(net "IO_LED3")
		)
		(pad "17" smd rect
			(at 2.02489 -4.24993)
			(size 1.54991 0.24994)
			(layers "F.Cu" "F.Mask" "F.Paste")
		)
		(pad "18" smd rect
			(at -2.02489 -4.24993)
			(size 1.54991 0.24994)
			(layers "F.Cu" "F.Mask" "F.Paste")
			(net "IO_LED4")
		)
		(pad "19" smd rect
			(at 2.02489 -4.75005)
			(size 1.54991 0.24994)
			(layers "F.Cu" "F.Mask" "F.Paste")
			(net "GND")
		)
		(pad "20" smd rect
			(at -2.02489 -4.75005)
			(size 1.54991 0.24994)
			(layers "F.Cu" "F.Mask" "F.Paste")
			(net "GND")
		)
		(pad "21" smd rect
			(at 2.02489 -5.24992)
			(size 1.54991 0.24994)
			(layers "F.Cu" "F.Mask" "F.Paste")
			(net "PCIE_PERST")
		)
		(pad "22" smd rect
			(at -2.02489 -5.24992)
			(size 1.54991 0.24994)
			(layers "F.Cu" "F.Mask" "F.Paste")
		)
		(pad "23" smd rect
			(at 2.02489 -5.75005)
			(size 1.54991 0.24994)
			(layers "F.Cu" "F.Mask" "F.Paste")
			(net "KEY1")
		)
		(pad "24" smd rect
			(at -2.02489 -5.75005)
			(size 1.54991 0.24994)
			(layers "F.Cu" "F.Mask" "F.Paste")
		)
		(pad "25" smd rect
			(at 2.02489 -6.24992)
			(size 1.54991 0.24994)
			(layers "F.Cu" "F.Mask" "F.Paste")
		)
		(pad "26" smd rect
			(at -2.02489 -6.24992)
			(size 1.54991 0.24994)
			(layers "F.Cu" "F.Mask" "F.Paste")
		)
		(pad "27" smd rect
			(at 2.02489 -6.75005)
			(size 1.54991 0.24994)
			(layers "F.Cu" "F.Mask" "F.Paste")
		)
		(pad "28" smd rect
			(at -2.02489 -6.75005)
			(size 1.54991 0.24994)
			(layers "F.Cu" "F.Mask" "F.Paste")
		)
		(pad "29" smd rect
			(at 2.02489 -7.24992)
			(size 1.54991 0.24994)
			(layers "F.Cu" "F.Mask" "F.Paste")
			(net "GND")
		)
		(pad "30" smd rect
			(at -2.02489 -7.24992)
			(size 1.54991 0.24994)
			(layers "F.Cu" "F.Mask" "F.Paste")
			(net "GND")
		)
		(pad "31" smd rect
			(at 2.02489 -7.75005)
			(size 1.54991 0.24994)
			(layers "F.Cu" "F.Mask" "F.Paste")
			(net "ANT1_IO_OUT")
		)
		(pad "32" smd rect
			(at -2.02489 -7.75005)
			(size 1.54991 0.24994)
			(layers "F.Cu" "F.Mask" "F.Paste")
			(net "EXT_GPIO_7")
		)
		(pad "33" smd rect
			(at 2.02489 -8.24992)
			(size 1.54991 0.24994)
			(layers "F.Cu" "F.Mask" "F.Paste")
			(net "ANT1_IO_IN")
		)
		(pad "34" smd rect
			(at -2.02489 -8.24992)
			(size 1.54991 0.24994)
			(layers "F.Cu" "F.Mask" "F.Paste")
			(net "EXT_GPIO_8")
		)
		(pad "35" smd rect
			(at 2.02489 -8.75004)
			(size 1.54991 0.24994)
			(layers "F.Cu" "F.Mask" "F.Paste")
			(net "ANT2_IO_OUT")
		)
		(pad "36" smd rect
			(at -2.02489 -8.75004)
			(size 1.54991 0.24994)
			(layers "F.Cu" "F.Mask" "F.Paste")
			(net "EXT_GPIO_9")
		)
		(pad "37" smd rect
			(at 2.02489 -9.24992)
			(size 1.54991 0.24994)
			(layers "F.Cu" "F.Mask" "F.Paste")
			(net "ANT2_IO_IN")
		)
		(pad "38" smd rect
			(at -2.02489 -9.24992)
			(size 1.54991 0.24994)
			(layers "F.Cu" "F.Mask" "F.Paste")
			(net "EXT_GPIO_10")
		)
		(pad "39" smd rect
			(at 2.02489 -9.75004)
			(size 1.54991 0.24994)
			(layers "F.Cu" "F.Mask" "F.Paste")
			(net "GND")
		)
		(pad "40" smd rect
			(at -2.02489 -9.75004)
			(size 1.54991 0.24994)
			(layers "F.Cu" "F.Mask" "F.Paste")
			(net "GND")
		)
		(pad "41" smd rect
			(at 2.02489 -10.24991)
			(size 1.54991 0.24994)
			(layers "F.Cu" "F.Mask" "F.Paste")
			(net "ANT3_IO_OUT")
		)
		(pad "42" smd rect
			(at -2.02489 -10.24991)
			(size 1.54991 0.24994)
			(layers "F.Cu" "F.Mask" "F.Paste")
			(net "EXT_GPIO_1")
		)
		(pad "43" smd rect
			(at 2.02489 -10.75004)
			(size 1.54991 0.24994)
			(layers "F.Cu" "F.Mask" "F.Paste")
			(net "ANT3_IO_IN")
		)
		(pad "44" smd rect
			(at -2.02489 -10.75004)
			(size 1.54991 0.24994)
			(layers "F.Cu" "F.Mask" "F.Paste")
			(net "EXT_GPIO_2")
		)
		(pad "45" smd rect
			(at 2.02489 -11.24991)
			(size 1.54991 0.24994)
			(layers "F.Cu" "F.Mask" "F.Paste")
			(net "ANT4_IO_OUT")
		)
		(pad "46" smd rect
			(at -2.02489 -11.24991)
			(size 1.54991 0.24994)
			(layers "F.Cu" "F.Mask" "F.Paste")
			(net "EXT_GPIO_3")
		)
		(pad "47" smd rect
			(at 2.02489 -11.75004)
			(size 1.54991 0.24994)
			(layers "F.Cu" "F.Mask" "F.Paste")
			(net "ANT4_IO_IN")
		)
		(pad "48" smd rect
			(at -2.02489 -11.75004)
			(size 1.54991 0.24994)
			(layers "F.Cu" "F.Mask" "F.Paste")
			(net "EXT_GPIO_4")
		)
		(pad "49" smd rect
			(at 2.02489 -12.24991)
			(size 1.54991 0.24994)
			(layers "F.Cu" "F.Mask" "F.Paste")
			(net "GND")
		)
		(pad "50" smd rect
			(at -2.02489 -12.24991)
			(size 1.54991 0.24994)
			(layers "F.Cu" "F.Mask" "F.Paste")
			(net "GND")
		)
		(pad "51" smd rect
			(at 2.02489 -12.75004)
			(size 1.54991 0.24994)
			(layers "F.Cu" "F.Mask" "F.Paste")
		)
		(pad "52" smd rect
			(at -2.02489 -12.75004)
			(size 1.54991 0.24994)
			(layers "F.Cu" "F.Mask" "F.Paste")
		)
		(pad "53" smd rect
			(at 2.02489 -13.24991)
			(size 1.54991 0.24994)
			(layers "F.Cu" "F.Mask" "F.Paste")
		)
		(pad "54" smd rect
			(at -2.02489 -13.24991)
			(size 1.54991 0.24994)
			(layers "F.Cu" "F.Mask" "F.Paste")
		)
		(pad "55" smd rect
			(at 2.02489 -13.75003)
			(size 1.54991 0.24994)
			(layers "F.Cu" "F.Mask" "F.Paste")
		)
		(pad "56" smd rect
			(at -2.02489 -13.75003)
			(size 1.54991 0.24994)
			(layers "F.Cu" "F.Mask" "F.Paste")
		)
		(pad "57" smd rect
			(at 2.02489 -14.24991)
			(size 1.54991 0.24994)
			(layers "F.Cu" "F.Mask" "F.Paste")
		)
		(pad "58" smd rect
			(at -2.02489 -14.24991)
			(size 1.54991 0.24994)
			(layers "F.Cu" "F.Mask" "F.Paste")
		)
		(pad "59" smd rect
			(at 2.02489 -14.75003)
			(size 1.54991 0.24994)
			(layers "F.Cu" "F.Mask" "F.Paste")
			(net "GND")
		)
		(pad "60" smd rect
			(at -2.02489 -14.75003)
			(size 1.54991 0.24994)
			(layers "F.Cu" "F.Mask" "F.Paste")
			(net "GND")
		)
		(pad "61" smd rect
			(at 2.02489 -15.2499)
			(size 1.54991 0.24994)
			(layers "F.Cu" "F.Mask" "F.Paste")
		)
		(pad "62" smd rect
			(at -2.02489 -15.2499)
			(size 1.54991 0.24994)
			(layers "F.Cu" "F.Mask" "F.Paste")
		)
		(pad "63" smd rect
			(at 2.02489 -15.75003)
			(size 1.54991 0.24994)
			(layers "F.Cu" "F.Mask" "F.Paste")
		)
		(pad "64" smd rect
			(at -2.02489 -15.75003)
			(size 1.54991 0.24994)
			(layers "F.Cu" "F.Mask" "F.Paste")
		)
		(pad "65" smd rect
			(at 2.02489 -16.2499)
			(size 1.54991 0.24994)
			(layers "F.Cu" "F.Mask" "F.Paste")
		)
		(pad "66" smd rect
			(at -2.02489 -16.2499)
			(size 1.54991 0.24994)
			(layers "F.Cu" "F.Mask" "F.Paste")
		)
		(pad "67" smd rect
			(at 2.02489 -16.75003)
			(size 1.54991 0.24994)
			(layers "F.Cu" "F.Mask" "F.Paste")
		)
		(pad "68" smd rect
			(at -2.02489 -16.75003)
			(size 1.54991 0.24994)
			(layers "F.Cu" "F.Mask" "F.Paste")
		)
		(pad "69" smd rect
			(at 2.02489 -17.2499)
			(size 1.54991 0.24994)
			(layers "F.Cu" "F.Mask" "F.Paste")
			(net "GND")
		)
		(pad "70" smd rect
			(at -2.02489 -17.2499)
			(size 1.54991 0.24994)
			(layers "F.Cu" "F.Mask" "F.Paste")
			(net "GND")
		)
		(pad "71" smd rect
			(at 2.02489 -17.75003)
			(size 1.54991 0.24994)
			(layers "F.Cu" "F.Mask" "F.Paste")
		)
		(pad "72" smd rect
			(at -2.02489 -17.75003)
			(size 1.54991 0.24994)
			(layers "F.Cu" "F.Mask" "F.Paste")
		)
		(pad "73" smd rect
			(at 2.02489 -18.2499)
			(size 1.54991 0.24994)
			(layers "F.Cu" "F.Mask" "F.Paste")
		)
		(pad "74" smd rect
			(at -2.02489 -18.2499)
			(size 1.54991 0.24994)
			(layers "F.Cu" "F.Mask" "F.Paste")
		)
		(pad "75" smd rect
			(at 2.02489 -18.75002)
			(size 1.54991 0.24994)
			(layers "F.Cu" "F.Mask" "F.Paste")
		)
		(pad "76" smd rect
			(at -2.02489 -18.75002)
			(size 1.54991 0.24994)
			(layers "F.Cu" "F.Mask" "F.Paste")
		)
		(pad "77" smd rect
			(at 2.02489 -19.2499)
			(size 1.54991 0.24994)
			(layers "F.Cu" "F.Mask" "F.Paste")
			(net "FPGA_TCK")
		)
		(pad "78" smd rect
			(at -2.02489 -19.2499)
			(size 1.54991 0.24994)
			(layers "F.Cu" "F.Mask" "F.Paste")
			(net "FPGA_TDI")
		)
		(pad "79" smd rect
			(at 2.02489 -19.75002)
			(size 1.54991 0.24994)
			(layers "F.Cu" "F.Mask" "F.Paste")
			(net "FPGA_TDO")
		)
		(pad "80" smd rect
			(at -2.02489 -19.75002)
			(size 1.54991 0.24994)
			(layers "F.Cu" "F.Mask" "F.Paste")
			(net "FPGA_TMS")
		)
		(pad "81" smd rect
			(at 0.01136 1.17626)
			(size 1.70002 1.35001)
			(layers "F.Cu" "F.Mask" "F.Paste")
		)
		(pad "82" thru_hole circle
			(at 0 0)
			(size 0.55016 0.55016)
			(drill 0.55016)
			(layers "*.Cu" "*.Mask")
			(remove_unused_layers no)
			(thermal_bridge_angle 90)
		)
		(pad "83" thru_hole circle
			(at 0 -19.99996)
			(size 0.55016 0.55016)
			(drill 0.55016)
			(layers "*.Cu" "*.Mask")
			(remove_unused_layers no)
			(thermal_bridge_angle 90)
		)
		(pad "84" smd rect
			(at 0.01136 -21.17374)
			(size 1.70002 1.35001)
			(layers "F.Cu" "F.Mask" "F.Paste")
		)
	)
	(footprint "Vault:AMPH-901-143-6RFX_V"
		(layer "F.Cu")
		(at 60.9761 135.5786 180)
		(property "Reference" "AN4"
			(at -5.817355 2.786 90)
			(unlocked yes)
			(layer "F.SilkS")
			(effects
				(font
					(size 0.762 0.762)
					(thickness 0.2286)
				)
				(justify left bottom)
			)
		)
		(property "Value" "901-143-6RFX"
			(at 4.6101 -12.21359 0)
			(unlocked yes)
			(layer "F.SilkS")
			(hide yes)
			(effects
				(font
					(size 1.524 1.524)
					(thickness 0.254)
				)
				(justify left bottom)
			)
		)
		(sheetname "USER_IO")
		(sheetfile "USER_IO.kicad_sch")
		(duplicate_pad_numbers_are_jumpers no)
		(fp_line
			(start 3.5 -1.38)
			(end 3.5 1.38)
			(stroke
				(width 0.2)
				(type solid)
			)
			(layer "F.SilkS")
		)
		(fp_line
			(start 1.38 3.5)
			(end -1.38 3.5)
			(stroke
				(width 0.2)
				(type solid)
			)
			(layer "F.SilkS")
		)
		(fp_line
			(start 1.38 -3.5)
			(end -1.38 -3.5)
			(stroke
				(width 0.2)
				(type solid)
			)
			(layer "F.SilkS")
		)
		(fp_line
			(start -3.5 -1.38)
			(end -3.5 1.38)
			(stroke
				(width 0.2)
				(type solid)
			)
			(layer "F.SilkS")
		)
		(pad "1" thru_hole rect
			(at 0 0 180)
			(size 2 2)
			(drill 1.5)
			(layers "*.Cu" "*.Mask")
			(remove_unused_layers no)
			(net "NetAN4_1")
		)
		(pad "2" thru_hole circle
			(at -2.54 -2.54 180)
			(size 2.2 2.2)
			(drill 1.7)
			(layers "*.Cu" "*.Mask")
			(remove_unused_layers no)
			(net "GND")
			(thermal_bridge_angle 90)
		)
		(pad "3" thru_hole circle
			(at -2.54 2.54 180)
			(size 2.2 2.2)
			(drill 1.7)
			(layers "*.Cu" "*.Mask")
			(remove_unused_layers no)
			(net "GND")
			(thermal_bridge_angle 90)
		)
		(pad "4" thru_hole circle
			(at 2.54 2.54 180)
			(size 2.2 2.2)
			(drill 1.7)
			(layers "*.Cu" "*.Mask")
			(remove_unused_layers no)
			(net "GND")
			(thermal_bridge_angle 90)
		)
		(pad "5" thru_hole circle
			(at 2.54 -2.54 180)
			(size 2.2 2.2)
			(drill 1.7)
			(layers "*.Cu" "*.Mask")
			(remove_unused_layers no)
			(net "GND")
			(thermal_bridge_angle 90)
		)
	)
	(footprint "Vault:FP-MK212BG-MFG"
		(layer "F.Cu")
		(at 94.3761 74.4286 -90)
		(property "Reference" "C58"
			(at 4.4 -0.843345 90)
			(unlocked yes)
			(layer "F.SilkS")
			(effects
				(font
					(size 0.762 0.762)
					(thickness 0.2286)
				)
				(justify left bottom)
			)
		)
		(property "Value" "10uF"
			(at 5.32679 1.5875 0)
			(unlocked yes)
			(layer "F.SilkS")
			(hide yes)
			(effects
				(font
					(size 1.524 1.524)
					(thickness 0.254)
				)
				(justify left bottom)
			)
		)
		(sheetname "GPS_IMU_SENSORS")
		(sheetfile "GPS_IMU_SENSORS.kicad_sch")
		(duplicate_pad_numbers_are_jumpers no)
		(fp_line
			(start 0.125 0.725)
			(end -0.125 0.725)
			(stroke
				(width 0.2)
				(type solid)
			)
			(layer "F.SilkS")
		)
		(fp_line
			(start 0.125 -0.725)
			(end -0.125 -0.725)
			(stroke
				(width 0.2)
				(type solid)
			)
			(layer "F.SilkS")
		)
		(fp_line
			(start -1.6 0.825)
			(end -1.6 -0.825)
			(stroke
				(width 0.2)
				(type solid)
			)
			(layer "F.CrtYd")
		)
		(fp_line
			(start 1.6 0.825)
			(end -1.6 0.825)
			(stroke
				(width 0.2)
				(type solid)
			)
			(layer "F.CrtYd")
		)
		(fp_line
			(start 1.6 0.825)
			(end 1.6 -0.825)
			(stroke
				(width 0.2)
				(type solid)
			)
			(layer "F.CrtYd")
		)
		(fp_line
			(start 1.6 -0.825)
			(end -1.6 -0.825)
			(stroke
				(width 0.2)
				(type solid)
			)
			(layer "F.CrtYd")
		)
		(fp_line
			(start -1.6 0.825)
			(end -1.6 -0.825)
			(stroke
				(width 0.2)
				(type solid)
			)
			(layer "F.Fab")
		)
		(fp_line
			(start 1.6 0.825)
			(end -1.6 0.825)
			(stroke
				(width 0.2)
				(type solid)
			)
			(layer "F.Fab")
		)
		(fp_line
			(start 1.6 0.825)
			(end 1.6 -0.825)
			(stroke
				(width 0.2)
				(type solid)
			)
			(layer "F.Fab")
		)
		(fp_line
			(start 0 0.5)
			(end 0 -0.5)
			(stroke
				(width 0.1)
				(type solid)
			)
			(layer "F.Fab")
		)
		(fp_line
			(start 0.5 0)
			(end -0.5 0)
			(stroke
				(width 0.1)
				(type solid)
			)
			(layer "F.Fab")
		)
		(fp_line
			(start 1.6 -0.825)
			(end -1.6 -0.825)
			(stroke
				(width 0.2)
				(type solid)
			)
			(layer "F.Fab")
		)
		(fp_text user "${REFERENCE}"
			(at -0.00001 0.09602 270)
			(unlocked yes)
			(layer "F.Fab")
			(effects
				(font
					(face "Arial")
					(size 0.63 0.63)
					(thickness 0.1)
				)
				(justify left bottom)
			)
		)
		(pad "1" smd rect
			(at -1 0 270)
			(size 1 1.25)
			(layers "F.Cu" "F.Mask" "F.Paste")
			(net "+3.3V")
			(solder_mask_margin 0)
			(solder_paste_margin 0)
		)
		(pad "2" smd rect
			(at 1 0 270)
			(size 1 1.25)
			(layers "F.Cu" "F.Mask" "F.Paste")
			(net "GND")
			(solder_mask_margin 0)
			(solder_paste_margin 0)
		)
	)
	(footprint "Vault:TECO-1909763-1_V"
		(layer "F.Cu")
		(at 74.3761 95.1162 -90)
		(property "Reference" "J1"
			(at -2.723079 1.271395 0)
			(unlocked yes)
			(layer "F.SilkS")
			(effects
				(font
					(size 0.762 0.762)
					(thickness 0.2286)
				)
			)
		)
		(property "Value" "1909763-1"
			(at 4.608085 3.749802 270)
			(unlocked yes)
			(layer "F.SilkS")
			(hide yes)
			(effects
				(font
					(size 1.524 1.524)
					(thickness 0.254)
				)
			)
		)
		(sheetname "USER_IO")
		(sheetfile "USER_IO.kicad_sch")
		(duplicate_pad_numbers_are_jumpers no)
		(fp_line
			(start 0.55 -1.3)
			(end -0.55 -1.3)
			(stroke
				(width 0.2)
				(type solid)
			)
			(layer "F.SilkS")
		)
		(fp_circle
			(center -1.778 1.65)
			(end -1.903 1.65)
			(stroke
				(width 0.25)
				(type solid)
			)
			(fill no)
			(layer "F.SilkS")
		)
		(pad "1" smd rect
			(at -1.475 0 270)
			(size 1.05 2.2)
			(layers "F.Cu" "F.Mask" "F.Paste")
			(net "GND")
		)
		(pad "2" smd rect
			(at 0 1.525 270)
			(size 1 1.05)
			(layers "F.Cu" "F.Mask" "F.Paste")
			(net "NetAN1_1")
		)
		(pad "3" smd rect
			(at 1.475 0 270)
			(size 1.05 2.2)
			(layers "F.Cu" "F.Mask" "F.Paste")
			(net "GND")
		)
	)
	(footprint "Capacitors:CAPC1608X10N"
		(layer "F.Cu")
		(at 202.4261 94.2162 -90)
		(property "Reference" "C3"
			(at -3.16 0.509345 270)
			(unlocked yes)
			(layer "F.SilkS")
			(effects
				(font
					(size 0.762 0.762)
					(thickness 0.2286)
				)
				(justify left bottom)
			)
		)
		(property "Value" "CAP_0603_0.01UF_50V"
			(at 0.91019 -8.8365 0)
			(unlocked yes)
			(layer "F.SilkS")
			(hide yes)
			(effects
				(font
					(size 1.524 1.524)
					(thickness 0.254)
				)
				(justify left bottom)
			)
		)
		(sheetname "POWER")
		(sheetfile "POWER.kicad_sch")
		(duplicate_pad_numbers_are_jumpers no)
		(fp_line
			(start 0.635 0.7112)
			(end -0.635 0.7112)
			(stroke
				(width 0.1524)
				(type solid)
			)
			(layer "F.SilkS")
		)
		(fp_line
			(start 0.635 -0.7112)
			(end -0.635 -0.7112)
			(stroke
				(width 0.1524)
				(type solid)
			)
			(layer "F.SilkS")
		)
		(pad "1" smd rect
			(at -0.8 0)
			(size 0.95 1)
			(layers "F.Cu" "F.Mask" "F.Paste")
			(net "NetC3_1")
		)
		(pad "2" smd rect
			(at 0.8 0)
			(size 0.95 1)
			(layers "F.Cu" "F.Mask" "F.Paste")
			(net "NetC3_2")
		)
	)
	(footprint "Vault:AMPH-901-143-6RFX_V"
		(layer "F.Cu")
		(at 60.9761 95.0786 180)
		(property "Reference" "AN1"
			(at -5.993345 2.7124 90)
			(unlocked yes)
			(layer "F.SilkS")
			(effects
				(font
					(size 0.762 0.762)
					(thickness 0.2286)
				)
				(justify left bottom)
			)
		)
		(property "Value" "901-143-6RFX"
			(at 4.6101 -12.21359 0)
			(unlocked yes)
			(layer "F.SilkS")
			(hide yes)
			(effects
				(font
					(size 1.524 1.524)
					(thickness 0.254)
				)
				(justify left bottom)
			)
		)
		(sheetname "USER_IO")
		(sheetfile "USER_IO.kicad_sch")
		(duplicate_pad_numbers_are_jumpers no)
		(fp_line
			(start 3.5 -1.38)
			(end 3.5 1.38)
			(stroke
				(width 0.2)
				(type solid)
			)
			(layer "F.SilkS")
		)
		(fp_line
			(start 1.38 3.5)
			(end -1.38 3.5)
			(stroke
				(width 0.2)
				(type solid)
			)
			(layer "F.SilkS")
		)
		(fp_line
			(start 1.38 -3.5)
			(end -1.38 -3.5)
			(stroke
				(width 0.2)
				(type solid)
			)
			(layer "F.SilkS")
		)
		(fp_line
			(start -3.5 -1.38)
			(end -3.5 1.38)
			(stroke
				(width 0.2)
				(type solid)
			)
			(layer "F.SilkS")
		)
		(pad "1" thru_hole rect
			(at 0 0 180)
			(size 2 2)
			(drill 1.5)
			(layers "*.Cu" "*.Mask")
			(remove_unused_layers no)
			(net "NetAN1_1")
		)
		(pad "2" thru_hole circle
			(at -2.54 -2.54 180)
			(size 2.2 2.2)
			(drill 1.7)
			(layers "*.Cu" "*.Mask")
			(remove_unused_layers no)
			(net "GND")
			(thermal_bridge_angle 90)
		)
		(pad "3" thru_hole circle
			(at -2.54 2.54 180)
			(size 2.2 2.2)
			(drill 1.7)
			(layers "*.Cu" "*.Mask")
			(remove_unused_layers no)
			(net "GND")
			(thermal_bridge_angle 90)
		)
		(pad "4" thru_hole circle
			(at 2.54 2.54 180)
			(size 2.2 2.2)
			(drill 1.7)
			(layers "*.Cu" "*.Mask")
			(remove_unused_layers no)
			(net "GND")
			(thermal_bridge_angle 90)
		)
		(pad "5" thru_hole circle
			(at 2.54 -2.54 180)
			(size 2.2 2.2)
			(drill 1.7)
			(layers "*.Cu" "*.Mask")
			(remove_unused_layers no)
			(net "GND")
			(thermal_bridge_angle 90)
		)
	)
	(footprint "Vault:RESC3116X65X50ML20T20"
		(layer "F.Cu")
		(at 149.9261 86.8162 180)
		(property "Reference" "R46"
			(at 1.5714 2.173079 0)
			(unlocked yes)
			(layer "F.SilkS")
			(effects
				(font
					(size 0.762 0.762)
					(thickness 0.2286)
				)
			)
		)
		(property "Value" "DNI_0_5%_1206"
			(at 7.29942 3.318002 180)
			(unlocked yes)
			(layer "F.SilkS")
			(hide yes)
			(effects
				(font
					(size 1.524 1.524)
					(thickness 0.254)
				)
			)
		)
		(sheetname "MAC")
		(sheetfile "MAC.kicad_sch")
		(duplicate_pad_numbers_are_jumpers no)
		(fp_line
			(start 0.35 0.85)
			(end -0.35 0.85)
			(stroke
				(width 0.2)
				(type solid)
			)
			(layer "F.SilkS")
		)
		(fp_line
			(start 0.35 -0.85)
			(end -0.35 -0.85)
			(stroke
				(width 0.2)
				(type solid)
			)
			(layer "F.SilkS")
		)
		(pad "1" smd rect
			(at -1.475 0 270)
			(size 1.9 1.45)
			(layers "F.Cu" "F.Mask" "F.Paste")
			(net "MAC_VCC")
		)
		(pad "2" smd rect
			(at 1.475 0 270)
			(size 1.9 1.45)
			(layers "F.Cu" "F.Mask" "F.Paste")
			(net "+12V")
		)
	)
	(footprint "Vault:CAPC1608X87X45ML20T05"
		(layer "F.Cu")
		(at 201.5087 84.9372 -90)
		(property "Reference" "C21"
			(at -4.371 0.538345 270)
			(unlocked yes)
			(layer "F.SilkS")
			(effects
				(font
					(size 0.762 0.762)
					(thickness 0.2286)
				)
				(justify left bottom)
			)
		)
		(property "Value" "0.1uF"
			(at 7.13319 -20.1395 0)
			(unlocked yes)
			(layer "F.SilkS")
			(hide yes)
			(effects
				(font
					(size 1.524 1.524)
					(thickness 0.254)
				)
				(justify left bottom)
			)
		)
		(sheetname "POWER")
		(sheetfile "POWER.kicad_sch")
		(duplicate_pad_numbers_are_jumpers no)
		(pad "1" smd rect
			(at -0.7 0)
			(size 1.1 1.05)
			(layers "F.Cu" "F.Mask" "F.Paste")
			(net "GND")
		)
		(pad "2" smd rect
			(at 0.7 0)
			(size 1.1 1.05)
			(layers "F.Cu" "F.Mask" "F.Paste")
			(net "NetC21_2")
		)
	)
	(footprint "Vault:RESC1608X55X30NL15T15"
		(layer "F.Cu")
		(at 84.1261 139.6162 -90)
		(property "Reference" "R31"
			(at 2.771395 -0.026921 90)
			(unlocked yes)
			(layer "F.SilkS")
			(effects
				(font
					(size 0.762 0.762)
					(thickness 0.2286)
				)
			)
		)
		(property "Value" "4.7K"
			(at 1.63744 2.352802 270)
			(unlocked yes)
			(layer "F.SilkS")
			(hide yes)
			(effects
				(font
					(size 1.524 1.524)
					(thickness 0.254)
				)
			)
		)
		(sheetname "USER_IO")
		(sheetfile "USER_IO.kicad_sch")
		(duplicate_pad_numbers_are_jumpers no)
		(pad "1" smd rect
			(at -0.75 0)
			(size 0.95 0.95)
			(layers "F.Cu" "F.Mask" "F.Paste")
			(net "ANT4_IO_OUT")
		)
		(pad "2" smd rect
			(at 0.75 0)
			(size 0.95 0.95)
			(layers "F.Cu" "F.Mask" "F.Paste")
			(net "+3.3V")
		)
	)
	(footprint "Vault:RESC1608X55X25LL10T15"
		(layer "F.Cu")
		(at 130.3761 87.3286)
		(property "Reference" "R11"
			(at -1.821395 0.014521 0)
			(unlocked yes)
			(layer "F.SilkS")
			(effects
				(font
					(size 0.762 0.762)
					(thickness 0.2286)
				)
			)
		)
		(property "Value" "4.7K"
			(at -2.657602 2.60264 270)
			(unlocked yes)
			(layer "F.SilkS")
			(hide yes)
			(effects
				(font
					(size 1.524 1.524)
					(thickness 0.254)
				)
			)
		)
		(sheetname "MAC")
		(sheetfile "MAC.kicad_sch")
		(duplicate_pad_numbers_are_jumpers no)
		(pad "1" smd rect
			(at -0.65 0 90)
			(size 0.8 0.6)
			(layers "F.Cu" "F.Mask" "F.Paste")
			(net "GND")
		)
		(pad "2" smd rect
			(at 0.65 0 90)
			(size 0.8 0.6)
			(layers "F.Cu" "F.Mask" "F.Paste")
			(net "FPGA_MAC_PPS_IN0-")
		)
	)
	(footprint "SamacSys:155124M173200"
		(layer "F.Cu")
		(at 58.4511 82.6662 90)
		(property "Reference" "D14"
			(at -4.7 -0.231655 90)
			(unlocked yes)
			(layer "F.SilkS")
			(effects
				(font
					(size 0.762 0.762)
					(thickness 0.2286)
				)
				(justify left bottom)
			)
		)
		(property "Value" "155124M173200"
			(at -4.13639 -0.5715 0)
			(unlocked yes)
			(layer "F.SilkS")
			(hide yes)
			(effects
				(font
					(size 1.524 1.524)
					(thickness 0.254)
				)
				(justify left bottom)
			)
		)
		(sheetname "USER_IO_STATUS")
		(sheetfile "USER_IO_STATUS.kicad_sch")
		(duplicate_pad_numbers_are_jumpers no)
		(fp_line
			(start -0.8 0.5)
			(end 0.8 0.5)
			(stroke
				(width 0.1)
				(type solid)
			)
			(layer "F.SilkS")
		)
		(fp_arc
			(start -2 -0.1)
			(mid -1.95 -0.05)
			(end -2 0)
			(stroke
				(width 0.1)
				(type solid)
			)
			(layer "F.SilkS")
		)
		(fp_arc
			(start -2 0)
			(mid -2.05 -0.05)
			(end -2 -0.1)
			(stroke
				(width 0.1)
				(type solid)
			)
			(layer "F.SilkS")
		)
		(pad "1" smd rect
			(at -1.4 0 180)
			(size 0.9 0.6)
			(layers "F.Cu" "F.Mask" "F.Paste")
			(net "+3.3V")
		)
		(pad "2" smd rect
			(at -0.45 -0.325 90)
			(size 0.6 0.55)
			(layers "F.Cu" "F.Mask" "F.Paste")
			(net "NetD14_2")
		)
		(pad "3" smd rect
			(at 0.45 -0.325 90)
			(size 0.6 0.55)
			(layers "F.Cu" "F.Mask" "F.Paste")
			(net "NetD14_3")
		)
		(pad "4" smd rect
			(at 1.4 0 180)
			(size 0.9 0.6)
			(layers "F.Cu" "F.Mask" "F.Paste")
			(net "NetD14_4")
		)
	)
	(footprint "Capacitors:CAPC2012X14N"
		(layer "F.Cu")
		(at 221.3637 88.7662)
		(property "Reference" "C7"
			(at 3 0.393345 0)
			(unlocked yes)
			(layer "F.SilkS")
			(effects
				(font
					(size 0.762 0.762)
					(thickness 0.2286)
				)
				(justify left bottom)
			)
		)
		(property "Value" "CAP_0805_10UF_25V"
			(at -4.8911 19.63119 0)
			(unlocked yes)
			(layer "F.SilkS")
			(hide yes)
			(effects
				(font
					(size 1.524 1.524)
					(thickness 0.254)
				)
				(justify left bottom)
			)
		)
		(sheetname "POWER")
		(sheetfile "POWER.kicad_sch")
		(duplicate_pad_numbers_are_jumpers no)
		(fp_line
			(start -0.762 -0.9652)
			(end 0.762 -0.9652)
			(stroke
				(width 0.1524)
				(type solid)
			)
			(layer "F.SilkS")
		)
		(fp_line
			(start -0.762 0.9652)
			(end 0.762 0.9652)
			(stroke
				(width 0.1524)
				(type solid)
			)
			(layer "F.SilkS")
		)
		(pad "1" smd rect
			(at -0.9 0 90)
			(size 1.45 1.15)
			(layers "F.Cu" "F.Mask" "F.Paste")
			(net "+3.3V")
		)
		(pad "2" smd rect
			(at 0.9 0 90)
			(size 1.45 1.15)
			(layers "F.Cu" "F.Mask" "F.Paste")
			(net "GND")
		)
	)
	(footprint "Vault:FP-LTST-C191TBKT-MFG"
		(layer "F.Cu")
		(at 73.3761 52.1162 90)
		(property "Reference" "D10"
			(at -6.5214 0.026921 90)
			(unlocked yes)
			(layer "F.SilkS")
			(effects
				(font
					(size 0.762 0.762)
					(thickness 0.2286)
				)
			)
		)
		(property "Value" "BLUE"
			(at 1.307195 2.479802 90)
			(unlocked yes)
			(layer "F.SilkS")
			(hide yes)
			(effects
				(font
					(size 1.524 1.524)
					(thickness 0.254)
				)
			)
		)
		(sheetname "USER_IO_STATUS")
		(sheetfile "USER_IO_STATUS.kicad_sch")
		(duplicate_pad_numbers_are_jumpers no)
		(fp_line
			(start -0.85 -0.8)
			(end 0.85 -0.8)
			(stroke
				(width 0.2)
				(type solid)
			)
			(layer "F.SilkS")
		)
		(fp_line
			(start -0.85 0.8)
			(end 0.85 0.8)
			(stroke
				(width 0.2)
				(type solid)
			)
			(layer "F.SilkS")
		)
		(fp_circle
			(center -1.75 0)
			(end -1.625 0)
			(stroke
				(width 0.25)
				(type solid)
			)
			(fill no)
			(layer "F.SilkS")
		)
		(fp_line
			(start 1.25 -0.55)
			(end 1.25 0.55)
			(stroke
				(width 0.2)
				(type solid)
			)
			(layer "F.CrtYd")
		)
		(fp_line
			(start -1.25 -0.55)
			(end 1.25 -0.55)
			(stroke
				(width 0.2)
				(type solid)
			)
			(layer "F.CrtYd")
		)
		(fp_line
			(start -1.25 -0.55)
			(end -1.25 0.55)
			(stroke
				(width 0.2)
				(type solid)
			)
			(layer "F.CrtYd")
		)
		(fp_line
			(start -1.25 0.55)
			(end 1.25 0.55)
			(stroke
				(width 0.2)
				(type solid)
			)
			(layer "F.CrtYd")
		)
		(fp_line
			(start 1.25 -0.55)
			(end 1.25 0.55)
			(stroke
				(width 0.2)
				(type solid)
			)
			(layer "F.Fab")
		)
		(fp_line
			(start -1.25 -0.55)
			(end 1.25 -0.55)
			(stroke
				(width 0.2)
				(type solid)
			)
			(layer "F.Fab")
		)
		(fp_line
			(start -1.25 -0.55)
			(end -1.25 0.55)
			(stroke
				(width 0.2)
				(type solid)
			)
			(layer "F.Fab")
		)
		(fp_line
			(start 0 -0.5)
			(end 0 0.5)
			(stroke
				(width 0.1)
				(type solid)
			)
			(layer "F.Fab")
		)
		(fp_line
			(start -0.5 0)
			(end 0.5 0)
			(stroke
				(width 0.1)
				(type solid)
			)
			(layer "F.Fab")
		)
		(fp_line
			(start -1.25 0.55)
			(end 1.25 0.55)
			(stroke
				(width 0.2)
				(type solid)
			)
			(layer "F.Fab")
		)
		(pad "1" smd rect
			(at -0.75 0 90)
			(size 0.8 0.8)
			(layers "F.Cu" "F.Mask" "F.Paste")
			(net "NetD10_1")
			(solder_mask_margin 0)
			(solder_paste_margin 0)
		)
		(pad "2" smd rect
			(at 0.75 0 90)
			(size 0.8 0.8)
			(layers "F.Cu" "F.Mask" "F.Paste")
			(net "+3.3V")
			(solder_mask_margin 0)
			(solder_paste_margin 0)
		)
	)
	(footprint "Resistors:RESC1005X04N"
		(layer "F.Cu")
		(at 133.4761 145.5786 -90)
		(property "Reference" "R24"
			(at 1.35111 0.884735 90)
			(unlocked yes)
			(layer "F.SilkS")
			(effects
				(font
					(size 0.762 0.762)
					(thickness 0.2286)
				)
				(justify left bottom)
			)
		)
		(property "Value" "ERJ-2GE0R00X"
			(at 3.42519 0.2413 0)
			(unlocked yes)
			(layer "F.SilkS")
			(hide yes)
			(effects
				(font
					(size 1.524 1.524)
					(thickness 0.254)
				)
				(justify left bottom)
			)
		)
		(sheetname "PCIe_JTAG")
		(sheetfile "PCIe_JTAG.kicad_sch")
		(duplicate_pad_numbers_are_jumpers no)
		(pad "1" smd rect
			(at -0.425 0)
			(size 0.6 0.65)
			(layers "F.Cu" "F.Mask" "F.Paste")
			(net "PRSNT")
		)
		(pad "2" smd rect
			(at 0.425 0)
			(size 0.6 0.65)
			(layers "F.Cu" "F.Mask" "F.Paste")
			(net "NetP2_B31")
		)
	)
	(footprint "Vault:TECO-1909763-1_V"
		(layer "F.Cu")
		(at 74.3761 108.6162 -90)
		(property "Reference" "J2"
			(at -2.973079 1.271395 0)
			(unlocked yes)
			(layer "F.SilkS")
			(effects
				(font
					(size 0.762 0.762)
					(thickness 0.2286)
				)
			)
		)
		(property "Value" "1909763-1"
			(at 4.608085 3.749802 270)
			(unlocked yes)
			(layer "F.SilkS")
			(hide yes)
			(effects
				(font
					(size 1.524 1.524)
					(thickness 0.254)
				)
			)
		)
		(sheetname "USER_IO")
		(sheetfile "USER_IO.kicad_sch")
		(duplicate_pad_numbers_are_jumpers no)
		(fp_line
			(start 0.55 -1.3)
			(end -0.55 -1.3)
			(stroke
				(width 0.2)
				(type solid)
			)
			(layer "F.SilkS")
		)
		(fp_circle
			(center -1.778 1.65)
			(end -1.903 1.65)
			(stroke
				(width 0.25)
				(type solid)
			)
			(fill no)
			(layer "F.SilkS")
		)
		(pad "1" smd rect
			(at -1.475 0 270)
			(size 1.05 2.2)
			(layers "F.Cu" "F.Mask" "F.Paste")
			(net "GND")
		)
		(pad "2" smd rect
			(at 0 1.525 270)
			(size 1 1.05)
			(layers "F.Cu" "F.Mask" "F.Paste")
			(net "NetAN2_1")
		)
		(pad "3" smd rect
			(at 1.475 0 270)
			(size 1.05 2.2)
			(layers "F.Cu" "F.Mask" "F.Paste")
			(net "GND")
		)
	)
	(footprint "Vault:M08A_N"
		(layer "F.Cu")
		(at 136.5261 85.9636)
		(property "Reference" "U3"
			(at 2.028595 -2.820479 0)
			(unlocked yes)
			(layer "F.SilkS")
			(effects
				(font
					(size 0.762 0.762)
					(thickness 0.2286)
				)
			)
		)
		(property "Value" "DS90LV027AQMA"
			(at 6.38498 4.359402 0)
			(unlocked yes)
			(layer "F.SilkS")
			(hide yes)
			(effects
				(font
					(size 1.524 1.524)
					(thickness 0.254)
				)
			)
		)
		(sheetname "MAC")
		(sheetfile "MAC.kicad_sch")
		(duplicate_pad_numbers_are_jumpers no)
		(fp_line
			(start -0.9 -2.5)
			(end 0.9 -2.5)
			(stroke
				(width 0.2)
				(type solid)
			)
			(layer "F.SilkS")
		)
		(fp_line
			(start -0.9 2.5)
			(end -0.9 -2.5)
			(stroke
				(width 0.2)
				(type solid)
			)
			(layer "F.SilkS")
		)
		(fp_line
			(start -0.9 2.5)
			(end 0.9 2.5)
			(stroke
				(width 0.2)
				(type solid)
			)
			(layer "F.SilkS")
		)
		(fp_line
			(start 0.9 2.5)
			(end 0.9 -2.5)
			(stroke
				(width 0.2)
				(type solid)
			)
			(layer "F.SilkS")
		)
		(fp_circle
			(center -2.4 -2.755)
			(end -2.4 -2.88)
			(stroke
				(width 0.25)
				(type solid)
			)
			(fill no)
			(layer "F.SilkS")
		)
		(fp_circle
			(center -0.1 -1.7)
			(end -0.1 -1.9)
			(stroke
				(width 0.4)
				(type solid)
			)
			(fill no)
			(layer "F.SilkS")
		)
		(pad "1" smd oval
			(at -2.4 -1.905 90)
			(size 0.6 2.2)
			(layers "F.Cu" "F.Mask" "F.Paste")
			(net "+3.3V")
		)
		(pad "2" smd oval
			(at -2.4 -0.635 90)
			(size 0.6 2.2)
			(layers "F.Cu" "F.Mask" "F.Paste")
			(net "FPGA_MAC_PPS_IN1-")
		)
		(pad "3" smd oval
			(at -2.4 0.635 90)
			(size 0.6 2.2)
			(layers "F.Cu" "F.Mask" "F.Paste")
			(net "FPGA_MAC_PPS_IN0-")
		)
		(pad "4" smd oval
			(at -2.4 1.905 90)
			(size 0.6 2.2)
			(layers "F.Cu" "F.Mask" "F.Paste")
			(net "GND")
		)
		(pad "5" smd oval
			(at 2.4 1.905 90)
			(size 0.6 2.2)
			(layers "F.Cu" "F.Mask" "F.Paste")
			(net "MAC_PPS_IN0-")
		)
		(pad "6" smd oval
			(at 2.4 0.635 90)
			(size 0.6 2.2)
			(layers "F.Cu" "F.Mask" "F.Paste")
			(net "MAC_PPS_IN0+")
		)
		(pad "7" smd oval
			(at 2.4 -0.635 90)
			(size 0.6 2.2)
			(layers "F.Cu" "F.Mask" "F.Paste")
			(net "MAC_PPS_IN1+")
		)
		(pad "8" smd oval
			(at 2.4 -1.905 90)
			(size 0.6 2.2)
			(layers "F.Cu" "F.Mask" "F.Paste")
			(net "MAC_PPS_IN1-")
		)
	)
	(footprint "Vault:RESC1608X55X30NL15T15"
		(layer "F.Cu")
		(at 164.6261 88.5786 90)
		(property "Reference" "R27"
			(at 3.2286 0.026921 90)
			(unlocked yes)
			(layer "F.SilkS")
			(effects
				(font
					(size 0.762 0.762)
					(thickness 0.2286)
				)
			)
		)
		(property "Value" "4.7K"
			(at -3.114802 2.39944 0)
			(unlocked yes)
			(layer "F.SilkS")
			(hide yes)
			(effects
				(font
					(size 1.524 1.524)
					(thickness 0.254)
				)
			)
		)
		(sheetname "GPS_IMU_SENSORS")
		(sheetfile "GPS_IMU_SENSORS.kicad_sch")
		(duplicate_pad_numbers_are_jumpers no)
		(pad "1" smd rect
			(at -0.75 0 180)
			(size 0.95 0.95)
			(layers "F.Cu" "F.Mask" "F.Paste")
			(net "SCL")
		)
		(pad "2" smd rect
			(at 0.75 0 180)
			(size 0.95 0.95)
			(layers "F.Cu" "F.Mask" "F.Paste")
			(net "+3.3V")
		)
	)
	(footprint "Vault:RESC1608X55X25NL10T15"
		(layer "F.Cu")
		(at 123.3761 86.3286 -90)
		(property "Reference" "R13"
			(at -2.2838 -0.023069 270)
			(unlocked yes)
			(layer "F.SilkS")
			(effects
				(font
					(size 0.762 0.762)
					(thickness 0.2286)
				)
			)
		)
		(property "Value" "49.9R"
			(at -2.911602 3.21199 180)
			(unlocked yes)
			(layer "F.SilkS")
			(hide yes)
			(effects
				(font
					(size 1.524 1.524)
					(thickness 0.254)
				)
			)
		)
		(sheetname "MAC")
		(sheetfile "MAC.kicad_sch")
		(duplicate_pad_numbers_are_jumpers no)
		(pad "1" smd rect
			(at -0.7 0)
			(size 0.9 0.7)
			(layers "F.Cu" "F.Mask" "F.Paste")
			(net "NetR13_1")
		)
		(pad "2" smd rect
			(at 0.7 0)
			(size 0.9 0.7)
			(layers "F.Cu" "F.Mask" "F.Paste")
			(net "FPGA_MAC_PPS_OUT-")
		)
	)
	(footprint "SamacSys:155124M173200"
		(layer "F.Cu")
		(at 58.4511 141.8162 90)
		(property "Reference" "D18"
			(at -0.5714 1.701931 90)
			(unlocked yes)
			(layer "F.SilkS")
			(effects
				(font
					(size 0.762 0.762)
					(thickness 0.2286)
				)
			)
		)
		(property "Value" "155124M173200"
			(at 7.1725 2.632202 90)
			(unlocked yes)
			(layer "F.SilkS")
			(hide yes)
			(effects
				(font
					(size 1.524 1.524)
					(thickness 0.254)
				)
			)
		)
		(sheetname "USER_IO_STATUS")
		(sheetfile "USER_IO_STATUS.kicad_sch")
		(duplicate_pad_numbers_are_jumpers no)
		(fp_line
			(start -0.8 0.5)
			(end 0.8 0.5)
			(stroke
				(width 0.1)
				(type solid)
			)
			(layer "F.SilkS")
		)
		(fp_arc
			(start -2 -0.1)
			(mid -1.95 -0.05)
			(end -2 0)
			(stroke
				(width 0.1)
				(type solid)
			)
			(layer "F.SilkS")
		)
		(fp_arc
			(start -2 0)
			(mid -2.05 -0.05)
			(end -2 -0.1)
			(stroke
				(width 0.1)
				(type solid)
			)
			(layer "F.SilkS")
		)
		(pad "1" smd rect
			(at -1.4 0 180)
			(size 0.9 0.6)
			(layers "F.Cu" "F.Mask" "F.Paste")
			(net "+3.3V")
		)
		(pad "2" smd rect
			(at -0.45 -0.325 90)
			(size 0.6 0.55)
			(layers "F.Cu" "F.Mask" "F.Paste")
			(net "NetD18_2")
		)
		(pad "3" smd rect
			(at 0.45 -0.325 90)
			(size 0.6 0.55)
			(layers "F.Cu" "F.Mask" "F.Paste")
			(net "NetD18_3")
		)
		(pad "4" smd rect
			(at 1.4 0 180)
			(size 0.9 0.6)
			(layers "F.Cu" "F.Mask" "F.Paste")
			(net "NetD18_4")
		)
	)
	(footprint "Passives:DIOM1608X06N"
		(layer "F.Cu")
		(at 220.8261 86.7162 180)
		(property "Reference" "D4"
			(at -2 -0.393345 0)
			(unlocked yes)
			(layer "F.SilkS")
			(effects
				(font
					(size 0.762 0.762)
					(thickness 0.2286)
				)
				(justify left bottom)
			)
		)
		(property "Value" "RED"
			(at 18.2973 -9.43439 0)
			(unlocked yes)
			(layer "F.SilkS")
			(hide yes)
			(effects
				(font
					(size 1.524 1.524)
					(thickness 0.254)
				)
				(justify left bottom)
			)
		)
		(sheetname "POWER")
		(sheetfile "POWER.kicad_sch")
		(duplicate_pad_numbers_are_jumpers no)
		(fp_circle
			(center -1.275 -0.725)
			(end -1.275 -0.675)
			(stroke
				(width 0.1)
				(type solid)
			)
			(fill no)
			(layer "F.SilkS")
		)
		(pad "1" smd rect
			(at -0.725 0 270)
			(size 0.85 1)
			(layers "F.Cu" "F.Mask" "F.Paste")
			(net "NetD4_1")
		)
		(pad "2" smd rect
			(at 0.725 0 270)
			(size 0.85 1)
			(layers "F.Cu" "F.Mask" "F.Paste")
			(net "+3.3V")
		)
	)
	(footprint "Vault:RESC1608X55X25NL10T15"
		(layer "F.Cu")
		(at 77.5761 135.6162 180)
		(property "Reference" "R34"
			(at -0.2286 1.473079 0)
			(unlocked yes)
			(layer "F.SilkS")
			(effects
				(font
					(size 0.762 0.762)
					(thickness 0.2286)
				)
			)
		)
		(property "Value" "49.9R"
			(at -2.911602 3.21199 90)
			(unlocked yes)
			(layer "F.SilkS")
			(hide yes)
			(effects
				(font
					(size 1.524 1.524)
					(thickness 0.254)
				)
			)
		)
		(sheetname "USER_IO")
		(sheetfile "USER_IO.kicad_sch")
		(duplicate_pad_numbers_are_jumpers no)
		(pad "1" smd rect
			(at -0.7 0 270)
			(size 0.9 0.7)
			(layers "F.Cu" "F.Mask" "F.Paste")
			(net "NetR34_1")
		)
		(pad "2" smd rect
			(at 0.7 0 270)
			(size 0.9 0.7)
			(layers "F.Cu" "F.Mask" "F.Paste")
			(net "NetAN4_1")
		)
	)
	(footprint "Passives:SOT65P210X110-3N"
		(layer "F.Cu")
		(at 229.6761 137.6412 -90)
		(property "Reference" "D7"
			(at -1.831655 -1.65 0)
			(unlocked yes)
			(layer "F.SilkS")
			(effects
				(font
					(size 0.762 0.762)
					(thickness 0.2286)
				)
				(justify left bottom)
			)
		)
		(property "Value" "BAT54SW"
			(at 0.6448 -1.0501 0)
			(unlocked yes)
			(layer "F.SilkS")
			(hide yes)
			(effects
				(font
					(size 1.524 1.524)
					(thickness 0.254)
				)
				(justify left bottom)
			)
		)
		(sheetname "PCIe_JTAG")
		(sheetfile "PCIe_JTAG.kicad_sch")
		(duplicate_pad_numbers_are_jumpers no)
		(fp_line
			(start 0.675 1.1)
			(end -0.32499 1.1)
			(stroke
				(width 0.2)
				(type solid)
			)
			(layer "F.SilkS")
		)
		(fp_line
			(start 0.675 1.1)
			(end 0.675 0.65)
			(stroke
				(width 0.2)
				(type solid)
			)
			(layer "F.SilkS")
		)
		(fp_line
			(start 0.675 -0.65)
			(end 0.675 -1.1)
			(stroke
				(width 0.2)
				(type solid)
			)
			(layer "F.SilkS")
		)
		(fp_line
			(start 0.675 -1.1)
			(end -0.32499 -1.1)
			(stroke
				(width 0.2)
				(type solid)
			)
			(layer "F.SilkS")
		)
		(fp_circle
			(center -1.125 -1.45)
			(end -1.25 -1.45)
			(stroke
				(width 0.25)
				(type solid)
			)
			(fill no)
			(layer "F.SilkS")
		)
		(pad "1" smd rect
			(at -1.125 -0.65)
			(size 0.5 0.9)
			(layers "F.Cu" "F.Mask" "F.Paste")
			(net "GND")
		)
		(pad "2" smd rect
			(at -1.125 0.65)
			(size 0.5 0.9)
			(layers "F.Cu" "F.Mask" "F.Paste")
			(net "+3.3V")
		)
		(pad "3" smd rect
			(at 1.125 0)
			(size 0.5 0.9)
			(layers "F.Cu" "F.Mask" "F.Paste")
			(net "FPGA_TMS")
		)
	)
	(footprint "Vault:RESC1608X55X30NL15T15"
		(layer "F.Cu")
		(at 82.1261 98.8662 -90)
		(property "Reference" "R15"
			(at 2.7714 -0.026921 90)
			(unlocked yes)
			(layer "F.SilkS")
			(effects
				(font
					(size 0.762 0.762)
					(thickness 0.2286)
				)
			)
		)
		(property "Value" "4.7K"
			(at 2.835402 -4.98946 0)
			(unlocked yes)
			(layer "F.SilkS")
			(hide yes)
			(effects
				(font
					(size 1.524 1.524)
					(thickness 0.254)
				)
			)
		)
		(sheetname "USER_IO")
		(sheetfile "USER_IO.kicad_sch")
		(duplicate_pad_numbers_are_jumpers no)
		(pad "1" smd rect
			(at -0.75 0)
			(size 0.95 0.95)
			(layers "F.Cu" "F.Mask" "F.Paste")
			(net "ANT1_IO_IN")
		)
		(pad "2" smd rect
			(at 0.75 0)
			(size 0.95 0.95)
			(layers "F.Cu" "F.Mask" "F.Paste")
			(net "+3.3V")
		)
	)
	(footprint "Vault:RESC1608X55X30LL15T20"
		(layer "F.Cu")
		(at 179.6261 90.0786 180)
		(property "Reference" "R37"
			(at 2.2714 -0.026921 0)
			(unlocked yes)
			(layer "F.SilkS")
			(effects
				(font
					(size 0.762 0.762)
					(thickness 0.2286)
				)
			)
		)
		(property "Value" "10K"
			(at -2.657602 1.790085 90)
			(unlocked yes)
			(layer "F.SilkS")
			(hide yes)
			(effects
				(font
					(size 1.524 1.524)
					(thickness 0.254)
				)
			)
		)
		(sheetname "GPS_IMU_SENSORS")
		(sheetfile "GPS_IMU_SENSORS.kicad_sch")
		(duplicate_pad_numbers_are_jumpers no)
		(pad "1" smd rect
			(at -0.575 0 270)
			(size 0.85 0.75)
			(layers "F.Cu" "F.Mask" "F.Paste")
			(net "EXT_EEPROM_WP")
		)
		(pad "2" smd rect
			(at 0.575 0 270)
			(size 0.85 0.75)
			(layers "F.Cu" "F.Mask" "F.Paste")
			(net "+3.3V")
		)
	)
	(footprint "Vault:SMTC-TLE-104-01-X-DV"
		(layer "F.Cu")
		(at 84.36315 70.82861 90)
		(property "Reference" "J6"
			(at 5.258558 3.51695 0)
			(unlocked yes)
			(layer "F.SilkS")
			(effects
				(font
					(size 1.524 1.524)
					(thickness 0.254)
				)
			)
		)
		(property "Value" "GNSS Header"
			(at 6.765575 4.994402 90)
			(unlocked yes)
			(layer "F.SilkS")
			(hide yes)
			(effects
				(font
					(size 1.524 1.524)
					(thickness 0.254)
				)
			)
		)
		(sheetname "GPS_IMU_SENSORS")
		(sheetfile "GPS_IMU_SENSORS.kicad_sch")
		(duplicate_pad_numbers_are_jumpers no)
		(fp_line
			(start 4.065 -2)
			(end 4.065 2)
			(stroke
				(width 0.2)
				(type solid)
			)
			(layer "F.SilkS")
		)
		(fp_line
			(start 3.959 -2)
			(end 4.065 -2)
			(stroke
				(width 0.2)
				(type solid)
			)
			(layer "F.SilkS")
		)
		(fp_line
			(start -4.06499 -2)
			(end -3.95899 -2)
			(stroke
				(width 0.2)
				(type solid)
			)
			(layer "F.SilkS")
		)
		(fp_line
			(start -4.06499 -2)
			(end -4.06499 2)
			(stroke
				(width 0.2)
				(type solid)
			)
			(layer "F.SilkS")
		)
		(fp_line
			(start 3.959 2)
			(end 4.065 2)
			(stroke
				(width 0.2)
				(type solid)
			)
			(layer "F.SilkS")
		)
		(fp_line
			(start -4.06499 2)
			(end -3.95899 2)
			(stroke
				(width 0.2)
				(type solid)
			)
			(layer "F.SilkS")
		)
		(fp_circle
			(center -4.41299 -2.286)
			(end -4.28799 -2.286)
			(stroke
				(width 0.25)
				(type solid)
			)
			(fill no)
			(layer "F.SilkS")
		)
		(pad "1" smd rect
			(at -2.99999 -2.43205 90)
			(size 1.1176 1.6891)
			(layers "F.Cu" "F.Mask" "F.Paste")
			(net "+5.0V")
		)
		(pad "2" smd rect
			(at -2.99999 2.43205 90)
			(size 1.1176 1.6891)
			(layers "F.Cu" "F.Mask" "F.Paste")
			(net "+3.3V")
		)
		(pad "3" smd rect
			(at -0.99999 -2.43205 90)
			(size 1.1176 1.6891)
			(layers "F.Cu" "F.Mask" "F.Paste")
			(net "GPS1_TX")
		)
		(pad "4" smd rect
			(at -0.99999 2.43205 90)
			(size 1.1176 1.6891)
			(layers "F.Cu" "F.Mask" "F.Paste")
			(net "GPS1_RST")
		)
		(pad "5" smd rect
			(at 1 -2.43205 90)
			(size 1.1176 1.6891)
			(layers "F.Cu" "F.Mask" "F.Paste")
			(net "GPS1_RX")
		)
		(pad "6" smd rect
			(at 1 2.43205 90)
			(size 1.1176 1.6891)
			(layers "F.Cu" "F.Mask" "F.Paste")
			(net "GPS1_TP1")
		)
		(pad "7" smd rect
			(at 3 -2.43205 90)
			(size 1.1176 1.6891)
			(layers "F.Cu" "F.Mask" "F.Paste")
			(net "GPS1_TP2")
		)
		(pad "8" smd rect
			(at 3 2.43205 90)
			(size 1.1176 1.6891)
			(layers "F.Cu" "F.Mask" "F.Paste")
			(net "GND")
		)
	)
	(footprint "Vault:RESC1608X55X30NL15T15"
		(layer "F.Cu")
		(at 84.1261 98.8662 -90)
		(property "Reference" "R14"
			(at 2.7714 -0.026931 90)
			(unlocked yes)
			(layer "F.SilkS")
			(effects
				(font
					(size 0.762 0.762)
					(thickness 0.2286)
				)
			)
		)
		(property "Value" "4.7K"
			(at 2.835402 -4.73554 0)
			(unlocked yes)
			(layer "F.SilkS")
			(hide yes)
			(effects
				(font
					(size 1.524 1.524)
					(thickness 0.254)
				)
			)
		)
		(sheetname "USER_IO")
		(sheetfile "USER_IO.kicad_sch")
		(duplicate_pad_numbers_are_jumpers no)
		(pad "1" smd rect
			(at -0.75 0)
			(size 0.95 0.95)
			(layers "F.Cu" "F.Mask" "F.Paste")
			(net "ANT1_IO_OUT")
		)
		(pad "2" smd rect
			(at 0.75 0)
			(size 0.95 0.95)
			(layers "F.Cu" "F.Mask" "F.Paste")
			(net "+3.3V")
		)
	)
	(footprint "Vault:CAPC1608X87X45ML20T05"
		(layer "F.Cu")
		(at 130.8761 83.5786)
		(property "Reference" "C23"
			(at -2.1214 -0.135479 0)
			(unlocked yes)
			(layer "F.SilkS")
			(effects
				(font
					(size 0.762 0.762)
					(thickness 0.2286)
				)
			)
		)
		(property "Value" "0.1uF"
			(at 2.09443 2.657602 0)
			(unlocked yes)
			(layer "F.SilkS")
			(hide yes)
			(effects
				(font
					(size 1.524 1.524)
					(thickness 0.254)
				)
			)
		)
		(sheetname "MAC")
		(sheetfile "MAC.kicad_sch")
		(duplicate_pad_numbers_are_jumpers no)
		(pad "1" smd rect
			(at -0.7 0 90)
			(size 1.1 1.05)
			(layers "F.Cu" "F.Mask" "F.Paste")
			(net "GND")
		)
		(pad "2" smd rect
			(at 0.7 0 90)
			(size 1.1 1.05)
			(layers "F.Cu" "F.Mask" "F.Paste")
			(net "+3.3V")
		)
	)
	(footprint "Capacitors:CAPC2012X14N"
		(layer "F.Cu")
		(at 203.0595 116.3062 180)
		(property "Reference" "C6"
			(at 0.3334 -1.416655 180)
			(unlocked yes)
			(layer "F.SilkS")
			(effects
				(font
					(size 0.762 0.762)
					(thickness 0.2286)
				)
				(justify left bottom)
			)
		)
		(property "Value" "CAP_0805_10UF_25V"
			(at -3.8601 8.85681 0)
			(unlocked yes)
			(layer "F.SilkS")
			(hide yes)
			(effects
				(font
					(size 1.524 1.524)
					(thickness 0.254)
				)
				(justify left bottom)
			)
		)
		(sheetname "POWER")
		(sheetfile "POWER.kicad_sch")
		(duplicate_pad_numbers_are_jumpers no)
		(fp_line
			(start 0.762 0.9652)
			(end -0.762 0.9652)
			(stroke
				(width 0.1524)
				(type solid)
			)
			(layer "F.SilkS")
		)
		(fp_line
			(start 0.762 -0.9652)
			(end -0.762 -0.9652)
			(stroke
				(width 0.1524)
				(type solid)
			)
			(layer "F.SilkS")
		)
		(pad "1" smd rect
			(at -0.9 0 270)
			(size 1.45 1.15)
			(layers "F.Cu" "F.Mask" "F.Paste")
			(net "+12V")
		)
		(pad "2" smd rect
			(at 0.9 0 270)
			(size 1.45 1.15)
			(layers "F.Cu" "F.Mask" "F.Paste")
			(net "GND")
		)
	)
	(footprint "Vault:CAPC1608X87X45ML20T05"
		(layer "F.Cu")
		(at 80.3761 98.8662 -90)
		(property "Reference" "C26"
			(at 2.7714 -0.026931 90)
			(unlocked yes)
			(layer "F.SilkS")
			(effects
				(font
					(size 0.762 0.762)
					(thickness 0.2286)
				)
			)
		)
		(property "Value" "0.1uF"
			(at 2.09443 2.657602 270)
			(unlocked yes)
			(layer "F.SilkS")
			(hide yes)
			(effects
				(font
					(size 1.524 1.524)
					(thickness 0.254)
				)
			)
		)
		(sheetname "USER_IO")
		(sheetfile "USER_IO.kicad_sch")
		(duplicate_pad_numbers_are_jumpers no)
		(pad "1" smd rect
			(at -0.7 0)
			(size 1.1 1.05)
			(layers "F.Cu" "F.Mask" "F.Paste")
			(net "+3.3V")
		)
		(pad "2" smd rect
			(at 0.7 0)
			(size 1.1 1.05)
			(layers "F.Cu" "F.Mask" "F.Paste")
			(net "GND")
		)
	)
	(footprint "Vault:RESC1608X55X30NL15T15"
		(layer "F.Cu")
		(at 69.8761 55.6162 90)
		(property "Reference" "R35"
			(at -5.7714 0.026921 90)
			(unlocked yes)
			(layer "F.SilkS")
			(effects
				(font
					(size 0.762 0.762)
					(thickness 0.2286)
				)
			)
		)
		(property "Value" "200 OHM"
			(at -2.962402 4.81166 0)
			(unlocked yes)
			(layer "F.SilkS")
			(hide yes)
			(effects
				(font
					(size 1.524 1.524)
					(thickness 0.254)
				)
			)
		)
		(sheetname "USER_IO_STATUS")
		(sheetfile "USER_IO_STATUS.kicad_sch")
		(duplicate_pad_numbers_are_jumpers no)
		(pad "1" smd rect
			(at -0.675 0 180)
			(size 0.95 0.8)
			(layers "F.Cu" "F.Mask" "F.Paste")
			(net "LED1")
		)
		(pad "2" smd rect
			(at 0.675 0 180)
			(size 0.95 0.8)
			(layers "F.Cu" "F.Mask" "F.Paste")
			(net "NetD3_1")
		)
	)
	(footprint "Vault:CAPC1608X90X35NL10T15"
		(layer "F.Cu")
		(at 208.7745 109.1942)
		(property "Reference" "C20"
			(at -1.336 -0.346345 180)
			(unlocked yes)
			(layer "F.SilkS")
			(effects
				(font
					(size 0.762 0.762)
					(thickness 0.2286)
				)
				(justify left bottom)
			)
		)
		(property "Value" "0.033uF"
			(at 6.5525 3.91939 0)
			(unlocked yes)
			(layer "F.SilkS")
			(hide yes)
			(effects
				(font
					(size 1.524 1.524)
					(thickness 0.254)
				)
				(justify left bottom)
			)
		)
		(sheetname "POWER")
		(sheetfile "POWER.kicad_sch")
		(duplicate_pad_numbers_are_jumpers no)
		(pad "1" smd rect
			(at -0.675 0 90)
			(size 0.95 0.85)
			(layers "F.Cu" "F.Mask" "F.Paste")
			(net "NetC20_1")
		)
		(pad "2" smd rect
			(at 0.675 0 90)
			(size 0.95 0.85)
			(layers "F.Cu" "F.Mask" "F.Paste")
			(net "NetC20_2")
		)
	)
	(footprint "Vault:RESC1608X55X25NL10T15"
		(layer "F.Cu")
		(at 77.8761 108.6162 180)
		(property "Reference" "R33"
			(at -0.2286 1.473069 0)
			(unlocked yes)
			(layer "F.SilkS")
			(effects
				(font
					(size 0.762 0.762)
					(thickness 0.2286)
				)
			)
		)
		(property "Value" "49.9R"
			(at -2.911602 3.21199 90)
			(unlocked yes)
			(layer "F.SilkS")
			(hide yes)
			(effects
				(font
					(size 1.524 1.524)
					(thickness 0.254)
				)
			)
		)
		(sheetname "USER_IO")
		(sheetfile "USER_IO.kicad_sch")
		(duplicate_pad_numbers_are_jumpers no)
		(pad "1" smd rect
			(at -0.7 0 270)
			(size 0.9 0.7)
			(layers "F.Cu" "F.Mask" "F.Paste")
			(net "NetR33_1")
		)
		(pad "2" smd rect
			(at 0.7 0 270)
			(size 0.9 0.7)
			(layers "F.Cu" "F.Mask" "F.Paste")
			(net "NetAN2_1")
		)
	)
	(footprint "Resistors:RESC1005X04N"
		(layer "F.Cu")
		(at 119.4761 145.5786 -90)
		(property "Reference" "R23"
			(at 1.27491 0.808535 90)
			(unlocked yes)
			(layer "F.SilkS")
			(effects
				(font
					(size 0.762 0.762)
					(thickness 0.2286)
				)
				(justify left bottom)
			)
		)
		(property "Value" "ERJ-2GE0R00X"
			(at 3.42519 0.2413 0)
			(unlocked yes)
			(layer "F.SilkS")
			(hide yes)
			(effects
				(font
					(size 1.524 1.524)
					(thickness 0.254)
				)
				(justify left bottom)
			)
		)
		(sheetname "PCIe_JTAG")
		(sheetfile "PCIe_JTAG.kicad_sch")
		(duplicate_pad_numbers_are_jumpers no)
		(pad "1" smd rect
			(at -0.425 0)
			(size 0.6 0.65)
			(layers "F.Cu" "F.Mask" "F.Paste")
			(net "PRSNT")
		)
		(pad "2" smd rect
			(at 0.425 0)
			(size 0.6 0.65)
			(layers "F.Cu" "F.Mask" "F.Paste")
			(net "NetP2_B17")
		)
	)
	(footprint "Resistors:RESC1608X50N"
		(layer "F.Cu")
		(at 91.9361 122.0786 180)
		(property "Reference" "R22"
			(at 1.06 0.906655 0)
			(unlocked yes)
			(layer "F.SilkS")
			(effects
				(font
					(size 0.762 0.762)
					(thickness 0.2286)
				)
				(justify left bottom)
			)
		)
		(property "Value" "ERJ-3EKF4701V"
			(at 0.4445 -3.72999 0)
			(unlocked yes)
			(layer "F.SilkS")
			(hide yes)
			(effects
				(font
					(size 1.524 1.524)
					(thickness 0.254)
				)
				(justify left bottom)
			)
		)
		(sheetname "PCIe_JTAG")
		(sheetfile "PCIe_JTAG.kicad_sch")
		(duplicate_pad_numbers_are_jumpers no)
		(fp_line
			(start 0 -0.5)
			(end 0 0.5)
			(stroke
				(width 0.1524)
				(type solid)
			)
			(layer "F.SilkS")
		)
		(pad "1" smd rect
			(at -0.69 0 270)
			(size 1 0.72)
			(layers "F.Cu" "F.Mask" "F.Paste")
			(net "PCIE_PERST")
		)
		(pad "2" smd rect
			(at 0.69 0 270)
			(size 1 0.72)
			(layers "F.Cu" "F.Mask" "F.Paste")
			(net "+3.3V")
		)
	)
	(footprint "Passives:FUSM1608X60N"
		(layer "F.Cu")
		(at 228.6261 118.5162 180)
		(property "Reference" "F1"
			(at -0.6 0.806655 0)
			(unlocked yes)
			(layer "F.SilkS")
			(effects
				(font
					(size 0.762 0.762)
					(thickness 0.2286)
				)
				(justify left bottom)
			)
		)
		(property "Value" "FUSE_0603_2.00A"
			(at 2.1929 -5.08039 0)
			(unlocked yes)
			(layer "F.SilkS")
			(hide yes)
			(effects
				(font
					(size 1.524 1.524)
					(thickness 0.254)
				)
				(justify left bottom)
			)
		)
		(sheetname "POWER")
		(sheetfile "POWER.kicad_sch")
		(duplicate_pad_numbers_are_jumpers no)
		(fp_line
			(start 0 -0.5)
			(end 0 0.5)
			(stroke
				(width 0.1524)
				(type solid)
			)
			(layer "F.SilkS")
		)
		(pad "1" smd rect
			(at -0.69 0 270)
			(size 1 0.72)
			(layers "F.Cu" "F.Mask" "F.Paste")
			(net "NetD12_1")
		)
		(pad "2" smd rect
			(at 0.69 0 270)
			(size 1 0.72)
			(layers "F.Cu" "F.Mask" "F.Paste")
			(net "+12V")
		)
	)
	(footprint "Vault:AMPH-901-143-6RFX_V"
		(layer "F.Cu")
		(at 60.9761 108.5782 180)
		(property "Reference" "AN2"
			(at -5.917345 2.55101 90)
			(unlocked yes)
			(layer "F.SilkS")
			(effects
				(font
					(size 0.762 0.762)
					(thickness 0.2286)
				)
				(justify left bottom)
			)
		)
		(property "Value" "901-143-6RFX"
			(at 4.6101 -2.05359 0)
			(unlocked yes)
			(layer "F.SilkS")
			(hide yes)
			(effects
				(font
					(size 1.524 1.524)
					(thickness 0.254)
				)
				(justify left bottom)
			)
		)
		(sheetname "USER_IO")
		(sheetfile "USER_IO.kicad_sch")
		(duplicate_pad_numbers_are_jumpers no)
		(fp_line
			(start 3.5 -1.38)
			(end 3.5 1.38)
			(stroke
				(width 0.2)
				(type solid)
			)
			(layer "F.SilkS")
		)
		(fp_line
			(start 1.38 3.5)
			(end -1.38 3.5)
			(stroke
				(width 0.2)
				(type solid)
			)
			(layer "F.SilkS")
		)
		(fp_line
			(start 1.38 -3.5)
			(end -1.38 -3.5)
			(stroke
				(width 0.2)
				(type solid)
			)
			(layer "F.SilkS")
		)
		(fp_line
			(start -3.5 -1.38)
			(end -3.5 1.38)
			(stroke
				(width 0.2)
				(type solid)
			)
			(layer "F.SilkS")
		)
		(pad "1" thru_hole rect
			(at 0 0 180)
			(size 2 2)
			(drill 1.5)
			(layers "*.Cu" "*.Mask")
			(remove_unused_layers no)
			(net "NetAN2_1")
		)
		(pad "2" thru_hole circle
			(at -2.54 -2.54 180)
			(size 2.2 2.2)
			(drill 1.7)
			(layers "*.Cu" "*.Mask")
			(remove_unused_layers no)
			(net "GND")
			(thermal_bridge_angle 90)
		)
		(pad "3" thru_hole circle
			(at -2.54 2.54 180)
			(size 2.2 2.2)
			(drill 1.7)
			(layers "*.Cu" "*.Mask")
			(remove_unused_layers no)
			(net "GND")
			(thermal_bridge_angle 90)
		)
		(pad "4" thru_hole circle
			(at 2.54 2.54 180)
			(size 2.2 2.2)
			(drill 1.7)
			(layers "*.Cu" "*.Mask")
			(remove_unused_layers no)
			(net "GND")
			(thermal_bridge_angle 90)
		)
		(pad "5" thru_hole circle
			(at 2.54 -2.54 180)
			(size 2.2 2.2)
			(drill 1.7)
			(layers "*.Cu" "*.Mask")
			(remove_unused_layers no)
			(net "GND")
			(thermal_bridge_angle 90)
		)
	)
	(footprint "Vault:RESC1608X55X30NL15T15"
		(layer "F.Cu")
		(at 166.1261 88.5786 90)
		(property "Reference" "R26"
			(at 3.14763 0.055781 90)
			(unlocked yes)
			(layer "F.SilkS")
			(effects
				(font
					(size 0.762 0.762)
					(thickness 0.2286)
				)
			)
		)
		(property "Value" "4.7K"
			(at -3.114802 2.39944 0)
			(unlocked yes)
			(layer "F.SilkS")
			(hide yes)
			(effects
				(font
					(size 1.524 1.524)
					(thickness 0.254)
				)
			)
		)
		(sheetname "GPS_IMU_SENSORS")
		(sheetfile "GPS_IMU_SENSORS.kicad_sch")
		(duplicate_pad_numbers_are_jumpers no)
		(pad "1" smd rect
			(at -0.75 0 180)
			(size 0.95 0.95)
			(layers "F.Cu" "F.Mask" "F.Paste")
			(net "SDA")
		)
		(pad "2" smd rect
			(at 0.75 0 180)
			(size 0.95 0.95)
			(layers "F.Cu" "F.Mask" "F.Paste")
			(net "+3.3V")
		)
	)
	(footprint "Vault:CAPC1608X87X45ML20T05"
		(layer "F.Cu")
		(at 80.3761 139.6162 -90)
		(property "Reference" "C29"
			(at 2.7714 -0.026931 90)
			(unlocked yes)
			(layer "F.SilkS")
			(effects
				(font
					(size 0.762 0.762)
					(thickness 0.2286)
				)
			)
		)
		(property "Value" "0.1uF"
			(at 2.09443 2.657602 270)
			(unlocked yes)
			(layer "F.SilkS")
			(hide yes)
			(effects
				(font
					(size 1.524 1.524)
					(thickness 0.254)
				)
			)
		)
		(sheetname "USER_IO")
		(sheetfile "USER_IO.kicad_sch")
		(duplicate_pad_numbers_are_jumpers no)
		(pad "1" smd rect
			(at -0.7 0)
			(size 1.1 1.05)
			(layers "F.Cu" "F.Mask" "F.Paste")
			(net "+3.3V")
		)
		(pad "2" smd rect
			(at 0.7 0)
			(size 1.1 1.05)
			(layers "F.Cu" "F.Mask" "F.Paste")
			(net "GND")
		)
	)
	(footprint "Passives:IND_PM124SH"
		(layer "F.Cu")
		(at 210.9261 99.2162 180)
		(property "Reference" "L2"
			(at -4.7 -7.493345 0)
			(unlocked yes)
			(layer "F.SilkS")
			(effects
				(font
					(size 0.762 0.762)
					(thickness 0.2286)
				)
				(justify left bottom)
			)
		)
		(property "Value" "PM124SH-100M-RC"
			(at 11.1787 -11.07019 0)
			(unlocked yes)
			(layer "F.SilkS")
			(hide yes)
			(effects
				(font
					(size 1.524 1.524)
					(thickness 0.254)
				)
				(justify left bottom)
			)
		)
		(sheetname "POWER")
		(sheetfile "POWER.kicad_sch")
		(duplicate_pad_numbers_are_jumpers no)
		(fp_line
			(start 6.681 6.4)
			(end -6.681 6.4)
			(stroke
				(width 0.254)
				(type solid)
			)
			(layer "F.SilkS")
		)
		(fp_line
			(start 6.681 -6.4)
			(end 6.681 6.4)
			(stroke
				(width 0.254)
				(type solid)
			)
			(layer "F.SilkS")
		)
		(fp_line
			(start 6.681 -6.4)
			(end -6.681 -6.4)
			(stroke
				(width 0.254)
				(type solid)
			)
			(layer "F.SilkS")
		)
		(fp_line
			(start -6.681 -6.4)
			(end -6.681 6.4)
			(stroke
				(width 0.254)
				(type solid)
			)
			(layer "F.SilkS")
		)
		(pad "1" smd rect
			(at -4.85 0 180)
			(size 2.9 5.4)
			(layers "F.Cu" "F.Mask" "F.Paste")
			(net "+3.3V")
		)
		(pad "2" smd rect
			(at 4.85 0 180)
			(size 2.9 5.4)
			(layers "F.Cu" "F.Mask" "F.Paste")
			(net "NetC3_2")
		)
	)
	(footprint "Connectors:SAMTEC_HTST-105-01-L-DV-A"
		(layer "F.Cu")
		(at 212.8061 138.9462)
		(property "Reference" "U5"
			(at -9.58 -5.136655 0)
			(unlocked yes)
			(layer "F.SilkS")
			(effects
				(font
					(size 0.762 0.762)
					(thickness 0.2286)
				)
				(justify left bottom)
			)
		)
		(property "Value" "HTST-105-01-L-DV-A"
			(at -0.5217 18.18359 0)
			(unlocked yes)
			(layer "F.SilkS")
			(hide yes)
			(effects
				(font
					(size 1.524 1.524)
					(thickness 0.254)
				)
				(justify left bottom)
			)
		)
		(sheetname "PCIe_JTAG")
		(sheetfile "PCIe_JTAG.kicad_sch")
		(duplicate_pad_numbers_are_jumpers no)
		(fp_line
			(start -10.16 -4.635)
			(end -6.065 -4.635)
			(stroke
				(width 0.2)
				(type solid)
			)
			(layer "F.SilkS")
		)
		(fp_line
			(start -10.16 4.635)
			(end -10.16 -4.635)
			(stroke
				(width 0.2)
				(type solid)
			)
			(layer "F.SilkS")
		)
		(fp_line
			(start -10.16 4.635)
			(end -6.065 4.635)
			(stroke
				(width 0.2)
				(type solid)
			)
			(layer "F.SilkS")
		)
		(fp_line
			(start 6.065 -4.635)
			(end 10.16 -4.635)
			(stroke
				(width 0.2)
				(type solid)
			)
			(layer "F.SilkS")
		)
		(fp_line
			(start 6.065 4.635)
			(end 10.16 4.635)
			(stroke
				(width 0.2)
				(type solid)
			)
			(layer "F.SilkS")
		)
		(fp_line
			(start 10.16 4.635)
			(end 10.16 -4.635)
			(stroke
				(width 0.2)
				(type solid)
			)
			(layer "F.SilkS")
		)
		(fp_circle
			(center -7.62 5.715)
			(end -7.62 5.08)
			(stroke
				(width 0.2)
				(type solid)
			)
			(fill no)
			(layer "F.SilkS")
		)
		(pad "" np_thru_hole circle
			(at -3.81 0)
			(size 1.676 1.676)
			(drill 1.676)
			(layers "*.Cu" "*.Mask")
			(thermal_bridge_angle 90)
		)
		(pad "" np_thru_hole circle
			(at 3.81 0)
			(size 1.676 1.676)
			(drill 1.676)
			(layers "*.Cu" "*.Mask")
			(thermal_bridge_angle 90)
		)
		(pad "1" smd rect
			(at -5.08 3.43)
			(size 1.27 5.08)
			(layers "F.Cu" "F.Mask" "F.Paste")
			(net "NetR18_2")
		)
		(pad "2" smd rect
			(at -5.08 -3.43)
			(size 1.27 5.08)
			(layers "F.Cu" "F.Mask" "F.Paste")
			(net "GND")
		)
		(pad "3" smd rect
			(at -2.54 3.43)
			(size 1.27 5.08)
			(layers "F.Cu" "F.Mask" "F.Paste")
			(net "NetR19_2")
		)
		(pad "4" smd rect
			(at -2.54 -3.43)
			(size 1.27 5.08)
			(layers "F.Cu" "F.Mask" "F.Paste")
			(net "+3.3V")
		)
		(pad "5" smd rect
			(at 0 3.43)
			(size 1.27 5.08)
			(layers "F.Cu" "F.Mask" "F.Paste")
			(net "NetR20_2")
		)
		(pad "6" smd rect
			(at 0 -3.43)
			(size 1.27 5.08)
			(layers "F.Cu" "F.Mask" "F.Paste")
			(net "+3.3V")
		)
		(pad "7" smd rect
			(at 2.54 3.43)
			(size 1.27 5.08)
			(layers "F.Cu" "F.Mask" "F.Paste")
		)
		(pad "8" smd rect
			(at 2.54 -3.43)
			(size 1.27 5.08)
			(layers "F.Cu" "F.Mask" "F.Paste")
		)
		(pad "9" smd rect
			(at 5.08 3.43)
			(size 1.27 5.08)
			(layers "F.Cu" "F.Mask" "F.Paste")
			(net "NetR21_2")
		)
		(pad "10" smd rect
			(at 5.08 -3.43)
			(size 1.27 5.08)
			(layers "F.Cu" "F.Mask" "F.Paste")
			(net "GND")
		)
	)
	(footprint "Vault:CAPC1608X87X45ML20T05"
		(layer "F.Cu")
		(at 215.9637 90.4662 90)
		(property "Reference" "C9"
			(at 4.2 -0.493345 270)
			(unlocked yes)
			(layer "F.SilkS")
			(effects
				(font
					(size 0.762 0.762)
					(thickness 0.2286)
				)
				(justify left bottom)
			)
		)
		(property "Value" "0.1uF"
			(at -11.53319 0.6471 0)
			(unlocked yes)
			(layer "F.SilkS")
			(hide yes)
			(effects
				(font
					(size 1.524 1.524)
					(thickness 0.254)
				)
				(justify left bottom)
			)
		)
		(sheetname "POWER")
		(sheetfile "POWER.kicad_sch")
		(duplicate_pad_numbers_are_jumpers no)
		(pad "1" smd rect
			(at -0.7 0 180)
			(size 1.1 1.05)
			(layers "F.Cu" "F.Mask" "F.Paste")
			(net "GND")
		)
		(pad "2" smd rect
			(at 0.7 0 180)
			(size 1.1 1.05)
			(layers "F.Cu" "F.Mask" "F.Paste")
			(net "+3.3V")
		)
	)
	(footprint "IS32FL3207:IS32FL3207"
		(layer "F.Cu")
		(at 89.3761 87.1162)
		(property "Reference" "U6"
			(at -2.271395 -3.723079 0)
			(unlocked yes)
			(layer "F.SilkS")
			(effects
				(font
					(size 0.762 0.762)
					(thickness 0.2286)
				)
			)
		)
		(property "Value" "IS32FL3207"
			(at 4.20136 4.689602 0)
			(unlocked yes)
			(layer "F.SilkS")
			(hide yes)
			(effects
				(font
					(size 1.524 1.524)
					(thickness 0.254)
				)
			)
		)
		(sheetname "USER_IO_STATUS")
		(sheetfile "USER_IO_STATUS.kicad_sch")
		(duplicate_pad_numbers_are_jumpers no)
		(fp_line
			(start -2.65 -2.65)
			(end -2.05 -2.65)
			(stroke
				(width 0.2)
				(type solid)
			)
			(layer "F.SilkS")
		)
		(fp_line
			(start -2.65 -2.05)
			(end -2.65 -2.65)
			(stroke
				(width 0.2)
				(type solid)
			)
			(layer "F.SilkS")
		)
		(fp_line
			(start -2.65 2.65)
			(end -2.65 2.05)
			(stroke
				(width 0.2)
				(type solid)
			)
			(layer "F.SilkS")
		)
		(fp_line
			(start -2.65 2.65)
			(end -2.05 2.65)
			(stroke
				(width 0.2)
				(type solid)
			)
			(layer "F.SilkS")
		)
		(fp_line
			(start 2.05 -2.65)
			(end 2.65 -2.65)
			(stroke
				(width 0.2)
				(type solid)
			)
			(layer "F.SilkS")
		)
		(fp_line
			(start 2.05 2.65)
			(end 2.65 2.65)
			(stroke
				(width 0.2)
				(type solid)
			)
			(layer "F.SilkS")
		)
		(fp_line
			(start 2.65 -2.05)
			(end 2.65 -2.65)
			(stroke
				(width 0.2)
				(type solid)
			)
			(layer "F.SilkS")
		)
		(fp_line
			(start 2.65 2.65)
			(end 2.65 2.05)
			(stroke
				(width 0.2)
				(type solid)
			)
			(layer "F.SilkS")
		)
		(fp_circle
			(center -3.3 -2.5)
			(end -3.3 -2.625)
			(stroke
				(width 0.25)
				(type solid)
			)
			(fill no)
			(layer "F.SilkS")
		)
		(pad "1" smd rect
			(at -2.325 -1.5 90)
			(size 0.26 0.9)
			(layers "F.Cu" "F.Mask" "F.Paste")
			(net "NetC39_2")
		)
		(pad "2" smd rect
			(at -2.325 -1 90)
			(size 0.26 0.9)
			(layers "F.Cu" "F.Mask" "F.Paste")
			(net "+3.3V")
		)
		(pad "3" smd rect
			(at -2.325 -0.5 90)
			(size 0.26 0.9)
			(layers "F.Cu" "F.Mask" "F.Paste")
			(net "+3.3V")
		)
		(pad "4" smd rect
			(at -2.325 0 90)
			(size 0.26 0.9)
			(layers "F.Cu" "F.Mask" "F.Paste")
			(net "GND")
		)
		(pad "5" smd rect
			(at -2.325 0.5 90)
			(size 0.26 0.9)
			(layers "F.Cu" "F.Mask" "F.Paste")
			(net "NetR41_2")
		)
		(pad "6" smd rect
			(at -2.325 1 90)
			(size 0.26 0.9)
			(layers "F.Cu" "F.Mask" "F.Paste")
			(net "SDA")
		)
		(pad "7" smd rect
			(at -2.325 1.5 90)
			(size 0.26 0.9)
			(layers "F.Cu" "F.Mask" "F.Paste")
			(net "SCL")
		)
		(pad "8" smd rect
			(at -1.5 2.325)
			(size 0.26 0.9)
			(layers "F.Cu" "F.Mask" "F.Paste")
			(net "NetD13_4")
		)
		(pad "9" smd rect
			(at -1 2.325)
			(size 0.26 0.9)
			(layers "F.Cu" "F.Mask" "F.Paste")
			(net "NetD13_3")
		)
		(pad "10" smd rect
			(at -0.5 2.325)
			(size 0.26 0.9)
			(layers "F.Cu" "F.Mask" "F.Paste")
			(net "NetD13_2")
		)
		(pad "11" smd rect
			(at 0 2.325)
			(size 0.26 0.9)
			(layers "F.Cu" "F.Mask" "F.Paste")
			(net "GND")
		)
		(pad "12" smd rect
			(at 0.5 2.325)
			(size 0.26 0.9)
			(layers "F.Cu" "F.Mask" "F.Paste")
			(net "NetD14_4")
		)
		(pad "13" smd rect
			(at 1 2.325)
			(size 0.26 0.9)
			(layers "F.Cu" "F.Mask" "F.Paste")
			(net "NetD14_3")
		)
		(pad "14" smd rect
			(at 1.5 2.325)
			(size 0.26 0.9)
			(layers "F.Cu" "F.Mask" "F.Paste")
			(net "NetD14_2")
		)
		(pad "15" smd rect
			(at 2.325 1.5 90)
			(size 0.26 0.9)
			(layers "F.Cu" "F.Mask" "F.Paste")
			(net "NetD15_4")
		)
		(pad "16" smd rect
			(at 2.325 1 90)
			(size 0.26 0.9)
			(layers "F.Cu" "F.Mask" "F.Paste")
			(net "NetD15_3")
		)
		(pad "17" smd rect
			(at 2.325 0.5 90)
			(size 0.26 0.9)
			(layers "F.Cu" "F.Mask" "F.Paste")
			(net "NetD15_2")
		)
		(pad "18" smd rect
			(at 2.325 0 90)
			(size 0.26 0.9)
			(layers "F.Cu" "F.Mask" "F.Paste")
			(net "GND")
		)
		(pad "19" smd rect
			(at 2.325 -0.5 90)
			(size 0.26 0.9)
			(layers "F.Cu" "F.Mask" "F.Paste")
			(net "NetD16_4")
		)
		(pad "20" smd rect
			(at 2.325 -1 90)
			(size 0.26 0.9)
			(layers "F.Cu" "F.Mask" "F.Paste")
			(net "NetD16_3")
		)
		(pad "21" smd rect
			(at 2.325 -1.5 90)
			(size 0.26 0.9)
			(layers "F.Cu" "F.Mask" "F.Paste")
			(net "NetD16_2")
		)
		(pad "22" smd rect
			(at 1.5 -2.325)
			(size 0.26 0.9)
			(layers "F.Cu" "F.Mask" "F.Paste")
			(net "NetD17_4")
		)
		(pad "23" smd rect
			(at 1 -2.325)
			(size 0.26 0.9)
			(layers "F.Cu" "F.Mask" "F.Paste")
			(net "NetD17_3")
		)
		(pad "24" smd rect
			(at 0.5 -2.325)
			(size 0.26 0.9)
			(layers "F.Cu" "F.Mask" "F.Paste")
			(net "NetD17_2")
		)
		(pad "25" smd rect
			(at 0 -2.325)
			(size 0.26 0.9)
			(layers "F.Cu" "F.Mask" "F.Paste")
			(net "GND")
		)
		(pad "26" smd rect
			(at -0.5 -2.325)
			(size 0.26 0.9)
			(layers "F.Cu" "F.Mask" "F.Paste")
			(net "NetD18_4")
		)
		(pad "27" smd rect
			(at -1 -2.325)
			(size 0.26 0.9)
			(layers "F.Cu" "F.Mask" "F.Paste")
			(net "NetD18_3")
		)
		(pad "28" smd rect
			(at -1.5 -2.325)
			(size 0.26 0.9)
			(layers "F.Cu" "F.Mask" "F.Paste")
			(net "NetD18_2")
		)
		(pad "29" smd rect
			(at 0 0)
			(size 3.25 3.25)
			(layers "F.Cu" "F.Mask" "F.Paste")
			(net "GND")
		)
	)
	(footprint "Vault:CAPC1608X87X45ML20T05"
		(layer "F.Cu")
		(at 225.6261 115.8162 -90)
		(property "Reference" "C2"
			(at -2.25 -0.343345 90)
			(unlocked yes)
			(layer "F.SilkS")
			(effects
				(font
					(size 0.762 0.762)
					(thickness 0.2286)
				)
				(justify left bottom)
			)
		)
		(property "Value" "0.1uF"
			(at 2.31879 1.4493 0)
			(unlocked yes)
			(layer "F.SilkS")
			(hide yes)
			(effects
				(font
					(size 1.524 1.524)
					(thickness 0.254)
				)
				(justify left bottom)
			)
		)
		(sheetname "POWER")
		(sheetfile "POWER.kicad_sch")
		(duplicate_pad_numbers_are_jumpers no)
		(pad "1" smd rect
			(at -0.7 0)
			(size 1.1 1.05)
			(layers "F.Cu" "F.Mask" "F.Paste")
			(net "GND")
		)
		(pad "2" smd rect
			(at 0.7 0)
			(size 1.1 1.05)
			(layers "F.Cu" "F.Mask" "F.Paste")
			(net "+12V")
		)
	)
	(footprint "SamacSys:SOP50P310X90-8N"
		(layer "F.Cu")
		(at 82.3761 122.3662 180)
		(property "Reference" "U11"
			(at 0.153605 2.026921 180)
			(unlocked yes)
			(layer "F.SilkS")
			(effects
				(font
					(size 0.762 0.762)
					(thickness 0.2286)
				)
			)
		)
		(property "Value" "NC7WV125K8X"
			(at 6.233115 2.911602 180)
			(unlocked yes)
			(layer "F.SilkS")
			(hide yes)
			(effects
				(font
					(size 1.524 1.524)
					(thickness 0.254)
				)
			)
		)
		(sheetname "USER_IO")
		(sheetfile "USER_IO.kicad_sch")
		(duplicate_pad_numbers_are_jumpers no)
		(fp_line
			(start 0.8 1)
			(end -0.8 1)
			(stroke
				(width 0.2)
				(type solid)
			)
			(layer "F.SilkS")
		)
		(fp_line
			(start 0.8 -1)
			(end 0.8 1)
			(stroke
				(width 0.2)
				(type solid)
			)
			(layer "F.SilkS")
		)
		(fp_line
			(start 0.8 -1)
			(end -0.8 -1)
			(stroke
				(width 0.2)
				(type solid)
			)
			(layer "F.SilkS")
		)
		(fp_line
			(start -0.8 -1)
			(end -0.8 1)
			(stroke
				(width 0.2)
				(type solid)
			)
			(layer "F.SilkS")
		)
		(fp_line
			(start -1.15 -1.25)
			(end -2 -1.25)
			(stroke
				(width 0.2)
				(type solid)
			)
			(layer "F.SilkS")
		)
		(pad "1" smd rect
			(at -1.575 -0.75 180)
			(size 0.85 0.3)
			(layers "F.Cu" "F.Mask" "F.Paste")
			(net "ANT3_IO_OUT")
		)
		(pad "2" smd rect
			(at -1.575 -0.25 180)
			(size 0.85 0.3)
			(layers "F.Cu" "F.Mask" "F.Paste")
			(net "ANT3_OUT")
		)
		(pad "3" smd rect
			(at -1.575 0.25 180)
			(size 0.85 0.3)
			(layers "F.Cu" "F.Mask" "F.Paste")
			(net "ANT3_IN")
		)
		(pad "4" smd rect
			(at -1.575 0.75 180)
			(size 0.85 0.3)
			(layers "F.Cu" "F.Mask" "F.Paste")
			(net "GND")
		)
		(pad "5" smd rect
			(at 1.575 0.75 180)
			(size 0.85 0.3)
			(layers "F.Cu" "F.Mask" "F.Paste")
			(net "NetR28_1")
		)
		(pad "6" smd rect
			(at 1.575 0.25 180)
			(size 0.85 0.3)
			(layers "F.Cu" "F.Mask" "F.Paste")
			(net "NetR28_1")
		)
		(pad "7" smd rect
			(at 1.575 -0.25 180)
			(size 0.85 0.3)
			(layers "F.Cu" "F.Mask" "F.Paste")
			(net "ANT3_IO_IN")
		)
		(pad "8" smd rect
			(at 1.575 -0.75 180)
			(size 0.85 0.3)
			(layers "F.Cu" "F.Mask" "F.Paste")
			(net "+3.3V")
		)
	)
	(footprint "Vault:RESC1608X55X30NL15T15"
		(layer "F.Cu")
		(at 75.1261 55.6162 90)
		(property "Reference" "R39"
			(at -5.7714 0.026921 90)
			(unlocked yes)
			(layer "F.SilkS")
			(effects
				(font
					(size 0.762 0.762)
					(thickness 0.2286)
				)
			)
		)
		(property "Value" "200 OHM"
			(at -2.962402 4.81166 0)
			(unlocked yes)
			(layer "F.SilkS")
			(hide yes)
			(effects
				(font
					(size 1.524 1.524)
					(thickness 0.254)
				)
			)
		)
		(sheetname "USER_IO_STATUS")
		(sheetfile "USER_IO_STATUS.kicad_sch")
		(duplicate_pad_numbers_are_jumpers no)
		(pad "1" smd rect
			(at -0.675 0 180)
			(size 0.95 0.8)
			(layers "F.Cu" "F.Mask" "F.Paste")
			(net "LED4")
		)
		(pad "2" smd rect
			(at 0.675 0 180)
			(size 0.95 0.8)
			(layers "F.Cu" "F.Mask" "F.Paste")
			(net "NetD11_1")
		)
	)
	(footprint "Resistors:RESC1608X50N"
		(layer "F.Cu")
		(at 208.7885 107.6662 180)
		(property "Reference" "R8"
			(at 1.5 0.393345 180)
			(unlocked yes)
			(layer "F.SilkS")
			(effects
				(font
					(size 0.762 0.762)
					(thickness 0.2286)
				)
				(justify left bottom)
			)
		)
		(property "Value" "ERJ-3EKF2201V"
			(at -7.3553 -5.15659 0)
			(unlocked yes)
			(layer "F.SilkS")
			(hide yes)
			(effects
				(font
					(size 1.524 1.524)
					(thickness 0.254)
				)
				(justify left bottom)
			)
		)
		(sheetname "POWER")
		(sheetfile "POWER.kicad_sch")
		(duplicate_pad_numbers_are_jumpers no)
		(fp_line
			(start 0 -0.5)
			(end 0 0.5)
			(stroke
				(width 0.1524)
				(type solid)
			)
			(layer "F.SilkS")
		)
		(pad "1" smd rect
			(at -0.69 0 270)
			(size 1 0.72)
			(layers "F.Cu" "F.Mask" "F.Paste")
			(net "GND")
		)
		(pad "2" smd rect
			(at 0.69 0 270)
			(size 1 0.72)
			(layers "F.Cu" "F.Mask" "F.Paste")
			(net "NetC20_1")
		)
	)
	(footprint "Resistors:RESC2012X50N"
		(layer "F.Cu")
		(at 224.9261 142.2162 -90)
		(property "Reference" "R21"
			(at -1.25 -1.406655 270)
			(unlocked yes)
			(layer "F.SilkS")
			(effects
				(font
					(size 0.762 0.762)
					(thickness 0.2286)
				)
				(justify left bottom)
			)
		)
		(property "Value" "CRCW080533R0FKEA"
			(at -3.08581 -11.2251 0)
			(unlocked yes)
			(layer "F.SilkS")
			(hide yes)
			(effects
				(font
					(size 1.524 1.524)
					(thickness 0.254)
				)
				(justify left bottom)
			)
		)
		(sheetname "PCIe_JTAG")
		(sheetfile "PCIe_JTAG.kicad_sch")
		(duplicate_pad_numbers_are_jumpers no)
		(fp_line
			(start 0 0.762)
			(end 0 -0.762)
			(stroke
				(width 0.1524)
				(type solid)
			)
			(layer "F.SilkS")
		)
		(pad "1" smd rect
			(at -1 0)
			(size 1.45 0.95)
			(layers "F.Cu" "F.Mask" "F.Paste")
			(net "FPGA_TDI")
		)
		(pad "2" smd rect
			(at 1 0)
			(size 1.45 0.95)
			(layers "F.Cu" "F.Mask" "F.Paste")
			(net "NetR21_2")
		)
	)
	(footprint "Vault:FP-5TS1-IPC_C"
		(layer "F.Cu")
		(at 180.1261 87.0786 -90)
		(property "Reference" "U7"
			(at -2.723069 0.771405 0)
			(unlocked yes)
			(layer "F.SilkS")
			(effects
				(font
					(size 0.762 0.762)
					(thickness 0.2286)
				)
			)
		)
		(property "Value" "AT24MAC402-STUM-T"
			(at 10.752795 3.216402 270)
			(unlocked yes)
			(layer "F.SilkS")
			(hide yes)
			(effects
				(font
					(size 1.524 1.524)
					(thickness 0.254)
				)
			)
		)
		(sheetname "GPS_IMU_SENSORS")
		(sheetfile "GPS_IMU_SENSORS.kicad_sch")
		(duplicate_pad_numbers_are_jumpers no)
		(fp_line
			(start 0.17207 1.45)
			(end -0.17207 1.45)
			(stroke
				(width 0.2)
				(type solid)
			)
			(layer "F.SilkS")
		)
		(fp_line
			(start 0.8 0.30894)
			(end 0.8 -0.30893)
			(stroke
				(width 0.2)
				(type solid)
			)
			(layer "F.SilkS")
		)
		(fp_line
			(start 0.17207 -1.45)
			(end -0.17207 -1.45)
			(stroke
				(width 0.2)
				(type solid)
			)
			(layer "F.SilkS")
		)
		(fp_circle
			(center -2.21035 -0.95)
			(end -2.33535 -0.95)
			(stroke
				(width 0.25)
				(type solid)
			)
			(fill no)
			(layer "F.SilkS")
		)
		(fp_line
			(start -1.68536 1.55)
			(end -1.68536 -1.55)
			(stroke
				(width 0.2)
				(type solid)
			)
			(layer "F.CrtYd")
		)
		(fp_line
			(start 1.68536 1.55)
			(end -1.68536 1.55)
			(stroke
				(width 0.2)
				(type solid)
			)
			(layer "F.CrtYd")
		)
		(fp_line
			(start 1.68536 1.55)
			(end 1.68536 -1.55)
			(stroke
				(width 0.2)
				(type solid)
			)
			(layer "F.CrtYd")
		)
		(fp_line
			(start 1.68536 -1.55)
			(end -1.68536 -1.55)
			(stroke
				(width 0.2)
				(type solid)
			)
			(layer "F.CrtYd")
		)
		(fp_line
			(start -1.68536 1.55)
			(end -1.68536 -1.55)
			(stroke
				(width 0.2)
				(type solid)
			)
			(layer "F.Fab")
		)
		(fp_line
			(start 1.68536 1.55)
			(end -1.68536 1.55)
			(stroke
				(width 0.2)
				(type solid)
			)
			(layer "F.Fab")
		)
		(fp_line
			(start 1.68536 1.55)
			(end 1.68536 -1.55)
			(stroke
				(width 0.2)
				(type solid)
			)
			(layer "F.Fab")
		)
		(fp_line
			(start 0 0.5)
			(end 0 -0.5)
			(stroke
				(width 0.1)
				(type solid)
			)
			(layer "F.Fab")
		)
		(fp_line
			(start 0.5 0)
			(end -0.5 0)
			(stroke
				(width 0.1)
				(type solid)
			)
			(layer "F.Fab")
		)
		(fp_line
			(start 1.68536 -1.55)
			(end -1.68536 -1.55)
			(stroke
				(width 0.2)
				(type solid)
			)
			(layer "F.Fab")
		)
		(fp_text user "${REFERENCE}"
			(at 0 0.28425 270)
			(unlocked yes)
			(layer "F.Fab")
			(effects
				(font
					(face "Arial")
					(size 0.63 0.63)
					(thickness 0.1)
				)
				(justify left bottom)
			)
		)
		(pad "1" smd rect
			(at -1.06621 -0.95 270)
			(size 1.03828 0.53213)
			(layers "F.Cu" "F.Mask" "F.Paste")
			(net "SCL")
			(solder_mask_margin 0)
			(solder_paste_margin 0)
		)
		(pad "2" smd roundrect
			(at -1.06621 0 270)
			(size 1.03828 0.53213)
			(layers "F.Cu" "F.Mask" "F.Paste")
			(roundrect_rratio 0.5)
			(net "GND")
			(solder_mask_margin 0)
			(solder_paste_margin 0)
		)
		(pad "3" smd roundrect
			(at -1.06621 0.95 270)
			(size 1.03828 0.53213)
			(layers "F.Cu" "F.Mask" "F.Paste")
			(roundrect_rratio 0.5)
			(net "SDA")
			(solder_mask_margin 0)
			(solder_paste_margin 0)
		)
		(pad "4" smd roundrect
			(at 1.06621 0.95 270)
			(size 1.03828 0.53213)
			(layers "F.Cu" "F.Mask" "F.Paste")
			(roundrect_rratio 0.5)
			(net "+3.3V")
			(solder_mask_margin 0)
			(solder_paste_margin 0)
		)
		(pad "5" smd roundrect
			(at 1.06621 -0.95 270)
			(size 1.03828 0.53213)
			(layers "F.Cu" "F.Mask" "F.Paste")
			(roundrect_rratio 0.5)
			(net "EXT_EEPROM_WP")
			(solder_mask_margin 0)
			(solder_paste_margin 0)
		)
	)
	(footprint "Vault:CAPC1608X87X45ML20T05"
		(layer "F.Cu")
		(at 80.6261 125.8662 -90)
		(property "Reference" "C27"
			(at 2.7714 -0.026931 90)
			(unlocked yes)
			(layer "F.SilkS")
			(effects
				(font
					(size 0.762 0.762)
					(thickness 0.2286)
				)
			)
		)
		(property "Value" "0.1uF"
			(at 2.09443 2.657602 270)
			(unlocked yes)
			(layer "F.SilkS")
			(hide yes)
			(effects
				(font
					(size 1.524 1.524)
					(thickness 0.254)
				)
			)
		)
		(sheetname "USER_IO")
		(sheetfile "USER_IO.kicad_sch")
		(duplicate_pad_numbers_are_jumpers no)
		(pad "1" smd rect
			(at -0.7 0)
			(size 1.1 1.05)
			(layers "F.Cu" "F.Mask" "F.Paste")
			(net "+3.3V")
		)
		(pad "2" smd rect
			(at 0.7 0)
			(size 1.1 1.05)
			(layers "F.Cu" "F.Mask" "F.Paste")
			(net "GND")
		)
	)
	(footprint "Vault:CAPC1608X87X45ML20T05"
		(layer "F.Cu")
		(at 216.2675 116.3062 90)
		(property "Reference" "C15"
			(at 1.74 0.414345 90)
			(unlocked yes)
			(layer "F.SilkS")
			(effects
				(font
					(size 0.762 0.762)
					(thickness 0.2286)
				)
				(justify left bottom)
			)
		)
		(property "Value" "0.1uF"
			(at -6.58639 -5.5125 0)
			(unlocked yes)
			(layer "F.SilkS")
			(hide yes)
			(effects
				(font
					(size 1.524 1.524)
					(thickness 0.254)
				)
				(justify left bottom)
			)
		)
		(sheetname "POWER")
		(sheetfile "POWER.kicad_sch")
		(duplicate_pad_numbers_are_jumpers no)
		(pad "1" smd rect
			(at -0.7 0 180)
			(size 1.1 1.05)
			(layers "F.Cu" "F.Mask" "F.Paste")
			(net "GND")
		)
		(pad "2" smd rect
			(at 0.7 0 180)
			(size 1.1 1.05)
			(layers "F.Cu" "F.Mask" "F.Paste")
			(net "+5.0V")
		)
	)
	(footprint "Vault:RESC1608X55X25NL10T15"
		(layer "F.Cu")
		(at 125.4261 87.4162 180)
		(property "Reference" "R43"
			(at -0.5286 -1.326921 0)
			(unlocked yes)
			(layer "F.SilkS")
			(effects
				(font
					(size 0.762 0.762)
					(thickness 0.2286)
				)
			)
		)
		(property "Value" "DNI_49.9R"
			(at -2.911602 6.132045 90)
			(unlocked yes)
			(layer "F.SilkS")
			(hide yes)
			(effects
				(font
					(size 1.524 1.524)
					(thickness 0.254)
				)
			)
		)
		(sheetname "MAC")
		(sheetfile "MAC.kicad_sch")
		(duplicate_pad_numbers_are_jumpers no)
		(pad "1" smd rect
			(at -0.7 0 270)
			(size 0.9 0.7)
			(layers "F.Cu" "F.Mask" "F.Paste")
			(net "MAC_PPS_OUT")
		)
		(pad "2" smd rect
			(at 0.7 0 270)
			(size 0.9 0.7)
			(layers "F.Cu" "F.Mask" "F.Paste")
			(net "FPGA_MAC_PPS_OUT-")
		)
	)
	(footprint "Vault:FP-LTST-C191TBKT-MFG"
		(layer "F.Cu")
		(at 71.6261 52.1162 90)
		(property "Reference" "D9"
			(at -6.771395 -0.223079 90)
			(unlocked yes)
			(layer "F.SilkS")
			(effects
				(font
					(size 0.762 0.762)
					(thickness 0.2286)
				)
			)
		)
		(property "Value" "BLUE"
			(at 1.307195 2.479802 90)
			(unlocked yes)
			(layer "F.SilkS")
			(hide yes)
			(effects
				(font
					(size 1.524 1.524)
					(thickness 0.254)
				)
			)
		)
		(sheetname "USER_IO_STATUS")
		(sheetfile "USER_IO_STATUS.kicad_sch")
		(duplicate_pad_numbers_are_jumpers no)
		(fp_line
			(start -0.85 -0.8)
			(end 0.85 -0.8)
			(stroke
				(width 0.2)
				(type solid)
			)
			(layer "F.SilkS")
		)
		(fp_line
			(start -0.85 0.8)
			(end 0.85 0.8)
			(stroke
				(width 0.2)
				(type solid)
			)
			(layer "F.SilkS")
		)
		(fp_circle
			(center -1.75 0)
			(end -1.625 0)
			(stroke
				(width 0.25)
				(type solid)
			)
			(fill no)
			(layer "F.SilkS")
		)
		(fp_line
			(start 1.25 -0.55)
			(end 1.25 0.55)
			(stroke
				(width 0.2)
				(type solid)
			)
			(layer "F.CrtYd")
		)
		(fp_line
			(start -1.25 -0.55)
			(end 1.25 -0.55)
			(stroke
				(width 0.2)
				(type solid)
			)
			(layer "F.CrtYd")
		)
		(fp_line
			(start -1.25 -0.55)
			(end -1.25 0.55)
			(stroke
				(width 0.2)
				(type solid)
			)
			(layer "F.CrtYd")
		)
		(fp_line
			(start -1.25 0.55)
			(end 1.25 0.55)
			(stroke
				(width 0.2)
				(type solid)
			)
			(layer "F.CrtYd")
		)
		(fp_line
			(start 1.25 -0.55)
			(end 1.25 0.55)
			(stroke
				(width 0.2)
				(type solid)
			)
			(layer "F.Fab")
		)
		(fp_line
			(start -1.25 -0.55)
			(end 1.25 -0.55)
			(stroke
				(width 0.2)
				(type solid)
			)
			(layer "F.Fab")
		)
		(fp_line
			(start -1.25 -0.55)
			(end -1.25 0.55)
			(stroke
				(width 0.2)
				(type solid)
			)
			(layer "F.Fab")
		)
		(fp_line
			(start 0 -0.5)
			(end 0 0.5)
			(stroke
				(width 0.1)
				(type solid)
			)
			(layer "F.Fab")
		)
		(fp_line
			(start -0.5 0)
			(end 0.5 0)
			(stroke
				(width 0.1)
				(type solid)
			)
			(layer "F.Fab")
		)
		(fp_line
			(start -1.25 0.55)
			(end 1.25 0.55)
			(stroke
				(width 0.2)
				(type solid)
			)
			(layer "F.Fab")
		)
		(fp_text user "${REFERENCE}"
			(at 0 0.28425 90)
			(unlocked yes)
			(layer "F.Fab")
			(effects
				(font
					(face "Arial")
					(size 0.63 0.63)
					(thickness 0.1)
				)
				(justify left bottom)
			)
		)
		(pad "1" smd rect
			(at -0.75 0 90)
			(size 0.8 0.8)
			(layers "F.Cu" "F.Mask" "F.Paste")
			(net "NetD9_1")
			(solder_mask_margin 0)
			(solder_paste_margin 0)
		)
		(pad "2" smd rect
			(at 0.75 0 90)
			(size 0.8 0.8)
			(layers "F.Cu" "F.Mask" "F.Paste")
			(net "+3.3V")
			(solder_mask_margin 0)
			(solder_paste_margin 0)
		)
	)
	(footprint "Vault:RESC1608X55X25LL10T15"
		(layer "F.Cu")
		(at 130.3761 85.3286)
		(property "Reference" "R10"
			(at -2.0214 0.014531 0)
			(unlocked yes)
			(layer "F.SilkS")
			(effects
				(font
					(size 0.762 0.762)
					(thickness 0.2286)
				)
			)
		)
		(property "Value" "4.7K"
			(at -2.657602 2.60264 270)
			(unlocked yes)
			(layer "F.SilkS")
			(hide yes)
			(effects
				(font
					(size 1.524 1.524)
					(thickness 0.254)
				)
			)
		)
		(sheetname "MAC")
		(sheetfile "MAC.kicad_sch")
		(duplicate_pad_numbers_are_jumpers no)
		(pad "1" smd rect
			(at -0.65 0 90)
			(size 0.8 0.6)
			(layers "F.Cu" "F.Mask" "F.Paste")
			(net "GND")
		)
		(pad "2" smd rect
			(at 0.65 0 90)
			(size 0.8 0.6)
			(layers "F.Cu" "F.Mask" "F.Paste")
			(net "FPGA_MAC_PPS_IN1-")
		)
	)
	(footprint "Vault:RESC1608X55X30NL15T15"
		(layer "F.Cu")
		(at 84.3761 125.8662 -90)
		(property "Reference" "R16"
			(at 2.7714 -0.026931 90)
			(unlocked yes)
			(layer "F.SilkS")
			(effects
				(font
					(size 0.762 0.762)
					(thickness 0.2286)
				)
			)
		)
		(property "Value" "4.7K"
			(at 0.585402 -4.85075 0)
			(unlocked yes)
			(layer "F.SilkS")
			(hide yes)
			(effects
				(font
					(size 1.524 1.524)
					(thickness 0.254)
				)
			)
		)
		(sheetname "USER_IO")
		(sheetfile "USER_IO.kicad_sch")
		(duplicate_pad_numbers_are_jumpers no)
		(pad "1" smd rect
			(at -0.75 0)
			(size 0.95 0.95)
			(layers "F.Cu" "F.Mask" "F.Paste")
			(net "ANT3_IO_OUT")
		)
		(pad "2" smd rect
			(at 0.75 0)
			(size 0.95 0.95)
			(layers "F.Cu" "F.Mask" "F.Paste")
			(net "+3.3V")
		)
	)
	(footprint "Vault:CAPC1608X87X45ML20T05"
		(layer "F.Cu")
		(at 194.1761 83.5786 180)
		(property "Reference" "C30"
			(at 2.8214 -0.026921 0)
			(unlocked yes)
			(layer "F.SilkS")
			(effects
				(font
					(size 0.762 0.762)
					(thickness 0.2286)
				)
			)
		)
		(property "Value" "0.1uF"
			(at 2.09443 2.657602 180)
			(unlocked yes)
			(layer "F.SilkS")
			(hide yes)
			(effects
				(font
					(size 1.524 1.524)
					(thickness 0.254)
				)
			)
		)
		(sheetname "GPS_IMU_SENSORS")
		(sheetfile "GPS_IMU_SENSORS.kicad_sch")
		(duplicate_pad_numbers_are_jumpers no)
		(pad "1" smd rect
			(at -0.7 0 270)
			(size 1.1 1.05)
			(layers "F.Cu" "F.Mask" "F.Paste")
			(net "GND")
		)
		(pad "2" smd rect
			(at 0.7 0 270)
			(size 1.1 1.05)
			(layers "F.Cu" "F.Mask" "F.Paste")
			(net "+3.3V")
		)
	)
	(footprint "Miscellaneous Connectors:HDR2X6_CEN"
		(layer "F.Cu")
		(at 212.7461 51.5762 180)
		(property "Reference" "P3"
			(at 18.324329 -2.146705 90)
			(unlocked yes)
			(layer "F.SilkS")
			(effects
				(font
					(size 0.762 0.762)
					(thickness 0.2286)
				)
			)
		)
		(property "Value" "EXT GPIO"
			(at -4.308602 2.32225 90)
			(unlocked yes)
			(layer "F.SilkS")
			(hide yes)
			(effects
				(font
					(size 1.524 1.524)
					(thickness 0.254)
				)
			)
		)
		(sheetname "GPS_IMU_SENSORS")
		(sheetfile "GPS_IMU_SENSORS.kicad_sch")
		(duplicate_pad_numbers_are_jumpers no)
		(fp_line
			(start 13.97 1.27)
			(end -1.27 1.27)
			(stroke
				(width 0.2)
				(type solid)
			)
			(layer "F.SilkS")
		)
		(fp_line
			(start 13.97 -3.81)
			(end 13.97 1.27)
			(stroke
				(width 0.2)
				(type solid)
			)
			(layer "F.SilkS")
		)
		(fp_line
			(start 13.97 -3.81)
			(end -1.27 -3.81)
			(stroke
				(width 0.2)
				(type solid)
			)
			(layer "F.SilkS")
		)
		(fp_line
			(start -1.27 -3.81)
			(end -1.27 1.27)
			(stroke
				(width 0.2)
				(type solid)
			)
			(layer "F.SilkS")
		)
		(fp_text user "6"
			(at 14.732 0.663575 180)
			(unlocked yes)
			(layer "F.SilkS")
			(effects
				(font
					(size 1.27 1.27)
					(thickness 0.2032)
				)
				(justify left bottom)
			)
		)
		(fp_text user "12"
			(at 14.732 -1.876425 180)
			(unlocked yes)
			(layer "F.SilkS")
			(effects
				(font
					(size 1.27 1.27)
					(thickness 0.2032)
				)
				(justify left bottom)
			)
		)
		(fp_text user "1"
			(at -2.54 0.663575 180)
			(unlocked yes)
			(layer "F.SilkS")
			(effects
				(font
					(size 1.27 1.27)
					(thickness 0.2032)
				)
				(justify left bottom)
			)
		)
		(fp_text user "7"
			(at -2.54 -1.876425 180)
			(unlocked yes)
			(layer "F.SilkS")
			(effects
				(font
					(size 1.27 1.27)
					(thickness 0.2032)
				)
				(justify left bottom)
			)
		)
		(pad "1" thru_hole rect
			(at 0 0 180)
			(size 1.5 1.5)
			(drill 0.9)
			(layers "*.Cu" "*.Mask")
			(remove_unused_layers no)
			(net "EXT_GPIO_1")
		)
		(pad "2" thru_hole circle
			(at 2.54 0 180)
			(size 1.5 1.5)
			(drill 0.9)
			(layers "*.Cu" "*.Mask")
			(remove_unused_layers no)
			(net "EXT_GPIO_2")
			(thermal_bridge_angle 90)
		)
		(pad "3" thru_hole circle
			(at 5.08 0 180)
			(size 1.5 1.5)
			(drill 0.9)
			(layers "*.Cu" "*.Mask")
			(remove_unused_layers no)
			(net "EXT_GPIO_3")
			(thermal_bridge_angle 90)
		)
		(pad "4" thru_hole circle
			(at 7.62 0 180)
			(size 1.5 1.5)
			(drill 0.9)
			(layers "*.Cu" "*.Mask")
			(remove_unused_layers no)
			(net "EXT_GPIO_4")
			(thermal_bridge_angle 90)
		)
		(pad "5" thru_hole circle
			(at 10.16 0 180)
			(size 1.5 1.5)
			(drill 0.9)
			(layers "*.Cu" "*.Mask")
			(remove_unused_layers no)
			(net "GND")
			(thermal_bridge_angle 90)
		)
		(pad "6" thru_hole circle
			(at 12.7 0 180)
			(size 1.5 1.5)
			(drill 0.9)
			(layers "*.Cu" "*.Mask")
			(remove_unused_layers no)
			(net "+3.3V")
			(thermal_bridge_angle 90)
		)
		(pad "7" thru_hole circle
			(at 0 -2.54 180)
			(size 1.5 1.5)
			(drill 0.9)
			(layers "*.Cu" "*.Mask")
			(remove_unused_layers no)
			(net "EXT_GPIO_7")
			(thermal_bridge_angle 90)
		)
		(pad "8" thru_hole circle
			(at 2.54 -2.54 180)
			(size 1.5 1.5)
			(drill 0.9)
			(layers "*.Cu" "*.Mask")
			(remove_unused_layers no)
			(net "EXT_GPIO_8")
			(thermal_bridge_angle 90)
		)
		(pad "9" thru_hole circle
			(at 5.08 -2.54 180)
			(size 1.5 1.5)
			(drill 0.9)
			(layers "*.Cu" "*.Mask")
			(remove_unused_layers no)
			(net "EXT_GPIO_9")
			(thermal_bridge_angle 90)
		)
		(pad "10" thru_hole circle
			(at 7.62 -2.54 180)
			(size 1.5 1.5)
			(drill 0.9)
			(layers "*.Cu" "*.Mask")
			(remove_unused_layers no)
			(net "EXT_GPIO_10")
			(thermal_bridge_angle 90)
		)
		(pad "11" thru_hole circle
			(at 10.16 -2.54 180)
			(size 1.5 1.5)
			(drill 0.9)
			(layers "*.Cu" "*.Mask")
			(remove_unused_layers no)
			(net "GND")
			(thermal_bridge_angle 90)
		)
		(pad "12" thru_hole circle
			(at 12.7 -2.54 180)
			(size 1.5 1.5)
			(drill 0.9)
			(layers "*.Cu" "*.Mask")
			(remove_unused_layers no)
			(net "+3.3V")
			(thermal_bridge_angle 90)
		)
	)
	(footprint "FPGA_CONN:SingleFPGAConn"
		(layer "F.Cu")
		(at 182.5759 133.49995 90)
		(property "Reference" "J37"
			(at -0.368955 -23.428198 90)
			(unlocked yes)
			(layer "F.SilkS")
			(effects
				(font
					(size 1.524 1.524)
					(thickness 0.254)
				)
			)
		)
		(property "Value" "Single FPGA Conn"
			(at 9.27992 3.521202 90)
			(unlocked yes)
			(layer "F.SilkS")
			(hide yes)
			(effects
				(font
					(size 1.524 1.524)
					(thickness 0.254)
				)
			)
		)
		(sheetname "FPGA")
		(sheetfile "FPGA.kicad_sch")
		(duplicate_pad_numbers_are_jumpers no)
		(fp_line
			(start 1.40004 -21.2499)
			(end 1.40004 -20.69999)
			(stroke
				(width 0.15011)
				(type solid)
			)
			(layer "F.SilkS")
		)
		(fp_line
			(start -1.40005 -21.2499)
			(end 1.40004 -21.2499)
			(stroke
				(width 0.15011)
				(type solid)
			)
			(layer "F.SilkS")
		)
		(fp_line
			(start -1.40005 -21.2499)
			(end -1.40005 -20.69999)
			(stroke
				(width 0.15011)
				(type solid)
			)
			(layer "F.SilkS")
		)
		(fp_line
			(start 1.99999 -20.69999)
			(end 1.99999 -20.03298)
			(stroke
				(width 0.15011)
				(type solid)
			)
			(layer "F.SilkS")
		)
		(fp_line
			(start 1.40004 -20.69999)
			(end 1.99999 -20.69999)
			(stroke
				(width 0.15011)
				(type solid)
			)
			(layer "F.SilkS")
		)
		(fp_line
			(start -2 -20.69999)
			(end -1.40005 -20.69999)
			(stroke
				(width 0.15011)
				(type solid)
			)
			(layer "F.SilkS")
		)
		(fp_line
			(start -2 -20.69999)
			(end -2 -20.03298)
			(stroke
				(width 0.15011)
				(type solid)
			)
			(layer "F.SilkS")
		)
		(fp_line
			(start 1.99999 0.03302)
			(end 1.99999 0.70002)
			(stroke
				(width 0.15011)
				(type solid)
			)
			(layer "F.SilkS")
		)
		(fp_line
			(start -2 0.03302)
			(end -2 0.70002)
			(stroke
				(width 0.15011)
				(type solid)
			)
			(layer "F.SilkS")
		)
		(fp_line
			(start 1.40004 0.70002)
			(end 1.99999 0.70002)
			(stroke
				(width 0.15011)
				(type solid)
			)
			(layer "F.SilkS")
		)
		(fp_line
			(start 1.40004 0.70002)
			(end 1.40004 1.24993)
			(stroke
				(width 0.15011)
				(type solid)
			)
			(layer "F.SilkS")
		)
		(fp_line
			(start -1.40005 0.70002)
			(end -1.40005 1.24993)
			(stroke
				(width 0.15011)
				(type solid)
			)
			(layer "F.SilkS")
		)
		(fp_line
			(start -2 0.70002)
			(end -1.40005 0.70002)
			(stroke
				(width 0.15011)
				(type solid)
			)
			(layer "F.SilkS")
		)
		(fp_line
			(start -1.40005 1.24993)
			(end 1.40004 1.24993)
			(stroke
				(width 0.15011)
				(type solid)
			)
			(layer "F.SilkS")
		)
		(fp_circle
			(center 3.5052 -0.22454)
			(end 3.70535 -0.22454)
			(stroke
				(width 0.40005)
				(type solid)
			)
			(fill no)
			(layer "F.SilkS")
		)
		(pad "1" smd rect
			(at 2.02488 -0.24994 90)
			(size 1.54991 0.24994)
			(layers "F.Cu" "F.Mask" "F.Paste")
		)
		(pad "2" smd rect
			(at -2.02489 -0.24994 90)
			(size 1.54991 0.24994)
			(layers "F.Cu" "F.Mask" "F.Paste")
		)
		(pad "3" smd rect
			(at 2.02488 -0.75006 90)
			(size 1.54991 0.24994)
			(layers "F.Cu" "F.Mask" "F.Paste")
		)
		(pad "4" smd rect
			(at -2.02489 -0.75006 90)
			(size 1.54991 0.24994)
			(layers "F.Cu" "F.Mask" "F.Paste")
		)
		(pad "5" smd rect
			(at 2.02488 -1.24994 90)
			(size 1.54991 0.24994)
			(layers "F.Cu" "F.Mask" "F.Paste")
		)
		(pad "6" smd rect
			(at -2.02489 -1.24994 90)
			(size 1.54991 0.24994)
			(layers "F.Cu" "F.Mask" "F.Paste")
		)
		(pad "7" smd rect
			(at 2.02488 -1.75006 90)
			(size 1.54991 0.24994)
			(layers "F.Cu" "F.Mask" "F.Paste")
		)
		(pad "8" smd rect
			(at -2.02489 -1.75006 90)
			(size 1.54991 0.24994)
			(layers "F.Cu" "F.Mask" "F.Paste")
		)
		(pad "9" smd rect
			(at 2.02488 -2.24993 90)
			(size 1.54991 0.24994)
			(layers "F.Cu" "F.Mask" "F.Paste")
			(net "GND")
		)
		(pad "10" smd rect
			(at -2.02489 -2.24993 90)
			(size 1.54991 0.24994)
			(layers "F.Cu" "F.Mask" "F.Paste")
			(net "GND")
		)
		(pad "11" smd rect
			(at 2.02488 -2.75006 90)
			(size 1.54991 0.24994)
			(layers "F.Cu" "F.Mask" "F.Paste")
		)
		(pad "12" smd rect
			(at -2.02489 -2.75006 90)
			(size 1.54991 0.24994)
			(layers "F.Cu" "F.Mask" "F.Paste")
			(net "PCIE_TX2_P")
		)
		(pad "13" smd rect
			(at 2.02488 -3.24993 90)
			(size 1.54991 0.24994)
			(layers "F.Cu" "F.Mask" "F.Paste")
		)
		(pad "14" smd rect
			(at -2.02489 -3.24993 90)
			(size 1.54991 0.24994)
			(layers "F.Cu" "F.Mask" "F.Paste")
			(net "PCIE_TX2_N")
		)
		(pad "15" smd rect
			(at 2.02488 -3.75006 90)
			(size 1.54991 0.24994)
			(layers "F.Cu" "F.Mask" "F.Paste")
			(net "GND")
		)
		(pad "16" smd rect
			(at -2.02489 -3.75006 90)
			(size 1.54991 0.24994)
			(layers "F.Cu" "F.Mask" "F.Paste")
		)
		(pad "17" smd rect
			(at 2.02488 -4.24993 90)
			(size 1.54991 0.24994)
			(layers "F.Cu" "F.Mask" "F.Paste")
			(net "PCIE_TX3_P")
		)
		(pad "18" smd rect
			(at -2.02489 -4.24993 90)
			(size 1.54991 0.24994)
			(layers "F.Cu" "F.Mask" "F.Paste")
			(net "PCIE_RX2_P")
		)
		(pad "19" smd rect
			(at 2.02488 -4.75006 90)
			(size 1.54991 0.24994)
			(layers "F.Cu" "F.Mask" "F.Paste")
			(net "PCIE_TX3_N")
		)
		(pad "20" smd rect
			(at -2.02489 -4.75006 90)
			(size 1.54991 0.24994)
			(layers "F.Cu" "F.Mask" "F.Paste")
			(net "PCIE_RX2_N")
		)
		(pad "21" smd rect
			(at 2.02488 -5.24993 90)
			(size 1.54991 0.24994)
			(layers "F.Cu" "F.Mask" "F.Paste")
			(net "GND")
		)
		(pad "22" smd rect
			(at -2.02489 -5.24993 90)
			(size 1.54991 0.24994)
			(layers "F.Cu" "F.Mask" "F.Paste")
		)
		(pad "23" smd rect
			(at 2.02488 -5.75005 90)
			(size 1.54991 0.24994)
			(layers "F.Cu" "F.Mask" "F.Paste")
			(net "PCIE_RX3_P")
		)
		(pad "24" smd rect
			(at -2.02489 -5.75005 90)
			(size 1.54991 0.24994)
			(layers "F.Cu" "F.Mask" "F.Paste")
			(net "PCIE_TX1_P")
		)
		(pad "25" smd rect
			(at 2.02488 -6.24993 90)
			(size 1.54991 0.24994)
			(layers "F.Cu" "F.Mask" "F.Paste")
			(net "PCIE_RX3_N")
		)
		(pad "26" smd rect
			(at -2.02489 -6.24993 90)
			(size 1.54991 0.24994)
			(layers "F.Cu" "F.Mask" "F.Paste")
			(net "PCIE_TX1_N")
		)
		(pad "27" smd rect
			(at 2.02488 -6.75005 90)
			(size 1.54991 0.24994)
			(layers "F.Cu" "F.Mask" "F.Paste")
			(net "GND")
		)
		(pad "28" smd rect
			(at -2.02489 -6.75005 90)
			(size 1.54991 0.24994)
			(layers "F.Cu" "F.Mask" "F.Paste")
		)
		(pad "29" smd rect
			(at 2.02488 -7.24992 90)
			(size 1.54991 0.24994)
			(layers "F.Cu" "F.Mask" "F.Paste")
			(net "PCIE_TX0_P")
		)
		(pad "30" smd rect
			(at -2.02489 -7.24992 90)
			(size 1.54991 0.24994)
			(layers "F.Cu" "F.Mask" "F.Paste")
			(net "PCIE_RX1_P")
		)
		(pad "31" smd rect
			(at 2.02488 -7.75005 90)
			(size 1.54991 0.24994)
			(layers "F.Cu" "F.Mask" "F.Paste")
			(net "PCIE_TX0_N")
		)
		(pad "32" smd rect
			(at -2.02489 -7.75005 90)
			(size 1.54991 0.24994)
			(layers "F.Cu" "F.Mask" "F.Paste")
			(net "PCIE_RX1_N")
		)
		(pad "33" smd rect
			(at 2.02488 -8.24992 90)
			(size 1.54991 0.24994)
			(layers "F.Cu" "F.Mask" "F.Paste")
			(net "GND")
		)
		(pad "34" smd rect
			(at -2.02489 -8.24992 90)
			(size 1.54991 0.24994)
			(layers "F.Cu" "F.Mask" "F.Paste")
		)
		(pad "35" smd rect
			(at 2.02488 -8.75005 90)
			(size 1.54991 0.24994)
			(layers "F.Cu" "F.Mask" "F.Paste")
			(net "PCIE_RX0_P")
		)
		(pad "36" smd rect
			(at -2.02489 -8.75005 90)
			(size 1.54991 0.24994)
			(layers "F.Cu" "F.Mask" "F.Paste")
			(net "PCIE_CLK_P")
		)
		(pad "37" smd rect
			(at 2.02488 -9.24992 90)
			(size 1.54991 0.24994)
			(layers "F.Cu" "F.Mask" "F.Paste")
			(net "PCIE_RX0_N")
		)
		(pad "38" smd rect
			(at -2.02489 -9.24992 90)
			(size 1.54991 0.24994)
			(layers "F.Cu" "F.Mask" "F.Paste")
			(net "PCIE_CLK_N")
		)
		(pad "39" smd rect
			(at 2.02488 -9.75005 90)
			(size 1.54991 0.24994)
			(layers "F.Cu" "F.Mask" "F.Paste")
			(net "GND")
		)
		(pad "40" smd rect
			(at -2.02489 -9.75005 90)
			(size 1.54991 0.24994)
			(layers "F.Cu" "F.Mask" "F.Paste")
			(net "GND")
		)
		(pad "41" smd rect
			(at 2.02488 -10.24992 90)
			(size 1.54991 0.24994)
			(layers "F.Cu" "F.Mask" "F.Paste")
		)
		(pad "42" smd rect
			(at -2.02489 -10.24992 90)
			(size 1.54991 0.24994)
			(layers "F.Cu" "F.Mask" "F.Paste")
		)
		(pad "43" smd rect
			(at 2.02488 -10.75004 90)
			(size 1.54991 0.24994)
			(layers "F.Cu" "F.Mask" "F.Paste")
		)
		(pad "44" smd rect
			(at -2.02489 -10.75004 90)
			(size 1.54991 0.24994)
			(layers "F.Cu" "F.Mask" "F.Paste")
		)
		(pad "45" smd rect
			(at 2.02488 -11.24992 90)
			(size 1.54991 0.24994)
			(layers "F.Cu" "F.Mask" "F.Paste")
		)
		(pad "46" smd rect
			(at -2.02489 -11.24992 90)
			(size 1.54991 0.24994)
			(layers "F.Cu" "F.Mask" "F.Paste")
		)
		(pad "47" smd rect
			(at 2.02488 -11.75004 90)
			(size 1.54991 0.24994)
			(layers "F.Cu" "F.Mask" "F.Paste")
		)
		(pad "48" smd rect
			(at -2.02489 -11.75004 90)
			(size 1.54991 0.24994)
			(layers "F.Cu" "F.Mask" "F.Paste")
		)
		(pad "49" smd rect
			(at 2.02488 -12.24991 90)
			(size 1.54991 0.24994)
			(layers "F.Cu" "F.Mask" "F.Paste")
			(net "GND")
		)
		(pad "50" smd rect
			(at -2.02489 -12.24991 90)
			(size 1.54991 0.24994)
			(layers "F.Cu" "F.Mask" "F.Paste")
			(net "GND")
		)
		(pad "51" smd rect
			(at 2.02488 -12.75004 90)
			(size 1.54991 0.24994)
			(layers "F.Cu" "F.Mask" "F.Paste")
		)
		(pad "52" smd rect
			(at -2.02489 -12.75004 90)
			(size 1.54991 0.24994)
			(layers "F.Cu" "F.Mask" "F.Paste")
		)
		(pad "53" smd rect
			(at 2.02488 -13.24991 90)
			(size 1.54991 0.24994)
			(layers "F.Cu" "F.Mask" "F.Paste")
		)
		(pad "54" smd rect
			(at -2.02489 -13.24991 90)
			(size 1.54991 0.24994)
			(layers "F.Cu" "F.Mask" "F.Paste")
		)
		(pad "55" smd rect
			(at 2.02488 -13.75004 90)
			(size 1.54991 0.24994)
			(layers "F.Cu" "F.Mask" "F.Paste")
		)
		(pad "56" smd rect
			(at -2.02489 -13.75004 90)
			(size 1.54991 0.24994)
			(layers "F.Cu" "F.Mask" "F.Paste")
		)
		(pad "57" smd rect
			(at 2.02488 -14.24991 90)
			(size 1.54991 0.24994)
			(layers "F.Cu" "F.Mask" "F.Paste")
		)
		(pad "58" smd rect
			(at -2.02489 -14.24991 90)
			(size 1.54991 0.24994)
			(layers "F.Cu" "F.Mask" "F.Paste")
		)
		(pad "59" smd rect
			(at 2.02488 -14.75004 90)
			(size 1.54991 0.24994)
			(layers "F.Cu" "F.Mask" "F.Paste")
			(net "GND")
		)
		(pad "60" smd rect
			(at -2.02489 -14.75004 90)
			(size 1.54991 0.24994)
			(layers "F.Cu" "F.Mask" "F.Paste")
			(net "GND")
		)
		(pad "61" smd rect
			(at 2.02488 -15.24991 90)
			(size 1.54991 0.24994)
			(layers "F.Cu" "F.Mask" "F.Paste")
		)
		(pad "62" smd rect
			(at -2.02489 -15.24991 90)
			(size 1.54991 0.24994)
			(layers "F.Cu" "F.Mask" "F.Paste")
		)
		(pad "63" smd rect
			(at 2.02488 -15.75003 90)
			(size 1.54991 0.24994)
			(layers "F.Cu" "F.Mask" "F.Paste")
		)
		(pad "64" smd rect
			(at -2.02489 -15.75003 90)
			(size 1.54991 0.24994)
			(layers "F.Cu" "F.Mask" "F.Paste")
		)
		(pad "65" smd rect
			(at 2.02488 -16.24991 90)
			(size 1.54991 0.24994)
			(layers "F.Cu" "F.Mask" "F.Paste")
		)
		(pad "66" smd rect
			(at -2.02489 -16.24991 90)
			(size 1.54991 0.24994)
			(layers "F.Cu" "F.Mask" "F.Paste")
		)
		(pad "67" smd rect
			(at 2.02488 -16.75003 90)
			(size 1.54991 0.24994)
			(layers "F.Cu" "F.Mask" "F.Paste")
		)
		(pad "68" smd rect
			(at -2.02489 -16.75003 90)
			(size 1.54991 0.24994)
			(layers "F.Cu" "F.Mask" "F.Paste")
		)
		(pad "69" smd rect
			(at 2.02488 -17.2499 90)
			(size 1.54991 0.24994)
			(layers "F.Cu" "F.Mask" "F.Paste")
			(net "GND")
		)
		(pad "70" smd rect
			(at -2.02489 -17.2499 90)
			(size 1.54991 0.24994)
			(layers "F.Cu" "F.Mask" "F.Paste")
			(net "GND")
		)
		(pad "71" smd rect
			(at 2.02488 -17.75003 90)
			(size 1.54991 0.24994)
			(layers "F.Cu" "F.Mask" "F.Paste")
		)
		(pad "72" smd rect
			(at -2.02489 -17.75003 90)
			(size 1.54991 0.24994)
			(layers "F.Cu" "F.Mask" "F.Paste")
		)
		(pad "73" smd rect
			(at 2.02488 -18.2499 90)
			(size 1.54991 0.24994)
			(layers "F.Cu" "F.Mask" "F.Paste")
		)
		(pad "74" smd rect
			(at -2.02489 -18.2499 90)
			(size 1.54991 0.24994)
			(layers "F.Cu" "F.Mask" "F.Paste")
		)
		(pad "75" smd rect
			(at 2.02488 -18.75003 90)
			(size 1.54991 0.24994)
			(layers "F.Cu" "F.Mask" "F.Paste")
		)
		(pad "76" smd rect
			(at -2.02489 -18.75003 90)
			(size 1.54991 0.24994)
			(layers "F.Cu" "F.Mask" "F.Paste")
		)
		(pad "77" smd rect
			(at 2.02488 -19.2499 90)
			(size 1.54991 0.24994)
			(layers "F.Cu" "F.Mask" "F.Paste")
		)
		(pad "78" smd rect
			(at -2.02489 -19.2499 90)
			(size 1.54991 0.24994)
			(layers "F.Cu" "F.Mask" "F.Paste")
		)
		(pad "79" smd rect
			(at 2.02488 -19.75003 90)
			(size 1.54991 0.24994)
			(layers "F.Cu" "F.Mask" "F.Paste")
		)
		(pad "80" smd rect
			(at -2.02489 -19.75003 90)
			(size 1.54991 0.24994)
			(layers "F.Cu" "F.Mask" "F.Paste")
		)
		(pad "81" smd rect
			(at 0.01135 1.17626 90)
			(size 1.70002 1.35001)
			(layers "F.Cu" "F.Mask" "F.Paste")
		)
		(pad "82" thru_hole circle
			(at 0 0 90)
			(size 0.55016 0.55016)
			(drill 0.55016)
			(layers "*.Cu" "*.Mask")
			(remove_unused_layers no)
			(thermal_bridge_angle 90)
		)
		(pad "83" thru_hole circle
			(at 0 -19.99996 90)
			(size 0.55016 0.55016)
			(drill 0.55016)
			(layers "*.Cu" "*.Mask")
			(remove_unused_layers no)
			(thermal_bridge_angle 90)
		)
		(pad "84" smd rect
			(at 0.01135 -21.17374 90)
			(size 1.70002 1.35001)
			(layers "F.Cu" "F.Mask" "F.Paste")
		)
	)
	(footprint "Vault:CAPC1608X87X45ML20T05"
		(layer "F.Cu")
		(at 227.5761 67.8286)
		(property "Reference" "C37"
			(at -2.9714 0.276921 0)
			(unlocked yes)
			(layer "F.SilkS")
			(effects
				(font
					(size 0.762 0.762)
					(thickness 0.2286)
				)
			)
		)
		(property "Value" "0.1uF"
			(at 2.09443 2.657602 0)
			(unlocked yes)
			(layer "F.SilkS")
			(hide yes)
			(effects
				(font
					(size 1.524 1.524)
					(thickness 0.254)
				)
			)
		)
		(sheetname "GPS_IMU_SENSORS")
		(sheetfile "GPS_IMU_SENSORS.kicad_sch")
		(duplicate_pad_numbers_are_jumpers no)
		(pad "1" smd rect
			(at -0.7 0 90)
			(size 1.1 1.05)
			(layers "F.Cu" "F.Mask" "F.Paste")
			(net "GND")
		)
		(pad "2" smd rect
			(at 0.7 0 90)
			(size 1.1 1.05)
			(layers "F.Cu" "F.Mask" "F.Paste")
			(net "+5.0V")
		)
	)
	(footprint "Vault:FP-MK212BG-MFG"
		(layer "F.Cu")
		(at 85.8761 79.0786 -90)
		(property "Reference" "C60"
			(at 1.5 -4.593345 90)
			(unlocked yes)
			(layer "F.SilkS")
			(effects
				(font
					(size 0.762 0.762)
					(thickness 0.2286)
				)
				(justify left bottom)
			)
		)
		(property "Value" "10uF"
			(at 3.52679 1.5875 0)
			(unlocked yes)
			(layer "F.SilkS")
			(hide yes)
			(effects
				(font
					(size 1.524 1.524)
					(thickness 0.254)
				)
				(justify left bottom)
			)
		)
		(sheetname "GPS_IMU_SENSORS")
		(sheetfile "GPS_IMU_SENSORS.kicad_sch")
		(duplicate_pad_numbers_are_jumpers no)
		(fp_line
			(start 0.125 0.725)
			(end -0.125 0.725)
			(stroke
				(width 0.2)
				(type solid)
			)
			(layer "F.SilkS")
		)
		(fp_line
			(start 0.125 -0.725)
			(end -0.125 -0.725)
			(stroke
				(width 0.2)
				(type solid)
			)
			(layer "F.SilkS")
		)
		(fp_line
			(start -1.6 0.825)
			(end -1.6 -0.825)
			(stroke
				(width 0.2)
				(type solid)
			)
			(layer "F.CrtYd")
		)
		(fp_line
			(start 1.6 0.825)
			(end -1.6 0.825)
			(stroke
				(width 0.2)
				(type solid)
			)
			(layer "F.CrtYd")
		)
		(fp_line
			(start 1.6 0.825)
			(end 1.6 -0.825)
			(stroke
				(width 0.2)
				(type solid)
			)
			(layer "F.CrtYd")
		)
		(fp_line
			(start 1.6 -0.825)
			(end -1.6 -0.825)
			(stroke
				(width 0.2)
				(type solid)
			)
			(layer "F.CrtYd")
		)
		(fp_line
			(start -1.6 0.825)
			(end -1.6 -0.825)
			(stroke
				(width 0.2)
				(type solid)
			)
			(layer "F.Fab")
		)
		(fp_line
			(start 1.6 0.825)
			(end -1.6 0.825)
			(stroke
				(width 0.2)
				(type solid)
			)
			(layer "F.Fab")
		)
		(fp_line
			(start 1.6 0.825)
			(end 1.6 -0.825)
			(stroke
				(width 0.2)
				(type solid)
			)
			(layer "F.Fab")
		)
		(fp_line
			(start 0 0.5)
			(end 0 -0.5)
			(stroke
				(width 0.1)
				(type solid)
			)
			(layer "F.Fab")
		)
		(fp_line
			(start 0.5 0)
			(end -0.5 0)
			(stroke
				(width 0.1)
				(type solid)
			)
			(layer "F.Fab")
		)
		(fp_line
			(start 1.6 -0.825)
			(end -1.6 -0.825)
			(stroke
				(width 0.2)
				(type solid)
			)
			(layer "F.Fab")
		)
		(fp_text user "${REFERENCE}"
			(at -0.00001 0.09601 270)
			(unlocked yes)
			(layer "F.Fab")
			(effects
				(font
					(face "Arial")
					(size 0.63 0.63)
					(thickness 0.1)
				)
				(justify left bottom)
			)
		)
		(pad "1" smd rect
			(at -1 0 270)
			(size 1 1.25)
			(layers "F.Cu" "F.Mask" "F.Paste")
			(net "+5.0V")
			(solder_mask_margin 0)
			(solder_paste_margin 0)
		)
		(pad "2" smd rect
			(at 1 0 270)
			(size 1 1.25)
			(layers "F.Cu" "F.Mask" "F.Paste")
			(net "GND")
			(solder_mask_margin 0)
			(solder_paste_margin 0)
		)
	)
	(footprint "Capacitors:CAPC2012X14N"
		(layer "F.Cu")
		(at 153.9261 80.6162 90)
		(property "Reference" "C62"
			(at 1.3 1.406655 270)
			(unlocked yes)
			(layer "F.SilkS")
			(effects
				(font
					(size 0.762 0.762)
					(thickness 0.2286)
				)
				(justify left bottom)
			)
		)
		(property "Value" "CAP_0805_10UF_25V"
			(at -2.52679 -1.7875 0)
			(unlocked yes)
			(layer "F.SilkS")
			(hide yes)
			(effects
				(font
					(size 1.524 1.524)
					(thickness 0.254)
				)
				(justify left bottom)
			)
		)
		(sheetname "MAC")
		(sheetfile "MAC.kicad_sch")
		(duplicate_pad_numbers_are_jumpers no)
		(fp_line
			(start -0.762 -0.9652)
			(end 0.762 -0.9652)
			(stroke
				(width 0.1524)
				(type solid)
			)
			(layer "F.SilkS")
		)
		(fp_line
			(start -0.762 0.9652)
			(end 0.762 0.9652)
			(stroke
				(width 0.1524)
				(type solid)
			)
			(layer "F.SilkS")
		)
		(pad "1" smd rect
			(at -0.9 0 180)
			(size 1.45 1.15)
			(layers "F.Cu" "F.Mask" "F.Paste")
			(net "MAC_VCC")
		)
		(pad "2" smd rect
			(at 0.9 0 180)
			(size 1.45 1.15)
			(layers "F.Cu" "F.Mask" "F.Paste")
			(net "GND")
		)
	)
	(footprint "Vault:CAPC1608X87X45ML20T05"
		(layer "F.Cu")
		(at 84.1261 87.1162 90)
		(property "Reference" "C40"
			(at 0.4786 -3.473069 90)
			(unlocked yes)
			(layer "F.SilkS")
			(effects
				(font
					(size 0.762 0.762)
					(thickness 0.2286)
				)
			)
		)
		(property "Value" "0.1uF"
			(at 2.09443 2.657602 90)
			(unlocked yes)
			(layer "F.SilkS")
			(hide yes)
			(effects
				(font
					(size 1.524 1.524)
					(thickness 0.254)
				)
			)
		)
		(sheetname "USER_IO_STATUS")
		(sheetfile "USER_IO_STATUS.kicad_sch")
		(duplicate_pad_numbers_are_jumpers no)
		(pad "1" smd rect
			(at -0.7 0 180)
			(size 1.1 1.05)
			(layers "F.Cu" "F.Mask" "F.Paste")
			(net "GND")
		)
		(pad "2" smd rect
			(at 0.7 0 180)
			(size 1.1 1.05)
			(layers "F.Cu" "F.Mask" "F.Paste")
			(net "+3.3V")
		)
	)
	(footprint "Vault:CAPC1608X87X45ML20T05"
		(layer "F.Cu")
		(at 151.54502 80.89267 -90)
		(property "Reference" "C63"
			(at 0.62353 1.525575 90)
			(unlocked yes)
			(layer "F.SilkS")
			(effects
				(font
					(size 0.762 0.762)
					(thickness 0.2286)
				)
				(justify left bottom)
			)
		)
		(property "Value" "0.1uF"
			(at 1.92305 -4.27006 0)
			(unlocked yes)
			(layer "F.SilkS")
			(hide yes)
			(effects
				(font
					(size 1.524 1.524)
					(thickness 0.254)
				)
				(justify left bottom)
			)
		)
		(sheetname "MAC")
		(sheetfile "MAC.kicad_sch")
		(duplicate_pad_numbers_are_jumpers no)
		(pad "1" smd rect
			(at -0.7 0)
			(size 1.1 1.05)
			(layers "F.Cu" "F.Mask" "F.Paste")
			(net "GND")
		)
		(pad "2" smd rect
			(at 0.7 0)
			(size 1.1 1.05)
			(layers "F.Cu" "F.Mask" "F.Paste")
			(net "MAC_VCC")
		)
	)
	(footprint "Resistors:RESC2012X50N"
		(layer "F.Cu")
		(at 199.41136 139.37763)
		(property "Reference" "R18"
			(at -0.68526 -1.068085 0)
			(unlocked yes)
			(layer "F.SilkS")
			(effects
				(font
					(size 0.762 0.762)
					(thickness 0.2286)
				)
				(justify left bottom)
			)
		)
		(property "Value" "CRCW080533R0FKEA"
			(at -5.5249 -8.83582 0)
			(unlocked yes)
			(layer "F.SilkS")
			(hide yes)
			(effects
				(font
					(size 1.524 1.524)
					(thickness 0.254)
				)
				(justify left bottom)
			)
		)
		(sheetname "PCIe_JTAG")
		(sheetfile "PCIe_JTAG.kicad_sch")
		(duplicate_pad_numbers_are_jumpers no)
		(fp_line
			(start 0 0.762)
			(end 0 -0.762)
			(stroke
				(width 0.1524)
				(type solid)
			)
			(layer "F.SilkS")
		)
		(pad "1" smd rect
			(at -1 0 90)
			(size 1.45 0.95)
			(layers "F.Cu" "F.Mask" "F.Paste")
			(net "FPGA_TCK")
		)
		(pad "2" smd rect
			(at 1 0 90)
			(size 1.45 0.95)
			(layers "F.Cu" "F.Mask" "F.Paste")
			(net "NetR18_2")
		)
	)
	(footprint "Vault:M08A_L"
		(layer "F.Cu")
		(at 118.6261 86.0786)
		(property "Reference" "U4"
			(at 2.128595 -3.135469 0)
			(unlocked yes)
			(layer "F.SilkS")
			(effects
				(font
					(size 0.762 0.762)
					(thickness 0.2286)
				)
			)
		)
		(property "Value" "DS90LV028AQMA"
			(at 6.74058 4.207002 0)
			(unlocked yes)
			(layer "F.SilkS")
			(hide yes)
			(effects
				(font
					(size 1.524 1.524)
					(thickness 0.254)
				)
			)
		)
		(sheetname "MAC")
		(sheetfile "MAC.kicad_sch")
		(duplicate_pad_numbers_are_jumpers no)
		(fp_line
			(start -1 -2.5)
			(end 1 -2.5)
			(stroke
				(width 0.2)
				(type solid)
			)
			(layer "F.SilkS")
		)
		(fp_line
			(start -1 2.5)
			(end -1 -2.5)
			(stroke
				(width 0.2)
				(type solid)
			)
			(layer "F.SilkS")
		)
		(fp_line
			(start -1 2.5)
			(end 1 2.5)
			(stroke
				(width 0.2)
				(type solid)
			)
			(layer "F.SilkS")
		)
		(fp_line
			(start 1 2.5)
			(end 1 -2.5)
			(stroke
				(width 0.2)
				(type solid)
			)
			(layer "F.SilkS")
		)
		(fp_circle
			(center -2.35 -2.755)
			(end -2.35 -2.88)
			(stroke
				(width 0.25)
				(type solid)
			)
			(fill no)
			(layer "F.SilkS")
		)
		(fp_circle
			(center -0.2 -1.7)
			(end -0.2 -1.9)
			(stroke
				(width 0.4)
				(type solid)
			)
			(fill no)
			(layer "F.SilkS")
		)
		(pad "1" smd oval
			(at -2.35 -1.905 90)
			(size 0.6 1.9)
			(layers "F.Cu" "F.Mask" "F.Paste")
			(net "MAC_PPS_OUT-")
		)
		(pad "2" smd oval
			(at -2.35 -0.635 90)
			(size 0.6 1.9)
			(layers "F.Cu" "F.Mask" "F.Paste")
			(net "MAC_PPS_OUT+")
		)
		(pad "3" smd oval
			(at -2.35 0.635 90)
			(size 0.6 1.9)
			(layers "F.Cu" "F.Mask" "F.Paste")
		)
		(pad "4" smd oval
			(at -2.35 1.905 90)
			(size 0.6 1.9)
			(layers "F.Cu" "F.Mask" "F.Paste")
		)
		(pad "5" smd oval
			(at 2.35 1.905 90)
			(size 0.6 1.9)
			(layers "F.Cu" "F.Mask" "F.Paste")
			(net "GND")
		)
		(pad "6" smd oval
			(at 2.35 0.635 90)
			(size 0.6 1.9)
			(layers "F.Cu" "F.Mask" "F.Paste")
		)
		(pad "7" smd oval
			(at 2.35 -0.635 90)
			(size 0.6 1.9)
			(layers "F.Cu" "F.Mask" "F.Paste")
			(net "NetR13_1")
		)
		(pad "8" smd oval
			(at 2.35 -1.905 90)
			(size 0.6 1.9)
			(layers "F.Cu" "F.Mask" "F.Paste")
			(net "+3.3V")
		)
	)
	(footprint "SA53:SA53_Header"
		(layer "F.Cu")
		(at 142.66107 112.99691 180)
		(property "Reference" "J31"
			(at 3.071485 -8.827838 180)
			(unlocked yes)
			(layer "F.SilkS")
			(effects
				(font
					(size 1.524 1.524)
					(thickness 0.254)
				)
			)
		)
		(property "Value" "SA53_Header"
			(at 7.680915 4.511792 180)
			(unlocked yes)
			(layer "F.SilkS")
			(hide yes)
			(effects
				(font
					(size 1.524 1.524)
					(thickness 0.254)
				)
			)
		)
		(sheetname "MAC")
		(sheetfile "MAC.kicad_sch")
		(duplicate_pad_numbers_are_jumpers no)
		(fp_circle
			(center 6.42 0.07199)
			(end 6.42 0.19899)
			(stroke
				(width 0.254)
				(type solid)
			)
			(fill no)
			(layer "F.SilkS")
		)
		(pad "1" smd rect
			(at 5 0.07199 270)
			(size 0.25 1.8)
			(layers "F.Cu" "F.Mask" "F.Paste")
			(net "MAC_PPS_IN1+")
		)
		(pad "2" smd rect
			(at 1 0.07199 270)
			(size 0.25 1.8)
			(layers "F.Cu" "F.Mask" "F.Paste")
			(net "MAC_USB+")
		)
		(pad "3" smd rect
			(at 5 -0.43601 270)
			(size 0.25 1.8)
			(layers "F.Cu" "F.Mask" "F.Paste")
			(net "MAC_PPS_IN1-")
		)
		(pad "4" smd rect
			(at 1 -0.43601 270)
			(size 0.25 1.8)
			(layers "F.Cu" "F.Mask" "F.Paste")
			(net "MAC_USB-")
		)
		(pad "5" smd rect
			(at 5 -0.94401 270)
			(size 0.25 1.8)
			(layers "F.Cu" "F.Mask" "F.Paste")
			(net "MAC_PPS_IN0+")
		)
		(pad "6" smd rect
			(at 1 -0.94401 270)
			(size 0.25 1.8)
			(layers "F.Cu" "F.Mask" "F.Paste")
			(net "MAC_USB_PWR")
		)
		(pad "7" smd rect
			(at 5 -1.45201 270)
			(size 0.25 1.8)
			(layers "F.Cu" "F.Mask" "F.Paste")
			(net "MAC_PPS_IN0-")
		)
		(pad "8" smd rect
			(at 1 -1.45201 270)
			(size 0.25 1.8)
			(layers "F.Cu" "F.Mask" "F.Paste")
			(net "GND")
		)
		(pad "9" smd rect
			(at 5 -1.96001 270)
			(size 0.25 1.8)
			(layers "F.Cu" "F.Mask" "F.Paste")
			(net "GND")
		)
		(pad "10" smd rect
			(at 1 -1.96001 270)
			(size 0.25 1.8)
			(layers "F.Cu" "F.Mask" "F.Paste")
		)
		(pad "11" smd rect
			(at 5 -2.46801 270)
			(size 0.25 1.8)
			(layers "F.Cu" "F.Mask" "F.Paste")
		)
		(pad "12" smd rect
			(at 1 -2.46801 270)
			(size 0.25 1.8)
			(layers "F.Cu" "F.Mask" "F.Paste")
		)
		(pad "13" smd rect
			(at 5 -2.97601 270)
			(size 0.25 1.8)
			(layers "F.Cu" "F.Mask" "F.Paste")
		)
		(pad "14" smd rect
			(at 1 -2.97601 270)
			(size 0.25 1.8)
			(layers "F.Cu" "F.Mask" "F.Paste")
		)
		(pad "15" smd rect
			(at 5 -3.48401 270)
			(size 0.25 1.8)
			(layers "F.Cu" "F.Mask" "F.Paste")
			(net "GND")
		)
		(pad "16" smd rect
			(at 1 -3.48401 270)
			(size 0.25 1.8)
			(layers "F.Cu" "F.Mask" "F.Paste")
		)
		(pad "17" smd rect
			(at 5 -3.99201 270)
			(size 0.25 1.8)
			(layers "F.Cu" "F.Mask" "F.Paste")
			(net "MAC_PPS_OUT+")
		)
		(pad "18" smd rect
			(at 1 -3.99201 270)
			(size 0.25 1.8)
			(layers "F.Cu" "F.Mask" "F.Paste")
		)
		(pad "19" smd rect
			(at 5 -4.50001 270)
			(size 0.25 1.8)
			(layers "F.Cu" "F.Mask" "F.Paste")
			(net "MAC_PPS_OUT-")
		)
		(pad "20" smd rect
			(at 1 -4.50001 270)
			(size 0.25 1.8)
			(layers "F.Cu" "F.Mask" "F.Paste")
			(net "MAC_ALARM")
		)
		(zone
			(layer "F.Cu")
			(hatch edge 0.5)
			(connect_pads
				(clearance 0)
			)
			(min_thickness 0.25)
			(keepout
				(tracks allowed)
				(vias allowed)
				(pads allowed)
				(copperpour not_allowed)
				(footprints allowed)
			)
			(placement
				(enabled no)
				(sheetname "")
			)
			(fill
				(thermal_gap 0.5)
				(thermal_bridge_width 0.5)
				(island_removal_mode 0)
			)
			(polygon
				(pts
					(xy 135.99358 120.0662) (xy 135.99359 110.0662) (xy 143.49359 110.0662) (xy 143.49358 120.0662)
				)
			)
		)
	)
	(footprint "Vault:SMTC-TLE-104-01-X-DV"
		(layer "F.Cu")
		(at 225.63905 61.67859 -90)
		(property "Reference" "J13"
			(at -5.408538 1.758945 0)
			(unlocked yes)
			(layer "F.SilkS")
			(effects
				(font
					(size 1.524 1.524)
					(thickness 0.254)
				)
			)
		)
		(property "Value" "GNSS Header"
			(at 6.765575 4.994402 270)
			(unlocked yes)
			(layer "F.SilkS")
			(hide yes)
			(effects
				(font
					(size 1.524 1.524)
					(thickness 0.254)
				)
			)
		)
		(sheetname "GPS_IMU_SENSORS")
		(sheetfile "GPS_IMU_SENSORS.kicad_sch")
		(duplicate_pad_numbers_are_jumpers no)
		(fp_line
			(start -4.06499 2)
			(end -4.06499 -2)
			(stroke
				(width 0.2)
				(type solid)
			)
			(layer "F.SilkS")
		)
		(fp_line
			(start -3.95899 2)
			(end -4.06499 2)
			(stroke
				(width 0.2)
				(type solid)
			)
			(layer "F.SilkS")
		)
		(fp_line
			(start 4.065 2)
			(end 3.959 2)
			(stroke
				(width 0.2)
				(type solid)
			)
			(layer "F.SilkS")
		)
		(fp_line
			(start 4.065 2)
			(end 4.065 -2)
			(stroke
				(width 0.2)
				(type solid)
			)
			(layer "F.SilkS")
		)
		(fp_line
			(start -3.95899 -2)
			(end -4.06499 -2)
			(stroke
				(width 0.2)
				(type solid)
			)
			(layer "F.SilkS")
		)
		(fp_line
			(start 4.065 -2)
			(end 3.959 -2)
			(stroke
				(width 0.2)
				(type solid)
			)
			(layer "F.SilkS")
		)
		(fp_circle
			(center -4.41299 -2.286)
			(end -4.53799 -2.286)
			(stroke
				(width 0.25)
				(type solid)
			)
			(fill no)
			(layer "F.SilkS")
		)
		(pad "1" smd rect
			(at -2.99999 -2.43205 270)
			(size 1.1176 1.6891)
			(layers "F.Cu" "F.Mask" "F.Paste")
			(net "+5.0V")
		)
		(pad "2" smd rect
			(at -2.99999 2.43205 270)
			(size 1.1176 1.6891)
			(layers "F.Cu" "F.Mask" "F.Paste")
			(net "+3.3V")
		)
		(pad "3" smd rect
			(at -0.99999 -2.43205 270)
			(size 1.1176 1.6891)
			(layers "F.Cu" "F.Mask" "F.Paste")
			(net "GPS2_TX")
		)
		(pad "4" smd rect
			(at -0.99999 2.43205 270)
			(size 1.1176 1.6891)
			(layers "F.Cu" "F.Mask" "F.Paste")
			(net "GPS2_RST")
		)
		(pad "5" smd rect
			(at 1 -2.43205 270)
			(size 1.1176 1.6891)
			(layers "F.Cu" "F.Mask" "F.Paste")
			(net "GPS2_RX")
		)
		(pad "6" smd rect
			(at 1 2.43205 270)
			(size 1.1176 1.6891)
			(layers "F.Cu" "F.Mask" "F.Paste")
			(net "GPS2_TP1")
		)
		(pad "7" smd rect
			(at 3 -2.43205 270)
			(size 1.1176 1.6891)
			(layers "F.Cu" "F.Mask" "F.Paste")
			(net "GPS2_TP2")
		)
		(pad "8" smd rect
			(at 3 2.43205 270)
			(size 1.1176 1.6891)
			(layers "F.Cu" "F.Mask" "F.Paste")
			(net "GND")
		)
	)
	(footprint "Capacitors:CAPC2012X14N"
		(layer "F.Cu")
		(at 221.0935 116.1792 -90)
		(property "Reference" "C13"
			(at -1.94991 -0.690055 90)
			(unlocked yes)
			(layer "F.SilkS")
			(effects
				(font
					(size 0.762 0.762)
					(thickness 0.2286)
				)
				(justify left bottom)
			)
		)
		(property "Value" "CAP_0805_10UF_25V"
			(at 6.89119 16.4599 0)
			(unlocked yes)
			(layer "F.SilkS")
			(hide yes)
			(effects
				(font
					(size 1.524 1.524)
					(thickness 0.254)
				)
				(justify left bottom)
			)
		)
		(sheetname "POWER")
		(sheetfile "POWER.kicad_sch")
		(duplicate_pad_numbers_are_jumpers no)
		(fp_line
			(start 0.762 0.9652)
			(end -0.762 0.9652)
			(stroke
				(width 0.1524)
				(type solid)
			)
			(layer "F.SilkS")
		)
		(fp_line
			(start 0.762 -0.9652)
			(end -0.762 -0.9652)
			(stroke
				(width 0.1524)
				(type solid)
			)
			(layer "F.SilkS")
		)
		(pad "1" smd rect
			(at -0.9 0)
			(size 1.45 1.15)
			(layers "F.Cu" "F.Mask" "F.Paste")
			(net "+5.0V")
		)
		(pad "2" smd rect
			(at 0.9 0)
			(size 1.45 1.15)
			(layers "F.Cu" "F.Mask" "F.Paste")
			(net "GND")
		)
	)
	(footprint "Vault:CAPC1608X87X45ML20T05"
		(layer "F.Cu")
		(at 88.1261 79.3286 90)
		(property "Reference" "C61"
			(at -1.25 3.593345 90)
			(unlocked yes)
			(layer "F.SilkS")
			(effects
				(font
					(size 0.762 0.762)
					(thickness 0.2286)
				)
				(justify left bottom)
			)
		)
		(property "Value" "0.1uF"
			(at -3.47599 -0.2921 0)
			(unlocked yes)
			(layer "F.SilkS")
			(hide yes)
			(effects
				(font
					(size 1.524 1.524)
					(thickness 0.254)
				)
				(justify left bottom)
			)
		)
		(sheetname "GPS_IMU_SENSORS")
		(sheetfile "GPS_IMU_SENSORS.kicad_sch")
		(duplicate_pad_numbers_are_jumpers no)
		(pad "1" smd rect
			(at -0.7 0 180)
			(size 1.1 1.05)
			(layers "F.Cu" "F.Mask" "F.Paste")
			(net "GND")
		)
		(pad "2" smd rect
			(at 0.7 0 180)
			(size 1.1 1.05)
			(layers "F.Cu" "F.Mask" "F.Paste")
			(net "+5.0V")
		)
	)
	(footprint "Resistors:RESC2012X50N"
		(layer "F.Cu")
		(at 199.31136 143.47763)
		(property "Reference" "R19"
			(at -1.28526 -1.268085 0)
			(unlocked yes)
			(layer "F.SilkS")
			(effects
				(font
					(size 0.762 0.762)
					(thickness 0.2286)
				)
				(justify left bottom)
			)
		)
		(property "Value" "CRCW080533R0FKEA"
			(at -3.0249 -6.33581 0)
			(unlocked yes)
			(layer "F.SilkS")
			(hide yes)
			(effects
				(font
					(size 1.524 1.524)
					(thickness 0.254)
				)
				(justify left bottom)
			)
		)
		(sheetname "PCIe_JTAG")
		(sheetfile "PCIe_JTAG.kicad_sch")
		(duplicate_pad_numbers_are_jumpers no)
		(fp_line
			(start 0 0.762)
			(end 0 -0.762)
			(stroke
				(width 0.1524)
				(type solid)
			)
			(layer "F.SilkS")
		)
		(pad "1" smd rect
			(at -1 0 90)
			(size 1.45 0.95)
			(layers "F.Cu" "F.Mask" "F.Paste")
			(net "FPGA_TDO")
		)
		(pad "2" smd rect
			(at 1 0 90)
			(size 1.45 0.95)
			(layers "F.Cu" "F.Mask" "F.Paste")
			(net "NetR19_2")
		)
	)
	(footprint "SamacSys:155124M173200"
		(layer "F.Cu")
		(at 58.4511 128.4162 90)
		(property "Reference" "D17"
			(at -0.4714 1.701931 90)
			(unlocked yes)
			(layer "F.SilkS")
			(effects
				(font
					(size 0.762 0.762)
					(thickness 0.2286)
				)
			)
		)
		(property "Value" "155124M173200"
			(at 7.1725 2.632202 90)
			(unlocked yes)
			(layer "F.SilkS")
			(hide yes)
			(effects
				(font
					(size 1.524 1.524)
					(thickness 0.254)
				)
			)
		)
		(sheetname "USER_IO_STATUS")
		(sheetfile "USER_IO_STATUS.kicad_sch")
		(duplicate_pad_numbers_are_jumpers no)
		(fp_line
			(start -0.8 0.5)
			(end 0.8 0.5)
			(stroke
				(width 0.1)
				(type solid)
			)
			(layer "F.SilkS")
		)
		(fp_arc
			(start -2 -0.1)
			(mid -1.95 -0.05)
			(end -2 0)
			(stroke
				(width 0.1)
				(type solid)
			)
			(layer "F.SilkS")
		)
		(fp_arc
			(start -2 0)
			(mid -2.05 -0.05)
			(end -2 -0.1)
			(stroke
				(width 0.1)
				(type solid)
			)
			(layer "F.SilkS")
		)
		(pad "1" smd rect
			(at -1.4 0 180)
			(size 0.9 0.6)
			(layers "F.Cu" "F.Mask" "F.Paste")
			(net "+3.3V")
		)
		(pad "2" smd rect
			(at -0.45 -0.325 90)
			(size 0.6 0.55)
			(layers "F.Cu" "F.Mask" "F.Paste")
			(net "NetD17_2")
		)
		(pad "3" smd rect
			(at 0.45 -0.325 90)
			(size 0.6 0.55)
			(layers "F.Cu" "F.Mask" "F.Paste")
			(net "NetD17_3")
		)
		(pad "4" smd rect
			(at 1.4 0 180)
			(size 0.9 0.6)
			(layers "F.Cu" "F.Mask" "F.Paste")
			(net "NetD17_4")
		)
	)
	(footprint "SamacSys:155124M173200"
		(layer "F.Cu")
		(at 58.4511 114.8162 90)
		(property "Reference" "D16"
			(at -0.5714 1.701931 90)
			(unlocked yes)
			(layer "F.SilkS")
			(effects
				(font
					(size 0.762 0.762)
					(thickness 0.2286)
				)
			)
		)
		(property "Value" "155124M173200"
			(at 7.1725 2.632202 90)
			(unlocked yes)
			(layer "F.SilkS")
			(hide yes)
			(effects
				(font
					(size 1.524 1.524)
					(thickness 0.254)
				)
			)
		)
		(sheetname "USER_IO_STATUS")
		(sheetfile "USER_IO_STATUS.kicad_sch")
		(duplicate_pad_numbers_are_jumpers no)
		(fp_line
			(start -0.8 0.5)
			(end 0.8 0.5)
			(stroke
				(width 0.1)
				(type solid)
			)
			(layer "F.SilkS")
		)
		(fp_arc
			(start -2 -0.1)
			(mid -1.95 -0.05)
			(end -2 0)
			(stroke
				(width 0.1)
				(type solid)
			)
			(layer "F.SilkS")
		)
		(fp_arc
			(start -2 0)
			(mid -2.05 -0.05)
			(end -2 -0.1)
			(stroke
				(width 0.1)
				(type solid)
			)
			(layer "F.SilkS")
		)
		(pad "1" smd rect
			(at -1.4 0 180)
			(size 0.9 0.6)
			(layers "F.Cu" "F.Mask" "F.Paste")
			(net "+3.3V")
		)
		(pad "2" smd rect
			(at -0.45 -0.325 90)
			(size 0.6 0.55)
			(layers "F.Cu" "F.Mask" "F.Paste")
			(net "NetD16_2")
		)
		(pad "3" smd rect
			(at 0.45 -0.325 90)
			(size 0.6 0.55)
			(layers "F.Cu" "F.Mask" "F.Paste")
			(net "NetD16_3")
		)
		(pad "4" smd rect
			(at 1.4 0 180)
			(size 0.9 0.6)
			(layers "F.Cu" "F.Mask" "F.Paste")
			(net "NetD16_4")
		)
	)
	(footprint "Vault:SOT143-4L"
		(layer "F.Cu")
		(at 71.8761 100.7662 90)
		(property "Reference" "D1"
			(at -2.776921 1.478595 0)
			(unlocked yes)
			(layer "F.SilkS")
			(effects
				(font
					(size 0.762 0.762)
					(thickness 0.2286)
				)
			)
		)
		(property "Value" "8240136"
			(at 2.7035 3.368802 90)
			(unlocked yes)
			(layer "F.SilkS")
			(hide yes)
			(effects
				(font
					(size 1.524 1.524)
					(thickness 0.254)
				)
			)
		)
		(sheetname "USER_IO")
		(sheetfile "USER_IO.kicad_sch")
		(duplicate_pad_numbers_are_jumpers no)
		(fp_line
			(start 2.05 -1.7)
			(end 2.05 1.7)
			(stroke
				(width 0.2)
				(type solid)
			)
			(layer "F.SilkS")
		)
		(fp_line
			(start -2.05 -1.7)
			(end 2.05 -1.7)
			(stroke
				(width 0.2)
				(type solid)
			)
			(layer "F.SilkS")
		)
		(fp_line
			(start -2.05 -1.7)
			(end -2.05 1.675)
			(stroke
				(width 0.2)
				(type solid)
			)
			(layer "F.SilkS")
		)
		(fp_line
			(start -2.05 1.7)
			(end 2.05 1.7)
			(stroke
				(width 0.2)
				(type solid)
			)
			(layer "F.SilkS")
		)
		(fp_circle
			(center -2.404 -1.075)
			(end -2.15 -1.075)
			(stroke
				(width 0.2)
				(type solid)
			)
			(fill no)
			(layer "F.SilkS")
		)
		(pad "1" smd rect
			(at -1.1 -0.75 180)
			(size 1.4 1.4)
			(layers "F.Cu" "F.Mask" "F.Paste")
			(net "GND")
		)
		(pad "2" smd rect
			(at -1.1 0.95 180)
			(size 1 1.4)
			(layers "F.Cu" "F.Mask" "F.Paste")
			(net "NetAN2_1")
		)
		(pad "3" smd rect
			(at 1.1 0.95 180)
			(size 1 1.4)
			(layers "F.Cu" "F.Mask" "F.Paste")
			(net "NetAN1_1")
		)
		(pad "4" smd rect
			(at 1.1 -0.95 180)
			(size 1 1.4)
			(layers "F.Cu" "F.Mask" "F.Paste")
			(net "+3.3V")
		)
	)
	(footprint "Vault:CAPC1608X87X45ML20T05"
		(layer "F.Cu")
		(at 176.8761 87.0786 -90)
		(property "Reference" "C25"
			(at -2.723069 -0.2286 0)
			(unlocked yes)
			(layer "F.SilkS")
			(effects
				(font
					(size 0.762 0.762)
					(thickness 0.2286)
				)
			)
		)
		(property "Value" "0.1uF"
			(at 2.09443 2.657602 270)
			(unlocked yes)
			(layer "F.SilkS")
			(hide yes)
			(effects
				(font
					(size 1.524 1.524)
					(thickness 0.254)
				)
			)
		)
		(sheetname "GPS_IMU_SENSORS")
		(sheetfile "GPS_IMU_SENSORS.kicad_sch")
		(duplicate_pad_numbers_are_jumpers no)
		(pad "1" smd rect
			(at -0.7 0)
			(size 1.1 1.05)
			(layers "F.Cu" "F.Mask" "F.Paste")
			(net "GND")
		)
		(pad "2" smd rect
			(at 0.7 0)
			(size 1.1 1.05)
			(layers "F.Cu" "F.Mask" "F.Paste")
			(net "+3.3V")
		)
	)
	(footprint "Vault:CAPC1608X87X45ML20T05"
		(layer "F.Cu")
		(at 214.2637 90.4662 90)
		(property "Reference" "C12"
			(at 4.2 0.106655 270)
			(unlocked yes)
			(layer "F.SilkS")
			(effects
				(font
					(size 0.762 0.762)
					(thickness 0.2286)
				)
				(justify left bottom)
			)
		)
		(property "Value" "0.1uF"
			(at -10.00739 4.2013 0)
			(unlocked yes)
			(layer "F.SilkS")
			(hide yes)
			(effects
				(font
					(size 1.524 1.524)
					(thickness 0.254)
				)
				(justify left bottom)
			)
		)
		(sheetname "POWER")
		(sheetfile "POWER.kicad_sch")
		(duplicate_pad_numbers_are_jumpers no)
		(pad "1" smd rect
			(at -0.7 0 180)
			(size 1.1 1.05)
			(layers "F.Cu" "F.Mask" "F.Paste")
			(net "GND")
		)
		(pad "2" smd rect
			(at 0.7 0 180)
			(size 1.1 1.05)
			(layers "F.Cu" "F.Mask" "F.Paste")
			(net "+3.3V")
		)
	)
	(footprint "FPGA_CONN:SingleFPGAConn"
		(layer "F.Cu")
		(at 197.33851 104.56486 180)
		(property "Reference" "J34"
			(at -0.368955 -23.428198 180)
			(unlocked yes)
			(layer "F.SilkS")
			(effects
				(font
					(size 1.524 1.524)
					(thickness 0.254)
				)
			)
		)
		(property "Value" "Single FPGA Conn"
			(at 9.27992 3.521202 180)
			(unlocked yes)
			(layer "F.SilkS")
			(hide yes)
			(effects
				(font
					(size 1.524 1.524)
					(thickness 0.254)
				)
			)
		)
		(sheetname "FPGA")
		(sheetfile "FPGA.kicad_sch")
		(duplicate_pad_numbers_are_jumpers no)
		(fp_line
			(start 2 0.70003)
			(end 1.40005 0.70003)
			(stroke
				(width 0.15011)
				(type solid)
			)
			(layer "F.SilkS")
		)
		(fp_line
			(start 2 0.03302)
			(end 2 0.70003)
			(stroke
				(width 0.15011)
				(type solid)
			)
			(layer "F.SilkS")
		)
		(fp_line
			(start 2 -20.69998)
			(end 2 -20.03298)
			(stroke
				(width 0.15011)
				(type solid)
			)
			(layer "F.SilkS")
		)
		(fp_line
			(start 2 -20.69998)
			(end 1.40005 -20.69998)
			(stroke
				(width 0.15011)
				(type solid)
			)
			(layer "F.SilkS")
		)
		(fp_line
			(start 1.40005 1.24994)
			(end -1.40005 1.24994)
			(stroke
				(width 0.15011)
				(type solid)
			)
			(layer "F.SilkS")
		)
		(fp_line
			(start 1.40005 0.70003)
			(end 1.40005 1.24994)
			(stroke
				(width 0.15011)
				(type solid)
			)
			(layer "F.SilkS")
		)
		(fp_line
			(start 1.40005 -21.24989)
			(end 1.40005 -20.69998)
			(stroke
				(width 0.15011)
				(type solid)
			)
			(layer "F.SilkS")
		)
		(fp_line
			(start 1.40005 -21.24989)
			(end -1.40005 -21.24989)
			(stroke
				(width 0.15011)
				(type solid)
			)
			(layer "F.SilkS")
		)
		(fp_line
			(start -1.40005 0.70003)
			(end -1.40005 1.24994)
			(stroke
				(width 0.15011)
				(type solid)
			)
			(layer "F.SilkS")
		)
		(fp_line
			(start -1.40005 0.70003)
			(end -2 0.70003)
			(stroke
				(width 0.15011)
				(type solid)
			)
			(layer "F.SilkS")
		)
		(fp_line
			(start -1.40005 -20.69998)
			(end -2 -20.69998)
			(stroke
				(width 0.15011)
				(type solid)
			)
			(layer "F.SilkS")
		)
		(fp_line
			(start -1.40005 -21.24989)
			(end -1.40005 -20.69998)
			(stroke
				(width 0.15011)
				(type solid)
			)
			(layer "F.SilkS")
		)
		(fp_line
			(start -2 0.03302)
			(end -2 0.70003)
			(stroke
				(width 0.15011)
				(type solid)
			)
			(layer "F.SilkS")
		)
		(fp_line
			(start -2 -20.69998)
			(end -2 -20.03298)
			(stroke
				(width 0.15011)
				(type solid)
			)
			(layer "F.SilkS")
		)
		(fp_circle
			(center 3.5052 -0.22453)
			(end 3.5052 -0.02438)
			(stroke
				(width 0.40005)
				(type solid)
			)
			(fill no)
			(layer "F.SilkS")
		)
		(pad "1" smd rect
			(at 2.02489 -0.24993 180)
			(size 1.54991 0.24994)
			(layers "F.Cu" "F.Mask" "F.Paste")
			(net "+5.0V")
		)
		(pad "2" smd rect
			(at -2.02489 -0.24993 180)
			(size 1.54991 0.24994)
			(layers "F.Cu" "F.Mask" "F.Paste")
			(net "+5.0V")
		)
		(pad "3" smd rect
			(at 2.02489 -0.75006 180)
			(size 1.54991 0.24994)
			(layers "F.Cu" "F.Mask" "F.Paste")
			(net "+5.0V")
		)
		(pad "4" smd rect
			(at -2.02489 -0.75006 180)
			(size 1.54991 0.24994)
			(layers "F.Cu" "F.Mask" "F.Paste")
			(net "+5.0V")
		)
		(pad "5" smd rect
			(at 2.02489 -1.24993 180)
			(size 1.54991 0.24994)
			(layers "F.Cu" "F.Mask" "F.Paste")
			(net "+5.0V")
		)
		(pad "6" smd rect
			(at -2.02489 -1.24993 180)
			(size 1.54991 0.24994)
			(layers "F.Cu" "F.Mask" "F.Paste")
			(net "+5.0V")
		)
		(pad "7" smd rect
			(at 2.02489 -1.75006 180)
			(size 1.54991 0.24994)
			(layers "F.Cu" "F.Mask" "F.Paste")
			(net "+5.0V")
		)
		(pad "8" smd rect
			(at -2.02489 -1.75006 180)
			(size 1.54991 0.24994)
			(layers "F.Cu" "F.Mask" "F.Paste")
			(net "+5.0V")
		)
		(pad "9" smd rect
			(at 2.02489 -2.24993 180)
			(size 1.54991 0.24994)
			(layers "F.Cu" "F.Mask" "F.Paste")
			(net "GND")
		)
		(pad "10" smd rect
			(at -2.02489 -2.24993 180)
			(size 1.54991 0.24994)
			(layers "F.Cu" "F.Mask" "F.Paste")
			(net "GND")
		)
		(pad "11" smd rect
			(at 2.02489 -2.75006 180)
			(size 1.54991 0.24994)
			(layers "F.Cu" "F.Mask" "F.Paste")
		)
		(pad "12" smd rect
			(at -2.02489 -2.75006 180)
			(size 1.54991 0.24994)
			(layers "F.Cu" "F.Mask" "F.Paste")
		)
		(pad "13" smd rect
			(at 2.02489 -3.24993 180)
			(size 1.54991 0.24994)
			(layers "F.Cu" "F.Mask" "F.Paste")
		)
		(pad "14" smd rect
			(at -2.02489 -3.24993 180)
			(size 1.54991 0.24994)
			(layers "F.Cu" "F.Mask" "F.Paste")
		)
		(pad "15" smd rect
			(at 2.02489 -3.75005 180)
			(size 1.54991 0.24994)
			(layers "F.Cu" "F.Mask" "F.Paste")
		)
		(pad "16" smd rect
			(at -2.02489 -3.75005 180)
			(size 1.54991 0.24994)
			(layers "F.Cu" "F.Mask" "F.Paste")
		)
		(pad "17" smd rect
			(at 2.02489 -4.24993 180)
			(size 1.54991 0.24994)
			(layers "F.Cu" "F.Mask" "F.Paste")
		)
		(pad "18" smd rect
			(at -2.02489 -4.24993 180)
			(size 1.54991 0.24994)
			(layers "F.Cu" "F.Mask" "F.Paste")
		)
		(pad "19" smd rect
			(at 2.02489 -4.75005 180)
			(size 1.54991 0.24994)
			(layers "F.Cu" "F.Mask" "F.Paste")
			(net "GND")
		)
		(pad "20" smd rect
			(at -2.02489 -4.75005 180)
			(size 1.54991 0.24994)
			(layers "F.Cu" "F.Mask" "F.Paste")
			(net "GND")
		)
		(pad "21" smd rect
			(at 2.02489 -5.24992 180)
			(size 1.54991 0.24994)
			(layers "F.Cu" "F.Mask" "F.Paste")
		)
		(pad "22" smd rect
			(at -2.02489 -5.24992 180)
			(size 1.54991 0.24994)
			(layers "F.Cu" "F.Mask" "F.Paste")
			(net "GPS1_RST")
		)
		(pad "23" smd rect
			(at 2.02489 -5.75005 180)
			(size 1.54991 0.24994)
			(layers "F.Cu" "F.Mask" "F.Paste")
		)
		(pad "24" smd rect
			(at -2.02489 -5.75005 180)
			(size 1.54991 0.24994)
			(layers "F.Cu" "F.Mask" "F.Paste")
		)
		(pad "25" smd rect
			(at 2.02489 -6.24992 180)
			(size 1.54991 0.24994)
			(layers "F.Cu" "F.Mask" "F.Paste")
		)
		(pad "26" smd rect
			(at -2.02489 -6.24992 180)
			(size 1.54991 0.24994)
			(layers "F.Cu" "F.Mask" "F.Paste")
		)
		(pad "27" smd rect
			(at 2.02489 -6.75005 180)
			(size 1.54991 0.24994)
			(layers "F.Cu" "F.Mask" "F.Paste")
		)
		(pad "28" smd rect
			(at -2.02489 -6.75005 180)
			(size 1.54991 0.24994)
			(layers "F.Cu" "F.Mask" "F.Paste")
		)
		(pad "29" smd rect
			(at 2.02489 -7.24992 180)
			(size 1.54991 0.24994)
			(layers "F.Cu" "F.Mask" "F.Paste")
			(net "GND")
		)
		(pad "30" smd rect
			(at -2.02489 -7.24992 180)
			(size 1.54991 0.24994)
			(layers "F.Cu" "F.Mask" "F.Paste")
			(net "GND")
		)
		(pad "31" smd rect
			(at 2.02489 -7.75005 180)
			(size 1.54991 0.24994)
			(layers "F.Cu" "F.Mask" "F.Paste")
		)
		(pad "32" smd rect
			(at -2.02489 -7.75005 180)
			(size 1.54991 0.24994)
			(layers "F.Cu" "F.Mask" "F.Paste")
			(net "GPS1_TP1")
		)
		(pad "33" smd rect
			(at 2.02489 -8.24992 180)
			(size 1.54991 0.24994)
			(layers "F.Cu" "F.Mask" "F.Paste")
		)
		(pad "34" smd rect
			(at -2.02489 -8.24992 180)
			(size 1.54991 0.24994)
			(layers "F.Cu" "F.Mask" "F.Paste")
			(net "GPS1_TP2")
		)
		(pad "35" smd rect
			(at 2.02489 -8.75004 180)
			(size 1.54991 0.24994)
			(layers "F.Cu" "F.Mask" "F.Paste")
		)
		(pad "36" smd rect
			(at -2.02489 -8.75004 180)
			(size 1.54991 0.24994)
			(layers "F.Cu" "F.Mask" "F.Paste")
		)
		(pad "37" smd rect
			(at 2.02489 -9.24992 180)
			(size 1.54991 0.24994)
			(layers "F.Cu" "F.Mask" "F.Paste")
		)
		(pad "38" smd rect
			(at -2.02489 -9.24992 180)
			(size 1.54991 0.24994)
			(layers "F.Cu" "F.Mask" "F.Paste")
		)
		(pad "39" smd rect
			(at 2.02489 -9.75004 180)
			(size 1.54991 0.24994)
			(layers "F.Cu" "F.Mask" "F.Paste")
			(net "GND")
		)
		(pad "40" smd rect
			(at -2.02489 -9.75004 180)
			(size 1.54991 0.24994)
			(layers "F.Cu" "F.Mask" "F.Paste")
			(net "GND")
		)
		(pad "41" smd rect
			(at 2.02489 -10.24991 180)
			(size 1.54991 0.24994)
			(layers "F.Cu" "F.Mask" "F.Paste")
		)
		(pad "42" smd rect
			(at -2.02489 -10.24991 180)
			(size 1.54991 0.24994)
			(layers "F.Cu" "F.Mask" "F.Paste")
		)
		(pad "43" smd rect
			(at 2.02489 -10.75004 180)
			(size 1.54991 0.24994)
			(layers "F.Cu" "F.Mask" "F.Paste")
		)
		(pad "44" smd rect
			(at -2.02489 -10.75004 180)
			(size 1.54991 0.24994)
			(layers "F.Cu" "F.Mask" "F.Paste")
			(net "EXT_EEPROM_WP")
		)
		(pad "45" smd rect
			(at 2.02489 -11.24991 180)
			(size 1.54991 0.24994)
			(layers "F.Cu" "F.Mask" "F.Paste")
		)
		(pad "46" smd rect
			(at -2.02489 -11.24991 180)
			(size 1.54991 0.24994)
			(layers "F.Cu" "F.Mask" "F.Paste")
		)
		(pad "47" smd rect
			(at 2.02489 -11.75004 180)
			(size 1.54991 0.24994)
			(layers "F.Cu" "F.Mask" "F.Paste")
		)
		(pad "48" smd rect
			(at -2.02489 -11.75004 180)
			(size 1.54991 0.24994)
			(layers "F.Cu" "F.Mask" "F.Paste")
		)
		(pad "49" smd rect
			(at 2.02489 -12.24991 180)
			(size 1.54991 0.24994)
			(layers "F.Cu" "F.Mask" "F.Paste")
			(net "GND")
		)
		(pad "50" smd rect
			(at -2.02489 -12.24991 180)
			(size 1.54991 0.24994)
			(layers "F.Cu" "F.Mask" "F.Paste")
			(net "GND")
		)
		(pad "51" smd rect
			(at 2.02489 -12.75004 180)
			(size 1.54991 0.24994)
			(layers "F.Cu" "F.Mask" "F.Paste")
		)
		(pad "52" smd rect
			(at -2.02489 -12.75004 180)
			(size 1.54991 0.24994)
			(layers "F.Cu" "F.Mask" "F.Paste")
		)
		(pad "53" smd rect
			(at 2.02489 -13.24991 180)
			(size 1.54991 0.24994)
			(layers "F.Cu" "F.Mask" "F.Paste")
		)
		(pad "54" smd rect
			(at -2.02489 -13.24991 180)
			(size 1.54991 0.24994)
			(layers "F.Cu" "F.Mask" "F.Paste")
		)
		(pad "55" smd rect
			(at 2.02489 -13.75003 180)
			(size 1.54991 0.24994)
			(layers "F.Cu" "F.Mask" "F.Paste")
		)
		(pad "56" smd rect
			(at -2.02489 -13.75003 180)
			(size 1.54991 0.24994)
			(layers "F.Cu" "F.Mask" "F.Paste")
		)
		(pad "57" smd rect
			(at 2.02489 -14.24991 180)
			(size 1.54991 0.24994)
			(layers "F.Cu" "F.Mask" "F.Paste")
		)
		(pad "58" smd rect
			(at -2.02489 -14.24991 180)
			(size 1.54991 0.24994)
			(layers "F.Cu" "F.Mask" "F.Paste")
		)
		(pad "59" smd rect
			(at 2.02489 -14.75003 180)
			(size 1.54991 0.24994)
			(layers "F.Cu" "F.Mask" "F.Paste")
			(net "GND")
		)
		(pad "60" smd rect
			(at -2.02489 -14.75003 180)
			(size 1.54991 0.24994)
			(layers "F.Cu" "F.Mask" "F.Paste")
			(net "GND")
		)
		(pad "61" smd rect
			(at 2.02489 -15.2499 180)
			(size 1.54991 0.24994)
			(layers "F.Cu" "F.Mask" "F.Paste")
		)
		(pad "62" smd rect
			(at -2.02489 -15.2499 180)
			(size 1.54991 0.24994)
			(layers "F.Cu" "F.Mask" "F.Paste")
		)
		(pad "63" smd rect
			(at 2.02489 -15.75003 180)
			(size 1.54991 0.24994)
			(layers "F.Cu" "F.Mask" "F.Paste")
		)
		(pad "64" smd rect
			(at -2.02489 -15.75003 180)
			(size 1.54991 0.24994)
			(layers "F.Cu" "F.Mask" "F.Paste")
		)
		(pad "65" smd rect
			(at 2.02489 -16.2499 180)
			(size 1.54991 0.24994)
			(layers "F.Cu" "F.Mask" "F.Paste")
		)
		(pad "66" smd rect
			(at -2.02489 -16.2499 180)
			(size 1.54991 0.24994)
			(layers "F.Cu" "F.Mask" "F.Paste")
		)
		(pad "67" smd rect
			(at 2.02489 -16.75003 180)
			(size 1.54991 0.24994)
			(layers "F.Cu" "F.Mask" "F.Paste")
			(net "KEY2")
		)
		(pad "68" smd rect
			(at -2.02489 -16.75003 180)
			(size 1.54991 0.24994)
			(layers "F.Cu" "F.Mask" "F.Paste")
		)
		(pad "69" smd rect
			(at 2.02489 -17.2499 180)
			(size 1.54991 0.24994)
			(layers "F.Cu" "F.Mask" "F.Paste")
			(net "GND")
		)
		(pad "70" smd rect
			(at -2.02489 -17.2499 180)
			(size 1.54991 0.24994)
			(layers "F.Cu" "F.Mask" "F.Paste")
			(net "GND")
		)
		(pad "71" smd rect
			(at 2.02489 -17.75003 180)
			(size 1.54991 0.24994)
			(layers "F.Cu" "F.Mask" "F.Paste")
			(net "LED4")
		)
		(pad "72" smd rect
			(at -2.02489 -17.75003 180)
			(size 1.54991 0.24994)
			(layers "F.Cu" "F.Mask" "F.Paste")
		)
		(pad "73" smd rect
			(at 2.02489 -18.2499 180)
			(size 1.54991 0.24994)
			(layers "F.Cu" "F.Mask" "F.Paste")
			(net "LED3")
		)
		(pad "74" smd rect
			(at -2.02489 -18.2499 180)
			(size 1.54991 0.24994)
			(layers "F.Cu" "F.Mask" "F.Paste")
		)
		(pad "75" smd rect
			(at 2.02489 -18.75002 180)
			(size 1.54991 0.24994)
			(layers "F.Cu" "F.Mask" "F.Paste")
			(net "LED2")
		)
		(pad "76" smd rect
			(at -2.02489 -18.75002 180)
			(size 1.54991 0.24994)
			(layers "F.Cu" "F.Mask" "F.Paste")
		)
		(pad "77" smd rect
			(at 2.02489 -19.2499 180)
			(size 1.54991 0.24994)
			(layers "F.Cu" "F.Mask" "F.Paste")
			(net "LED1")
		)
		(pad "78" smd rect
			(at -2.02489 -19.2499 180)
			(size 1.54991 0.24994)
			(layers "F.Cu" "F.Mask" "F.Paste")
		)
		(pad "79" smd rect
			(at 2.02489 -19.75002 180)
			(size 1.54991 0.24994)
			(layers "F.Cu" "F.Mask" "F.Paste")
		)
		(pad "80" smd rect
			(at -2.02489 -19.75002 180)
			(size 1.54991 0.24994)
			(layers "F.Cu" "F.Mask" "F.Paste")
		)
		(pad "81" smd rect
			(at 0.01135 1.17626 180)
			(size 1.70002 1.35001)
			(layers "F.Cu" "F.Mask" "F.Paste")
		)
		(pad "82" thru_hole circle
			(at 0 0 180)
			(size 0.55016 0.55016)
			(drill 0.55016)
			(layers "*.Cu" "*.Mask")
			(remove_unused_layers no)
			(thermal_bridge_angle 90)
		)
		(pad "83" thru_hole circle
			(at 0 -19.99996 180)
			(size 0.55016 0.55016)
			(drill 0.55016)
			(layers "*.Cu" "*.Mask")
			(remove_unused_layers no)
			(thermal_bridge_angle 90)
		)
		(pad "84" smd rect
			(at 0.01135 -21.17374 180)
			(size 1.70002 1.35001)
			(layers "F.Cu" "F.Mask" "F.Paste")
		)
	)
	(footprint "Vault:FP-LTST-C191TBKT-MFG"
		(layer "F.Cu")
		(at 75.1261 52.1162 90)
		(property "Reference" "D11"
			(at -7.75 0.343345 90)
			(unlocked yes)
			(layer "F.SilkS")
			(effects
				(font
					(size 0.762 0.762)
					(thickness 0.2286)
				)
				(justify left bottom)
			)
		)
		(property "Value" "BLUE"
			(at -3.22199 -1.4097 0)
			(unlocked yes)
			(layer "F.SilkS")
			(hide yes)
			(effects
				(font
					(size 1.524 1.524)
					(thickness 0.254)
				)
				(justify left bottom)
			)
		)
		(sheetname "USER_IO_STATUS")
		(sheetfile "USER_IO_STATUS.kicad_sch")
		(duplicate_pad_numbers_are_jumpers no)
		(fp_line
			(start -0.85 -0.8)
			(end 0.85 -0.8)
			(stroke
				(width 0.2)
				(type solid)
			)
			(layer "F.SilkS")
		)
		(fp_line
			(start -0.85 0.8)
			(end 0.85 0.8)
			(stroke
				(width 0.2)
				(type solid)
			)
			(layer "F.SilkS")
		)
		(fp_circle
			(center -1.75 0)
			(end -1.625 0)
			(stroke
				(width 0.25)
				(type solid)
			)
			(fill no)
			(layer "F.SilkS")
		)
		(fp_line
			(start 1.25 -0.55)
			(end 1.25 0.55)
			(stroke
				(width 0.2)
				(type solid)
			)
			(layer "F.CrtYd")
		)
		(fp_line
			(start -1.25 -0.55)
			(end 1.25 -0.55)
			(stroke
				(width 0.2)
				(type solid)
			)
			(layer "F.CrtYd")
		)
		(fp_line
			(start -1.25 -0.55)
			(end -1.25 0.55)
			(stroke
				(width 0.2)
				(type solid)
			)
			(layer "F.CrtYd")
		)
		(fp_line
			(start -1.25 0.55)
			(end 1.25 0.55)
			(stroke
				(width 0.2)
				(type solid)
			)
			(layer "F.CrtYd")
		)
		(fp_line
			(start 1.25 -0.55)
			(end 1.25 0.55)
			(stroke
				(width 0.2)
				(type solid)
			)
			(layer "F.Fab")
		)
		(fp_line
			(start -1.25 -0.55)
			(end 1.25 -0.55)
			(stroke
				(width 0.2)
				(type solid)
			)
			(layer "F.Fab")
		)
		(fp_line
			(start -1.25 -0.55)
			(end -1.25 0.55)
			(stroke
				(width 0.2)
				(type solid)
			)
			(layer "F.Fab")
		)
		(fp_line
			(start 0 -0.5)
			(end 0 0.5)
			(stroke
				(width 0.1)
				(type solid)
			)
			(layer "F.Fab")
		)
		(fp_line
			(start -0.5 0)
			(end 0.5 0)
			(stroke
				(width 0.1)
				(type solid)
			)
			(layer "F.Fab")
		)
		(fp_line
			(start -1.25 0.55)
			(end 1.25 0.55)
			(stroke
				(width 0.2)
				(type solid)
			)
			(layer "F.Fab")
		)
		(pad "1" smd rect
			(at -0.75 0 90)
			(size 0.8 0.8)
			(layers "F.Cu" "F.Mask" "F.Paste")
			(net "NetD11_1")
			(solder_mask_margin 0)
			(solder_paste_margin 0)
		)
		(pad "2" smd rect
			(at 0.75 0 90)
			(size 0.8 0.8)
			(layers "F.Cu" "F.Mask" "F.Paste")
			(net "+3.3V")
			(solder_mask_margin 0)
			(solder_paste_margin 0)
		)
	)
	(footprint "Resistors:RESC1608X50N"
		(layer "F.Cu")
		(at 210.9885 113.6662 90)
		(property "Reference" "R6"
			(at -3.398 0.321345 90)
			(unlocked yes)
			(layer "F.SilkS")
			(effects
				(font
					(size 0.762 0.762)
					(thickness 0.2286)
				)
				(justify left bottom)
			)
		)
		(property "Value" "ERJ-3EKF1002V"
			(at -1.35659 -0.8447 0)
			(unlocked yes)
			(layer "F.SilkS")
			(hide yes)
			(effects
				(font
					(size 1.524 1.524)
					(thickness 0.254)
				)
				(justify left bottom)
			)
		)
		(sheetname "POWER")
		(sheetfile "POWER.kicad_sch")
		(duplicate_pad_numbers_are_jumpers no)
		(fp_line
			(start 0 -0.5)
			(end 0 0.5)
			(stroke
				(width 0.1524)
				(type solid)
			)
			(layer "F.SilkS")
		)
		(pad "1" smd rect
			(at -0.69 0 180)
			(size 1 0.72)
			(layers "F.Cu" "F.Mask" "F.Paste")
			(net "GND")
		)
		(pad "2" smd rect
			(at 0.69 0 180)
			(size 1 0.72)
			(layers "F.Cu" "F.Mask" "F.Paste")
			(net "NetR4_2")
		)
	)
	(footprint "Vault:RESC1608X55X30NL15T15"
		(layer "F.Cu")
		(at 82.3761 125.8662 -90)
		(property "Reference" "R17"
			(at 2.7714 -0.026921 90)
			(unlocked yes)
			(layer "F.SilkS")
			(effects
				(font
					(size 0.762 0.762)
					(thickness 0.2286)
				)
			)
		)
		(property "Value" "4.7K"
			(at -2.911592 3.21199 180)
			(unlocked yes)
			(layer "F.SilkS")
			(hide yes)
			(effects
				(font
					(size 1.524 1.524)
					(thickness 0.254)
				)
			)
		)
		(sheetname "USER_IO")
		(sheetfile "USER_IO.kicad_sch")
		(duplicate_pad_numbers_are_jumpers no)
		(pad "1" smd rect
			(at -0.75 0)
			(size 0.95 0.95)
			(layers "F.Cu" "F.Mask" "F.Paste")
			(net "ANT3_IO_IN")
		)
		(pad "2" smd rect
			(at 0.75 0)
			(size 0.95 0.95)
			(layers "F.Cu" "F.Mask" "F.Paste")
			(net "+3.3V")
		)
	)
	(footprint "Vault:CAPC1608X87X45ML20T05"
		(layer "F.Cu")
		(at 203.9485 110.8452 -90)
		(property "Reference" "C19"
			(at 1.046 1.141655 90)
			(unlocked yes)
			(layer "F.SilkS")
			(effects
				(font
					(size 0.762 0.762)
					(thickness 0.2286)
				)
				(justify left bottom)
			)
		)
		(property "Value" "0.1uF"
			(at -1.94801 -9.4735 0)
			(unlocked yes)
			(layer "F.SilkS")
			(hide yes)
			(effects
				(font
					(size 1.524 1.524)
					(thickness 0.254)
				)
				(justify left bottom)
			)
		)
		(sheetname "POWER")
		(sheetfile "POWER.kicad_sch")
		(duplicate_pad_numbers_are_jumpers no)
		(pad "1" smd rect
			(at -0.7 0)
			(size 1.1 1.05)
			(layers "F.Cu" "F.Mask" "F.Paste")
			(net "GND")
		)
		(pad "2" smd rect
			(at 0.7 0)
			(size 1.1 1.05)
			(layers "F.Cu" "F.Mask" "F.Paste")
			(net "NetC19_2")
		)
	)
	(footprint "Vault:FP-C0603C105K3PACTU-MFG"
		(layer "F.Cu")
		(at 82.3761 86.9662 -90)
		(property "Reference" "C38"
			(at -0.3286 2.973069 90)
			(unlocked yes)
			(layer "F.SilkS")
			(effects
				(font
					(size 0.762 0.762)
					(thickness 0.2286)
				)
			)
		)
		(property "Value" "1uF"
			(at -2.886202 1.485285 180)
			(unlocked yes)
			(layer "F.SilkS")
			(hide yes)
			(effects
				(font
					(size 1.524 1.524)
					(thickness 0.254)
				)
			)
		)
		(sheetname "USER_IO_STATUS")
		(sheetfile "USER_IO_STATUS.kicad_sch")
		(duplicate_pad_numbers_are_jumpers no)
		(fp_line
			(start 0.875 0.825)
			(end -0.875 0.825)
			(stroke
				(width 0.2)
				(type solid)
			)
			(layer "F.SilkS")
		)
		(fp_line
			(start 0.875 -0.825)
			(end -0.875 -0.825)
			(stroke
				(width 0.2)
				(type solid)
			)
			(layer "F.SilkS")
		)
		(fp_line
			(start -1.2 0.6)
			(end -1.2 -0.6)
			(stroke
				(width 0.2)
				(type solid)
			)
			(layer "F.CrtYd")
		)
		(fp_line
			(start 1.2 0.6)
			(end -1.2 0.6)
			(stroke
				(width 0.2)
				(type solid)
			)
			(layer "F.CrtYd")
		)
		(fp_line
			(start 1.2 0.6)
			(end 1.2 -0.6)
			(stroke
				(width 0.2)
				(type solid)
			)
			(layer "F.CrtYd")
		)
		(fp_line
			(start 1.2 -0.6)
			(end -1.2 -0.6)
			(stroke
				(width 0.2)
				(type solid)
			)
			(layer "F.CrtYd")
		)
		(fp_line
			(start -1.2 0.6)
			(end -1.2 -0.6)
			(stroke
				(width 0.2)
				(type solid)
			)
			(layer "F.Fab")
		)
		(fp_line
			(start 1.2 0.6)
			(end -1.2 0.6)
			(stroke
				(width 0.2)
				(type solid)
			)
			(layer "F.Fab")
		)
		(fp_line
			(start 1.2 0.6)
			(end 1.2 -0.6)
			(stroke
				(width 0.2)
				(type solid)
			)
			(layer "F.Fab")
		)
		(fp_line
			(start 0 0.5)
			(end 0 -0.5)
			(stroke
				(width 0.1)
				(type solid)
			)
			(layer "F.Fab")
		)
		(fp_line
			(start 0.5 0)
			(end -0.5 0)
			(stroke
				(width 0.1)
				(type solid)
			)
			(layer "F.Fab")
		)
		(fp_line
			(start 1.2 -0.6)
			(end -1.2 -0.6)
			(stroke
				(width 0.2)
				(type solid)
			)
			(layer "F.Fab")
		)
		(pad "1" smd rect
			(at -0.6 0 270)
			(size 0.75 0.9)
			(layers "F.Cu" "F.Mask" "F.Paste")
			(net "+3.3V")
			(solder_mask_margin 0)
			(solder_paste_margin 0)
		)
		(pad "2" smd rect
			(at 0.6 0 270)
			(size 0.75 0.9)
			(layers "F.Cu" "F.Mask" "F.Paste")
			(net "GND")
			(solder_mask_margin 0)
			(solder_paste_margin 0)
		)
	)
	(footprint "SamacSys:155124M173200"
		(layer "F.Cu")
		(at 58.4511 71.6662 90)
		(property "Reference" "D13"
			(at -4.7 -0.231655 90)
			(unlocked yes)
			(layer "F.SilkS")
			(effects
				(font
					(size 0.762 0.762)
					(thickness 0.2286)
				)
				(justify left bottom)
			)
		)
		(property "Value" "155124M173200"
			(at -4.13639 -0.5715 0)
			(unlocked yes)
			(layer "F.SilkS")
			(hide yes)
			(effects
				(font
					(size 1.524 1.524)
					(thickness 0.254)
				)
				(justify left bottom)
			)
		)
		(sheetname "USER_IO_STATUS")
		(sheetfile "USER_IO_STATUS.kicad_sch")
		(duplicate_pad_numbers_are_jumpers no)
		(fp_line
			(start -0.8 0.5)
			(end 0.8 0.5)
			(stroke
				(width 0.1)
				(type solid)
			)
			(layer "F.SilkS")
		)
		(fp_arc
			(start -2 -0.1)
			(mid -1.95 -0.05)
			(end -2 0)
			(stroke
				(width 0.1)
				(type solid)
			)
			(layer "F.SilkS")
		)
		(fp_arc
			(start -2 0)
			(mid -2.05 -0.05)
			(end -2 -0.1)
			(stroke
				(width 0.1)
				(type solid)
			)
			(layer "F.SilkS")
		)
		(pad "1" smd rect
			(at -1.4 0 180)
			(size 0.9 0.6)
			(layers "F.Cu" "F.Mask" "F.Paste")
			(net "+3.3V")
		)
		(pad "2" smd rect
			(at -0.45 -0.325 90)
			(size 0.6 0.55)
			(layers "F.Cu" "F.Mask" "F.Paste")
			(net "NetD13_2")
		)
		(pad "3" smd rect
			(at 0.45 -0.325 90)
			(size 0.6 0.55)
			(layers "F.Cu" "F.Mask" "F.Paste")
			(net "NetD13_3")
		)
		(pad "4" smd rect
			(at 1.4 0 180)
			(size 0.9 0.6)
			(layers "F.Cu" "F.Mask" "F.Paste")
			(net "NetD13_4")
		)
	)
	(footprint "Vault:CAPC1608X87X45ML20T05"
		(layer "F.Cu")
		(at 190.1261 89.3786 90)
		(property "Reference" "C33"
			(at 3.2786 0.026921 90)
			(unlocked yes)
			(layer "F.SilkS")
			(effects
				(font
					(size 0.762 0.762)
					(thickness 0.2286)
				)
			)
		)
		(property "Value" "0.1uF"
			(at 2.09443 2.657602 90)
			(unlocked yes)
			(layer "F.SilkS")
			(hide yes)
			(effects
				(font
					(size 1.524 1.524)
					(thickness 0.254)
				)
			)
		)
		(sheetname "GPS_IMU_SENSORS")
		(sheetfile "GPS_IMU_SENSORS.kicad_sch")
		(duplicate_pad_numbers_are_jumpers no)
		(pad "1" smd rect
			(at -0.7 0 180)
			(size 1.1 1.05)
			(layers "F.Cu" "F.Mask" "F.Paste")
			(net "GND")
		)
		(pad "2" smd rect
			(at 0.7 0 180)
			(size 1.1 1.05)
			(layers "F.Cu" "F.Mask" "F.Paste")
			(net "+3.3V")
		)
	)
	(footprint "Passives:SOT65P210X110-3N"
		(layer "F.Cu")
		(at 195.08636 143.47763)
		(property "Reference" "D6"
			(at -3.16026 -1.068085 0)
			(unlocked yes)
			(layer "F.SilkS")
			(effects
				(font
					(size 0.762 0.762)
					(thickness 0.2286)
				)
				(justify left bottom)
			)
		)
		(property "Value" "BAT54SW"
			(at -4.0249 -1.73021 0)
			(unlocked yes)
			(layer "F.SilkS")
			(hide yes)
			(effects
				(font
					(size 1.524 1.524)
					(thickness 0.254)
				)
				(justify left bottom)
			)
		)
		(sheetname "PCIe_JTAG")
		(sheetfile "PCIe_JTAG.kicad_sch")
		(duplicate_pad_numbers_are_jumpers no)
		(fp_line
			(start -0.325 -1.1)
			(end 0.675 -1.1)
			(stroke
				(width 0.2)
				(type solid)
			)
			(layer "F.SilkS")
		)
		(fp_line
			(start -0.325 1.1)
			(end 0.675 1.1)
			(stroke
				(width 0.2)
				(type solid)
			)
			(layer "F.SilkS")
		)
		(fp_line
			(start 0.675 -0.65)
			(end 0.675 -1.1)
			(stroke
				(width 0.2)
				(type solid)
			)
			(layer "F.SilkS")
		)
		(fp_line
			(start 0.675 1.1)
			(end 0.675 0.65)
			(stroke
				(width 0.2)
				(type solid)
			)
			(layer "F.SilkS")
		)
		(fp_circle
			(center -1.125 -1.45)
			(end -1.125 -1.575)
			(stroke
				(width 0.25)
				(type solid)
			)
			(fill no)
			(layer "F.SilkS")
		)
		(pad "1" smd rect
			(at -1.125 -0.65 90)
			(size 0.5 0.9)
			(layers "F.Cu" "F.Mask" "F.Paste")
			(net "GND")
		)
		(pad "2" smd rect
			(at -1.125 0.65 90)
			(size 0.5 0.9)
			(layers "F.Cu" "F.Mask" "F.Paste")
			(net "+3.3V")
		)
		(pad "3" smd rect
			(at 1.125 0 90)
			(size 0.5 0.9)
			(layers "F.Cu" "F.Mask" "F.Paste")
			(net "FPGA_TDO")
		)
	)
	(footprint "Passives:IND_PM124SH"
		(layer "F.Cu")
		(at 215.2515 124.9422 180)
		(property "Reference" "L1"
			(at 8.2254 -1.667345 0)
			(unlocked yes)
			(layer "F.SilkS")
			(effects
				(font
					(size 0.762 0.762)
					(thickness 0.2286)
				)
				(justify left bottom)
			)
		)
		(property "Value" "PM124SH-100M-RC"
			(at 22.7845 -1.30319 0)
			(unlocked yes)
			(layer "F.SilkS")
			(hide yes)
			(effects
				(font
					(size 1.524 1.524)
					(thickness 0.254)
				)
				(justify left bottom)
			)
		)
		(sheetname "POWER")
		(sheetfile "POWER.kicad_sch")
		(duplicate_pad_numbers_are_jumpers no)
		(fp_line
			(start 6.681 6.4)
			(end -6.681 6.4)
			(stroke
				(width 0.254)
				(type solid)
			)
			(layer "F.SilkS")
		)
		(fp_line
			(start 6.681 -6.4)
			(end 6.681 6.4)
			(stroke
				(width 0.254)
				(type solid)
			)
			(layer "F.SilkS")
		)
		(fp_line
			(start 6.681 -6.4)
			(end -6.681 -6.4)
			(stroke
				(width 0.254)
				(type solid)
			)
			(layer "F.SilkS")
		)
		(fp_line
			(start -6.681 -6.4)
			(end -6.681 6.4)
			(stroke
				(width 0.254)
				(type solid)
			)
			(layer "F.SilkS")
		)
		(pad "1" smd rect
			(at -4.85 0 180)
			(size 2.9 5.4)
			(layers "F.Cu" "F.Mask" "F.Paste")
			(net "+5.0V")
		)
		(pad "2" smd rect
			(at 4.85 0 180)
			(size 2.9 5.4)
			(layers "F.Cu" "F.Mask" "F.Paste")
			(net "NetC4_2")
		)
	)
	(footprint "GNSS:GNSS"
		(locked yes)
		(layer "F.Cu")
		(at 84.1536 70.8286)
		(property "Reference" "U9"
			(at -0.6275 -5.419055 0)
			(unlocked yes)
			(layer "F.SilkS")
			(effects
				(font
					(size 0.762 0.762)
					(thickness 0.2286)
				)
				(justify left bottom)
			)
		)
		(property "Value" "RCB-F9T"
			(at -9.8007 23.16699 0)
			(unlocked yes)
			(layer "F.SilkS")
			(hide yes)
			(effects
				(font
					(size 1.524 1.524)
					(thickness 0.254)
				)
				(justify left bottom)
			)
		)
		(sheetname "GPS_IMU_SENSORS")
		(sheetfile "GPS_IMU_SENSORS.kicad_sch")
		(duplicate_pad_numbers_are_jumpers no)
		(fp_line
			(start -6.11 -20.47)
			(end 61.07 -20.47)
			(stroke
				(width 0.254)
				(type solid)
			)
			(layer "F.SilkS")
		)
		(fp_line
			(start -6.11 11.28)
			(end -6.11 -20.47)
			(stroke
				(width 0.254)
				(type solid)
			)
			(layer "F.SilkS")
		)
		(fp_line
			(start -6.11 11.28)
			(end 61.07 11.28)
			(stroke
				(width 0.254)
				(type solid)
			)
			(layer "F.SilkS")
		)
		(fp_line
			(start 61.07 11.28)
			(end 61.07 -20.47)
			(stroke
				(width 0.254)
				(type solid)
			)
			(layer "F.SilkS")
		)
		(pad "0" thru_hole circle
			(at 0 -2 270)
			(size 0 0)
			(drill 0.76)
			(layers "*.Cu" "*.Mask")
			(remove_unused_layers no)
			(thermal_bridge_angle 90)
		)
		(pad "0" thru_hole circle
			(at 0 2 270)
			(size 0 0)
			(drill 0.76)
			(layers "*.Cu" "*.Mask")
			(remove_unused_layers no)
			(thermal_bridge_angle 90)
		)
		(pad "1" smd rect
			(at -2.2225 3 270)
			(size 1.12 2.105)
			(layers "F.Cu" "F.Mask" "F.Paste")
			(net "+5.0V")
		)
		(pad "2" smd rect
			(at 2.2225 3 270)
			(size 1.12 2.105)
			(layers "F.Cu" "F.Mask" "F.Paste")
			(net "+3.3V")
		)
		(pad "3" smd rect
			(at -2.2225 1 270)
			(size 1.12 2.105)
			(layers "F.Cu" "F.Mask" "F.Paste")
			(net "GPS1_TX")
		)
		(pad "4" smd rect
			(at 2.2225 1 270)
			(size 1.12 2.105)
			(layers "F.Cu" "F.Mask" "F.Paste")
			(net "GPS1_RST")
		)
		(pad "5" smd rect
			(at -2.2225 -1 270)
			(size 1.12 2.105)
			(layers "F.Cu" "F.Mask" "F.Paste")
			(net "GPS1_RX")
		)
		(pad "6" smd rect
			(at 2.2225 -1 270)
			(size 1.12 2.105)
			(layers "F.Cu" "F.Mask" "F.Paste")
			(net "GPS1_TP1")
		)
		(pad "7" smd rect
			(at -2.2225 -3 270)
			(size 1.12 2.105)
			(layers "F.Cu" "F.Mask" "F.Paste")
			(net "GPS1_TP2")
		)
		(pad "8" smd rect
			(at 2.2225 -3 270)
			(size 1.12 2.105)
			(layers "F.Cu" "F.Mask" "F.Paste")
			(net "GND")
		)
	)
	(footprint "Vault:FP-RC0603-0_55-MFG"
		(layer "F.Cu")
		(at 84.1261 83.8662 -90)
		(property "Reference" "R40"
			(at 0.0214 3.473069 90)
			(unlocked yes)
			(layer "F.SilkS")
			(effects
				(font
					(size 0.762 0.762)
					(thickness 0.2286)
				)
			)
		)
		(property "Value" "100k"
			(at -3.089402 2.39948 180)
			(unlocked yes)
			(layer "F.SilkS")
			(hide yes)
			(effects
				(font
					(size 1.524 1.524)
					(thickness 0.254)
				)
			)
		)
		(sheetname "USER_IO_STATUS")
		(sheetfile "USER_IO_STATUS.kicad_sch")
		(duplicate_pad_numbers_are_jumpers no)
		(fp_line
			(start 0.025 0.45)
			(end -0.025 0.45)
			(stroke
				(width 0.2)
				(type solid)
			)
			(layer "F.SilkS")
		)
		(fp_line
			(start 0.025 -0.45)
			(end -0.025 -0.45)
			(stroke
				(width 0.2)
				(type solid)
			)
			(layer "F.SilkS")
		)
		(fp_line
			(start -1.4 0.55)
			(end -1.4 -0.55)
			(stroke
				(width 0.2)
				(type solid)
			)
			(layer "F.CrtYd")
		)
		(fp_line
			(start 1.4 0.55)
			(end -1.4 0.55)
			(stroke
				(width 0.2)
				(type solid)
			)
			(layer "F.CrtYd")
		)
		(fp_line
			(start 1.4 0.55)
			(end 1.4 -0.55)
			(stroke
				(width 0.2)
				(type solid)
			)
			(layer "F.CrtYd")
		)
		(fp_line
			(start 1.4 -0.55)
			(end -1.4 -0.55)
			(stroke
				(width 0.2)
				(type solid)
			)
			(layer "F.CrtYd")
		)
		(fp_line
			(start -1.4 0.55)
			(end -1.4 -0.55)
			(stroke
				(width 0.2)
				(type solid)
			)
			(layer "F.Fab")
		)
		(fp_line
			(start 1.4 0.55)
			(end -1.4 0.55)
			(stroke
				(width 0.2)
				(type solid)
			)
			(layer "F.Fab")
		)
		(fp_line
			(start 1.4 0.55)
			(end 1.4 -0.55)
			(stroke
				(width 0.2)
				(type solid)
			)
			(layer "F.Fab")
		)
		(fp_line
			(start 0 0.5)
			(end 0 -0.5)
			(stroke
				(width 0.1)
				(type solid)
			)
			(layer "F.Fab")
		)
		(fp_line
			(start 0.5 0)
			(end -0.5 0)
			(stroke
				(width 0.1)
				(type solid)
			)
			(layer "F.Fab")
		)
		(fp_line
			(start 1.4 -0.55)
			(end -1.4 -0.55)
			(stroke
				(width 0.2)
				(type solid)
			)
			(layer "F.Fab")
		)
		(pad "1" smd rect
			(at -0.85 0 270)
			(size 0.9 0.8)
			(layers "F.Cu" "F.Mask" "F.Paste")
			(net "GND")
			(solder_mask_margin 0)
			(solder_paste_margin 0)
		)
		(pad "2" smd rect
			(at 0.85 0 270)
			(size 0.9 0.8)
			(layers "F.Cu" "F.Mask" "F.Paste")
			(net "NetC39_2")
			(solder_mask_margin 0)
			(solder_paste_margin 0)
		)
	)
	(footprint "Resistors:RESC1608X50N"
		(layer "F.Cu")
		(at 220.8637 85.1662)
		(property "Reference" "R1"
			(at 2.4 0.393345 0)
			(unlocked yes)
			(layer "F.SilkS")
			(effects
				(font
					(size 0.762 0.762)
					(thickness 0.2286)
				)
				(justify left bottom)
			)
		)
		(property "Value" "ERJ-3EKF2000V"
			(at -19.0909 11.38359 0)
			(unlocked yes)
			(layer "F.SilkS")
			(hide yes)
			(effects
				(font
					(size 1.524 1.524)
					(thickness 0.254)
				)
				(justify left bottom)
			)
		)
		(sheetname "POWER")
		(sheetfile "POWER.kicad_sch")
		(duplicate_pad_numbers_are_jumpers no)
		(fp_line
			(start 0 0.5)
			(end 0 -0.5)
			(stroke
				(width 0.1524)
				(type solid)
			)
			(layer "F.SilkS")
		)
		(pad "1" smd rect
			(at -0.69 0 90)
			(size 1 0.72)
			(layers "F.Cu" "F.Mask" "F.Paste")
			(net "GND")
		)
		(pad "2" smd rect
			(at 0.69 0 90)
			(size 1 0.72)
			(layers "F.Cu" "F.Mask" "F.Paste")
			(net "NetD4_1")
		)
	)
	(footprint "Vault:RESC1608X55X30NL15T15"
		(layer "F.Cu")
		(at 83.3761 89.6162)
		(property "Reference" "R41"
			(at -2.521405 0.026921 0)
			(unlocked yes)
			(layer "F.SilkS")
			(effects
				(font
					(size 0.762 0.762)
					(thickness 0.2286)
				)
			)
		)
		(property "Value" "4.7K"
			(at 1.63744 2.352802 0)
			(unlocked yes)
			(layer "F.SilkS")
			(hide yes)
			(effects
				(font
					(size 1.524 1.524)
					(thickness 0.254)
				)
			)
		)
		(sheetname "USER_IO_STATUS")
		(sheetfile "USER_IO_STATUS.kicad_sch")
		(duplicate_pad_numbers_are_jumpers no)
		(pad "1" smd rect
			(at -0.75 0 90)
			(size 0.95 0.95)
			(layers "F.Cu" "F.Mask" "F.Paste")
			(net "GND")
		)
		(pad "2" smd rect
			(at 0.75 0 90)
			(size 0.95 0.95)
			(layers "F.Cu" "F.Mask" "F.Paste")
			(net "NetR41_2")
		)
	)
	(footprint "Vault:FP-STPS5L60S-MFG"
		(layer "F.Cu")
		(at 234.0261 112.9162 90)
		(property "Reference" "D12"
			(at -0.354005 4.546148 270)
			(unlocked yes)
			(layer "F.SilkS")
			(effects
				(font
					(size 1.524 1.524)
					(thickness 0.254)
				)
			)
		)
		(property "Value" "STPS5L60S"
			(at -6.518402 3.795165 0)
			(unlocked yes)
			(layer "F.SilkS")
			(hide yes)
			(effects
				(font
					(size 1.524 1.524)
					(thickness 0.254)
				)
			)
		)
		(sheetname "POWER")
		(sheetfile "POWER.kicad_sch")
		(duplicate_pad_numbers_are_jumpers no)
		(fp_line
			(start 3.575 -3.125)
			(end 3.575 -2.025)
			(stroke
				(width 0.2)
				(type solid)
			)
			(layer "F.SilkS")
		)
		(fp_line
			(start -3.575 -3.125)
			(end 3.575 -3.125)
			(stroke
				(width 0.2)
				(type solid)
			)
			(layer "F.SilkS")
		)
		(fp_line
			(start -3.575 -3.125)
			(end -3.575 -2.025)
			(stroke
				(width 0.2)
				(type solid)
			)
			(layer "F.SilkS")
		)
		(fp_line
			(start 3.575 2.025)
			(end 3.575 3.125)
			(stroke
				(width 0.2)
				(type solid)
			)
			(layer "F.SilkS")
		)
		(fp_line
			(start -3.575 2.025)
			(end -3.575 3.125)
			(stroke
				(width 0.2)
				(type solid)
			)
			(layer "F.SilkS")
		)
		(fp_line
			(start -3.575 3.125)
			(end 3.575 3.125)
			(stroke
				(width 0.2)
				(type solid)
			)
			(layer "F.SilkS")
		)
		(fp_circle
			(center -4.7 -0.025)
			(end -4.575 -0.025)
			(stroke
				(width 0.25)
				(type solid)
			)
			(fill no)
			(layer "F.SilkS")
		)
		(fp_line
			(start 4.195 -3.225)
			(end 4.195 3.225)
			(stroke
				(width 0.2)
				(type solid)
			)
			(layer "F.CrtYd")
		)
		(fp_line
			(start -4.195 -3.225)
			(end 4.195 -3.225)
			(stroke
				(width 0.2)
				(type solid)
			)
			(layer "F.CrtYd")
		)
		(fp_line
			(start -4.195 -3.225)
			(end -4.195 3.225)
			(stroke
				(width 0.2)
				(type solid)
			)
			(layer "F.CrtYd")
		)
		(fp_line
			(start -4.195 3.225)
			(end 4.195 3.225)
			(stroke
				(width 0.2)
				(type solid)
			)
			(layer "F.CrtYd")
		)
		(fp_line
			(start 4.195 -3.225)
			(end 4.195 3.225)
			(stroke
				(width 0.2)
				(type solid)
			)
			(layer "F.Fab")
		)
		(fp_line
			(start -4.195 -3.225)
			(end 4.195 -3.225)
			(stroke
				(width 0.2)
				(type solid)
			)
			(layer "F.Fab")
		)
		(fp_line
			(start -4.195 -3.225)
			(end -4.195 3.225)
			(stroke
				(width 0.2)
				(type solid)
			)
			(layer "F.Fab")
		)
		(fp_line
			(start 0 -0.5)
			(end 0 0.5)
			(stroke
				(width 0.1)
				(type solid)
			)
			(layer "F.Fab")
		)
		(fp_line
			(start -0.5 0)
			(end 0.5 0)
			(stroke
				(width 0.1)
				(type solid)
			)
			(layer "F.Fab")
		)
		(fp_line
			(start -4.195 3.225)
			(end 4.195 3.225)
			(stroke
				(width 0.2)
				(type solid)
			)
			(layer "F.Fab")
		)
		(fp_text user "${REFERENCE}"
			(at -0.00001 0.10711 90)
			(unlocked yes)
			(layer "F.Fab")
			(effects
				(font
					(face "Arial")
					(size 0.63 0.63)
					(thickness 0.1)
				)
				(justify left bottom)
			)
		)
		(pad "1" smd rect
			(at -3.325 0 90)
			(size 1.54 3.14)
			(layers "F.Cu" "F.Mask" "F.Paste")
			(net "NetD12_1")
			(solder_mask_margin 0)
			(solder_paste_margin 0)
		)
		(pad "2" smd rect
			(at 3.325 0 90)
			(size 1.54 3.14)
			(layers "F.Cu" "F.Mask" "F.Paste")
			(net "NetD12_2")
			(solder_mask_margin 0)
			(solder_paste_margin 0)
		)
	)
	(footprint "Capacitors:CAPC1005X06N"
		(layer "B.Cu")
		(at 115.5621 151.7886 90)
		(property "Reference" "C44"
			(at 2.885 -1.204345 270)
			(unlocked yes)
			(layer "B.SilkS")
			(effects
				(font
					(size 0.762 0.762)
					(thickness 0.2286)
				)
				(justify left bottom mirror)
			)
		)
		(property "Value" "CAP_0402_0.1UF_50V"
			(at -3.47599 0.2921 0)
			(unlocked yes)
			(layer "B.SilkS")
			(hide yes)
			(effects
				(font
					(size 1.524 1.524)
					(thickness 0.254)
				)
				(justify left bottom mirror)
			)
		)
		(sheetname "PCIe_JTAG")
		(sheetfile "PCIe_JTAG.kicad_sch")
		(duplicate_pad_numbers_are_jumpers no)
		(pad "1" smd rect
			(at -0.43 0)
			(size 0.64 0.68)
			(layers "B.Cu" "B.Mask" "B.Paste")
			(net "NetC44_1")
		)
		(pad "2" smd rect
			(at 0.43 0)
			(size 0.64 0.68)
			(layers "B.Cu" "B.Mask" "B.Paste")
			(net "PCIE_CLK_P")
		)
	)
	(footprint "Capacitors:CAPC1005X06N"
		(layer "B.Cu")
		(at 127.5001 151.7886 90)
		(property "Reference" "C50"
			(at 2.41349 -0.766255 270)
			(unlocked yes)
			(layer "B.SilkS")
			(effects
				(font
					(size 0.762 0.762)
					(thickness 0.2286)
				)
				(justify left bottom mirror)
			)
		)
		(property "Value" "CAP_0402_0.1UF_50V"
			(at -3.47599 0.2921 0)
			(unlocked yes)
			(layer "B.SilkS")
			(hide yes)
			(effects
				(font
					(size 1.524 1.524)
					(thickness 0.254)
				)
				(justify left bottom mirror)
			)
		)
		(sheetname "PCIe_JTAG")
		(sheetfile "PCIe_JTAG.kicad_sch")
		(duplicate_pad_numbers_are_jumpers no)
		(pad "1" smd rect
			(at -0.43 0)
			(size 0.64 0.68)
			(layers "B.Cu" "B.Mask" "B.Paste")
			(net "NetC50_1")
		)
		(pad "2" smd rect
			(at 0.43 0)
			(size 0.64 0.68)
			(layers "B.Cu" "B.Mask" "B.Paste")
			(net "PCIE_TX2_P")
		)
	)
	(footprint "Capacitors:CAPC1005X06N"
		(layer "B.Cu")
		(at 119.6769 151.7886 90)
		(property "Reference" "C47"
			(at 2.41349 0.097345 270)
			(unlocked yes)
			(layer "B.SilkS")
			(effects
				(font
					(size 0.762 0.762)
					(thickness 0.2286)
				)
				(justify left bottom mirror)
			)
		)
		(property "Value" "CAP_0402_0.1UF_50V"
			(at -3.47599 0.2921 0)
			(unlocked yes)
			(layer "B.SilkS")
			(hide yes)
			(effects
				(font
					(size 1.524 1.524)
					(thickness 0.254)
				)
				(justify left bottom mirror)
			)
		)
		(sheetname "PCIe_JTAG")
		(sheetfile "PCIe_JTAG.kicad_sch")
		(duplicate_pad_numbers_are_jumpers no)
		(pad "1" smd rect
			(at -0.43 0)
			(size 0.64 0.68)
			(layers "B.Cu" "B.Mask" "B.Paste")
			(net "NetC47_1")
		)
		(pad "2" smd rect
			(at 0.43 0)
			(size 0.64 0.68)
			(layers "B.Cu" "B.Mask" "B.Paste")
			(net "PCIE_TX0_N")
		)
	)
	(footprint "Capacitors:CAPC1005X06N"
		(layer "B.Cu")
		(at 116.5781 151.7886 90)
		(property "Reference" "C45"
			(at 2.835 -0.445345 270)
			(unlocked yes)
			(layer "B.SilkS")
			(effects
				(font
					(size 0.762 0.762)
					(thickness 0.2286)
				)
				(justify left bottom mirror)
			)
		)
		(property "Value" "CAP_0402_0.1UF_50V"
			(at -3.47599 0.2921 0)
			(unlocked yes)
			(layer "B.SilkS")
			(hide yes)
			(effects
				(font
					(size 1.524 1.524)
					(thickness 0.254)
				)
				(justify left bottom mirror)
			)
		)
		(sheetname "PCIe_JTAG")
		(sheetfile "PCIe_JTAG.kicad_sch")
		(duplicate_pad_numbers_are_jumpers no)
		(pad "1" smd rect
			(at -0.43 0)
			(size 0.64 0.68)
			(layers "B.Cu" "B.Mask" "B.Paste")
			(net "NetC45_1")
		)
		(pad "2" smd rect
			(at 0.43 0)
			(size 0.64 0.68)
			(layers "B.Cu" "B.Mask" "B.Paste")
			(net "PCIE_CLK_N")
		)
	)
	(footprint "Capacitors:CAPC1005X06N"
		(layer "B.Cu")
		(at 123.5631 151.7886 90)
		(property "Reference" "C48"
			(at 2.41349 -0.867855 270)
			(unlocked yes)
			(layer "B.SilkS")
			(effects
				(font
					(size 0.762 0.762)
					(thickness 0.2286)
				)
				(justify left bottom mirror)
			)
		)
		(property "Value" "CAP_0402_0.1UF_50V"
			(at -3.47599 0.2921 0)
			(unlocked yes)
			(layer "B.SilkS")
			(hide yes)
			(effects
				(font
					(size 1.524 1.524)
					(thickness 0.254)
				)
				(justify left bottom mirror)
			)
		)
		(sheetname "PCIe_JTAG")
		(sheetfile "PCIe_JTAG.kicad_sch")
		(duplicate_pad_numbers_are_jumpers no)
		(pad "1" smd rect
			(at -0.43 0)
			(size 0.64 0.68)
			(layers "B.Cu" "B.Mask" "B.Paste")
			(net "NetC48_1")
		)
		(pad "2" smd rect
			(at 0.43 0)
			(size 0.64 0.68)
			(layers "B.Cu" "B.Mask" "B.Paste")
			(net "PCIE_TX1_P")
		)
	)
	(footprint "Capacitors:CAPC1005X06N"
		(layer "B.Cu")
		(at 132.5801 151.7886 90)
		(property "Reference" "C53"
			(at 2.41349 0.046545 270)
			(unlocked yes)
			(layer "B.SilkS")
			(effects
				(font
					(size 0.762 0.762)
					(thickness 0.2286)
				)
				(justify left bottom mirror)
			)
		)
		(property "Value" "CAP_0402_0.1UF_50V"
			(at -3.47599 0.2921 0)
			(unlocked yes)
			(layer "B.SilkS")
			(hide yes)
			(effects
				(font
					(size 1.524 1.524)
					(thickness 0.254)
				)
				(justify left bottom mirror)
			)
		)
		(sheetname "PCIe_JTAG")
		(sheetfile "PCIe_JTAG.kicad_sch")
		(duplicate_pad_numbers_are_jumpers no)
		(pad "1" smd rect
			(at -0.43 0)
			(size 0.64 0.68)
			(layers "B.Cu" "B.Mask" "B.Paste")
			(net "NetC53_1")
		)
		(pad "2" smd rect
			(at 0.43 0)
			(size 0.64 0.68)
			(layers "B.Cu" "B.Mask" "B.Paste")
			(net "PCIE_TX3_N")
		)
	)
	(footprint "Capacitors:CAPC1005X06N"
		(layer "B.Cu")
		(at 124.5791 151.7886 90)
		(property "Reference" "C49"
			(at 2.41349 -0.156655 270)
			(unlocked yes)
			(layer "B.SilkS")
			(effects
				(font
					(size 0.762 0.762)
					(thickness 0.2286)
				)
				(justify left bottom mirror)
			)
		)
		(property "Value" "CAP_0402_0.1UF_50V"
			(at -3.47599 0.2921 0)
			(unlocked yes)
			(layer "B.SilkS")
			(hide yes)
			(effects
				(font
					(size 1.524 1.524)
					(thickness 0.254)
				)
				(justify left bottom mirror)
			)
		)
		(sheetname "PCIe_JTAG")
		(sheetfile "PCIe_JTAG.kicad_sch")
		(duplicate_pad_numbers_are_jumpers no)
		(pad "1" smd rect
			(at -0.43 0)
			(size 0.64 0.68)
			(layers "B.Cu" "B.Mask" "B.Paste")
			(net "NetC49_1")
		)
		(pad "2" smd rect
			(at 0.43 0)
			(size 0.64 0.68)
			(layers "B.Cu" "B.Mask" "B.Paste")
			(net "PCIE_TX1_N")
		)
	)
	(footprint "Capacitors:CAPC1005X06N"
		(layer "B.Cu")
		(at 131.5641 151.7886 90)
		(property "Reference" "C52"
			(at 2.41349 -0.613855 270)
			(unlocked yes)
			(layer "B.SilkS")
			(effects
				(font
					(size 0.762 0.762)
					(thickness 0.2286)
				)
				(justify left bottom mirror)
			)
		)
		(property "Value" "CAP_0402_0.1UF_50V"
			(at -3.47599 0.2921 0)
			(unlocked yes)
			(layer "B.SilkS")
			(hide yes)
			(effects
				(font
					(size 1.524 1.524)
					(thickness 0.254)
				)
				(justify left bottom mirror)
			)
		)
		(sheetname "PCIe_JTAG")
		(sheetfile "PCIe_JTAG.kicad_sch")
		(duplicate_pad_numbers_are_jumpers no)
		(pad "1" smd rect
			(at -0.43 0)
			(size 0.64 0.68)
			(layers "B.Cu" "B.Mask" "B.Paste")
			(net "NetC52_1")
		)
		(pad "2" smd rect
			(at 0.43 0)
			(size 0.64 0.68)
			(layers "B.Cu" "B.Mask" "B.Paste")
			(net "PCIE_TX3_P")
		)
	)
	(footprint "Capacitors:CAPC1005X06N"
		(layer "B.Cu")
		(at 118.5847 151.7886 90)
		(property "Reference" "C46"
			(at 2.41349 -0.563055 270)
			(unlocked yes)
			(layer "B.SilkS")
			(effects
				(font
					(size 0.762 0.762)
					(thickness 0.2286)
				)
				(justify left bottom mirror)
			)
		)
		(property "Value" "CAP_0402_0.1UF_50V"
			(at -3.47599 0.2921 0)
			(unlocked yes)
			(layer "B.SilkS")
			(hide yes)
			(effects
				(font
					(size 1.524 1.524)
					(thickness 0.254)
				)
				(justify left bottom mirror)
			)
		)
		(sheetname "PCIe_JTAG")
		(sheetfile "PCIe_JTAG.kicad_sch")
		(duplicate_pad_numbers_are_jumpers no)
		(pad "1" smd rect
			(at -0.43 0)
			(size 0.64 0.68)
			(layers "B.Cu" "B.Mask" "B.Paste")
			(net "NetC46_1")
		)
		(pad "2" smd rect
			(at 0.43 0)
			(size 0.64 0.68)
			(layers "B.Cu" "B.Mask" "B.Paste")
			(net "PCIE_TX0_P")
		)
	)
	(footprint "Capacitors:CAPC1005X06N"
		(layer "B.Cu")
		(at 128.3891 151.7886 90)
		(property "Reference" "C51"
			(at 2.41349 0.148145 270)
			(unlocked yes)
			(layer "B.SilkS")
			(effects
				(font
					(size 0.762 0.762)
					(thickness 0.2286)
				)
				(justify left bottom mirror)
			)
		)
		(property "Value" "CAP_0402_0.1UF_50V"
			(at -3.47599 0.2921 0)
			(unlocked yes)
			(layer "B.SilkS")
			(hide yes)
			(effects
				(font
					(size 1.524 1.524)
					(thickness 0.254)
				)
				(justify left bottom mirror)
			)
		)
		(sheetname "PCIe_JTAG")
		(sheetfile "PCIe_JTAG.kicad_sch")
		(duplicate_pad_numbers_are_jumpers no)
		(pad "1" smd rect
			(at -0.43 0)
			(size 0.64 0.68)
			(layers "B.Cu" "B.Mask" "B.Paste")
			(net "NetC51_1")
		)
		(pad "2" smd rect
			(at 0.43 0)
			(size 0.64 0.68)
			(layers "B.Cu" "B.Mask" "B.Paste")
			(net "PCIE_TX2_N")
		)
	)
	(gr_rect
		(start 101.3261 154.6036)
		(end 103.8511 152.8786)
		(stroke
			(width 0)
			(type default)
		)
		(fill yes)
		(layer "F.Cu")
		(net "+12V_PCIE")
	)
	(gr_rect
		(start 101.4261 153.0786)
		(end 103.83346 145.6162)
		(stroke
			(width 0)
			(type default)
		)
		(fill yes)
		(layer "F.Cu")
		(net "+12V_PCIE")
	)
	(gr_rect
		(start 108.1261 154.5786)
		(end 110.93108 152.8786)
		(stroke
			(width 0)
			(type default)
		)
		(fill yes)
		(layer "F.Cu")
		(net "+3.3V_PCIE")
	)
	(gr_poly
		(pts
			(xy 151.7636 64.37564) (xy 151.7636 64.38937) (xy 151.7636 64.4031) (xy 151.7636 64.41684) (xy 151.7636 64.43057)
			(xy 151.7636 64.4443) (xy 151.7636 64.45803) (xy 151.7636 64.47176) (xy 151.7636 64.4855) (xy 151.7636 64.49923)
			(xy 151.7636 64.51296) (xy 151.7636 64.52669) (xy 151.7636 64.54042) (xy 151.7636 64.55416) (xy 151.7636 64.56789)
			(xy 151.7636 64.58162) (xy 151.7636 64.59535) (xy 151.7636 64.60908) (xy 151.7636 64.62281) (xy 151.7636 64.63655)
			(xy 151.7636 64.65028) (xy 151.7636 64.66401) (xy 151.7636 64.67774) (xy 151.7636 64.69147) (xy 151.7636 64.7052)
			(xy 151.7636 64.71894) (xy 151.7636 64.73267) (xy 151.7636 64.7464) (xy 151.7636 64.76013) (xy 151.7636 64.77386)
			(xy 151.7636 64.78759) (xy 151.7636 64.80133) (xy 151.7636 64.81506) (xy 151.7636 64.82879) (xy 151.7636 64.84252)
			(xy 151.7636 64.85625) (xy 151.7636 64.86998) (xy 151.7636 64.88372) (xy 151.7636 64.89745) (xy 151.7636 64.91118)
			(xy 151.7636 64.92491) (xy 151.7636 64.93864) (xy 151.7636 64.95238) (xy 151.7636 64.96611) (xy 151.7636 64.97984)
			(xy 151.7636 64.99357) (xy 151.7636 65.0073) (xy 151.7636 65.02104) (xy 151.7636 65.03477) (xy 151.7636 65.0485)
			(xy 151.7636 65.06223) (xy 151.7636 65.07596) (xy 151.7636 65.08969) (xy 152.79348 65.08969) (xy 152.79348 65.07596)
			(xy 152.79348 65.06223) (xy 152.79348 65.0485) (xy 152.79348 65.03477) (xy 152.79348 65.02104) (xy 152.79348 65.0073)
			(xy 152.79348 64.99357) (xy 152.79348 64.97984) (xy 152.79348 64.96611) (xy 152.79348 64.95238) (xy 152.79348 64.93864)
			(xy 152.79348 64.92491) (xy 152.79348 64.91118) (xy 152.79348 64.89745) (xy 152.79348 64.88372) (xy 152.79348 64.86998)
			(xy 152.79348 64.85625) (xy 152.79348 64.84252) (xy 152.79348 64.82879) (xy 152.79348 64.81506) (xy 152.79348 64.80133)
			(xy 152.79348 64.78759) (xy 152.79348 64.77386) (xy 152.79348 64.76013) (xy 152.79348 64.7464) (xy 152.79348 64.73267)
			(xy 152.79348 64.71894) (xy 152.79348 64.7052) (xy 152.79348 64.69147) (xy 152.79348 64.67774) (xy 152.79348 64.66401)
			(xy 152.79348 64.65028) (xy 152.79348 64.63655) (xy 152.79348 64.62281) (xy 152.79348 64.60908) (xy 152.79348 64.59535)
			(xy 152.79348 64.58162) (xy 152.79348 64.56789) (xy 152.79348 64.55416) (xy 152.79348 64.54042) (xy 152.79348 64.52669)
			(xy 152.79348 64.51296) (xy 152.79348 64.49923) (xy 152.79348 64.4855) (xy 152.79348 64.47176) (xy 152.79348 64.45803)
			(xy 152.79348 64.4443) (xy 152.79348 64.43057) (xy 152.79348 64.41684) (xy 152.79348 64.4031) (xy 152.79348 64.38937)
			(xy 152.79348 64.37564) (xy 152.79348 64.36191) (xy 151.7636 64.36191)
		)
		(stroke
			(width 0)
			(type default)
		)
		(fill yes)
		(layer "B.Cu")
	)
	(gr_poly
		(pts
			(xy 162.85885 68.39905) (xy 162.80393 68.39905) (xy 162.80393 68.41278) (xy 162.77646 68.41278) (xy 162.77646 68.42651)
			(xy 162.749 68.42651) (xy 162.749 68.44024) (xy 162.72154 68.44024) (xy 162.72154 68.45397) (xy 162.69407 68.45397)
			(xy 162.69407 68.4677) (xy 162.68034 68.4677) (xy 162.68034 68.48144) (xy 162.65288 68.48144) (xy 162.65288 68.49517)
			(xy 162.63915 68.49517) (xy 162.63915 68.5089) (xy 162.62542 68.5089) (xy 162.62542 68.52263) (xy 162.61168 68.52263)
			(xy 162.61168 68.53636) (xy 162.59795 68.53636) (xy 162.59795 68.55009) (xy 162.58422 68.55009) (xy 162.58422 68.56383)
			(xy 162.57049 68.56383) (xy 162.57049 68.57756) (xy 162.55676 68.57756) (xy 162.55676 68.59129) (xy 162.55676 68.60502)
			(xy 162.54302 68.60502) (xy 162.54302 68.61875) (xy 162.52929 68.61875) (xy 162.52929 68.63248) (xy 162.52929 68.64622)
			(xy 162.51556 68.64622) (xy 162.51556 68.65995) (xy 162.51556 68.67368) (xy 162.50183 68.67368) (xy 162.50183 68.68741)
			(xy 162.50183 68.70114) (xy 162.4881 68.70114) (xy 162.4881 68.71488) (xy 162.4881 68.72861) (xy 162.4881 68.74234)
			(xy 162.47436 68.74234) (xy 162.47436 68.75607) (xy 162.47436 68.7698) (xy 162.47436 68.78354) (xy 162.47436 68.79727)
			(xy 162.47436 68.811) (xy 162.46063 68.811) (xy 162.46063 68.82473) (xy 162.46063 68.83846) (xy 162.46063 68.85219)
			(xy 162.46063 68.86593) (xy 162.46063 68.87966) (xy 162.46063 68.89339) (xy 162.46063 68.90712) (xy 162.46063 68.92085)
			(xy 162.46063 68.93458) (xy 162.46063 68.94832) (xy 162.46063 68.96205) (xy 162.46063 68.97578) (xy 162.47436 68.97578)
			(xy 162.47436 68.98951) (xy 162.47436 69.00324) (xy 162.47436 69.01697) (xy 162.47436 69.03071) (xy 162.47436 69.04444)
			(xy 162.4881 69.04444) (xy 162.4881 69.05817) (xy 162.4881 69.0719) (xy 162.4881 69.08563) (xy 162.50183 69.08563)
			(xy 162.50183 69.09936) (xy 162.50183 69.1131) (xy 162.51556 69.1131) (xy 162.51556 69.12683) (xy 162.51556 69.14056)
			(xy 162.52929 69.14056) (xy 162.52929 69.15429) (xy 162.52929 69.16802) (xy 162.54302 69.16802) (xy 162.54302 69.18175)
			(xy 162.55676 69.18175) (xy 162.55676 69.19549) (xy 162.55676 69.20922) (xy 162.57049 69.20922) (xy 162.57049 69.22295)
			(xy 162.58422 69.22295) (xy 162.58422 69.23668) (xy 162.59795 69.23668) (xy 162.59795 69.25041) (xy 162.61168 69.25041)
			(xy 162.61168 69.26415) (xy 162.62542 69.26415) (xy 162.62542 69.27788) (xy 162.63915 69.27788) (xy 162.63915 69.29161)
			(xy 162.65288 69.29161) (xy 162.65288 69.30534) (xy 162.68034 69.30534) (xy 162.68034 69.31907) (xy 162.69407 69.31907)
			(xy 162.69407 69.33281) (xy 162.72154 69.33281) (xy 162.72154 69.34654) (xy 162.749 69.34654) (xy 162.749 69.36027)
			(xy 162.77646 69.36027) (xy 162.77646 69.374) (xy 162.81766 69.374) (xy 162.81766 69.38773) (xy 162.85885 69.38773)
			(xy 162.85885 69.40146) (xy 163.09229 69.40146) (xy 163.09229 69.38773) (xy 163.13349 69.38773) (xy 163.13349 69.374)
			(xy 163.17468 69.374) (xy 163.17468 69.36027) (xy 163.20215 69.36027) (xy 163.20215 69.34654) (xy 163.22961 69.34654)
			(xy 163.22961 69.33281) (xy 163.25707 69.33281) (xy 163.25707 69.31907) (xy 163.27081 69.31907) (xy 163.27081 69.30534)
			(xy 163.28454 69.30534) (xy 163.28454 69.29161) (xy 163.312 69.29161) (xy 163.312 69.27788) (xy 163.32573 69.27788)
			(xy 163.32573 69.26415) (xy 163.33946 69.26415) (xy 163.33946 69.25041) (xy 163.3532 69.25041) (xy 163.3532 69.23668)
			(xy 163.36693 69.23668) (xy 163.36693 69.22295) (xy 163.38066 69.22295) (xy 163.38066 69.20922) (xy 163.38066 69.19549)
			(xy 163.39439 69.19549) (xy 163.39439 69.18175) (xy 163.40812 69.18175) (xy 163.40812 69.16802) (xy 163.40812 69.15429)
			(xy 163.42185 69.15429) (xy 163.42185 69.14056) (xy 163.42185 69.12683) (xy 163.43559 69.12683) (xy 163.43559 69.1131)
			(xy 163.43559 69.09936) (xy 163.44932 69.09936) (xy 163.44932 69.08563) (xy 163.44932 69.0719) (xy 163.46305 69.0719)
			(xy 163.46305 69.05817) (xy 163.46305 69.04444) (xy 163.46305 69.03071) (xy 163.47678 69.03071) (xy 163.47678 69.01697)
			(xy 163.47678 69.00324) (xy 163.47678 68.98951) (xy 163.47678 68.97578) (xy 163.47678 68.96205) (xy 163.49051 68.96205)
			(xy 163.49051 68.94832) (xy 163.49051 68.93458) (xy 163.49051 68.92085) (xy 163.49051 68.90712) (xy 163.49051 68.89339)
			(xy 163.49051 68.87966) (xy 163.49051 68.86593) (xy 163.49051 68.85219) (xy 163.49051 68.83846) (xy 163.49051 68.82473)
			(xy 163.47678 68.82473) (xy 163.47678 68.811) (xy 163.47678 68.79727) (xy 163.47678 68.78354) (xy 163.47678 68.7698)
			(xy 163.47678 68.75607) (xy 163.46305 68.75607) (xy 163.46305 68.74234) (xy 163.46305 68.72861) (xy 163.46305 68.71488)
			(xy 163.44932 68.71488) (xy 163.44932 68.70114) (xy 163.44932 68.68741) (xy 163.43559 68.68741) (xy 163.43559 68.67368)
			(xy 163.43559 68.65995) (xy 163.42185 68.65995) (xy 163.42185 68.64622) (xy 163.42185 68.63248) (xy 163.40812 68.63248)
			(xy 163.40812 68.61875) (xy 163.40812 68.60502) (xy 163.39439 68.60502) (xy 163.39439 68.59129) (xy 163.38066 68.59129)
			(xy 163.38066 68.57756) (xy 163.38066 68.56383) (xy 163.36693 68.56383) (xy 163.36693 68.55009) (xy 163.3532 68.55009)
			(xy 163.3532 68.53636) (xy 163.33946 68.53636) (xy 163.33946 68.52263) (xy 163.32573 68.52263) (xy 163.32573 68.5089)
			(xy 163.312 68.5089) (xy 163.312 68.49517) (xy 163.29827 68.49517) (xy 163.29827 68.48144) (xy 163.27081 68.48144)
			(xy 163.27081 68.4677) (xy 163.25707 68.4677) (xy 163.25707 68.45397) (xy 163.22961 68.45397) (xy 163.22961 68.44024)
			(xy 163.20215 68.44024) (xy 163.20215 68.42651) (xy 163.17468 68.42651) (xy 163.17468 68.41278) (xy 163.13349 68.41278)
			(xy 163.13349 68.39905) (xy 163.09229 68.39905) (xy 163.09229 68.38531) (xy 162.85885 68.38531)
		)
		(stroke
			(width 0)
			(type default)
		)
		(fill yes)
		(layer "B.Cu")
	)
	(gr_poly
		(pts
			(xy 148.8662 64.4031) (xy 148.83874 64.4031) (xy 148.83874 64.41684) (xy 148.83874 64.43057) (xy 148.83874 64.4443)
			(xy 148.83874 64.45803) (xy 148.83874 64.47176) (xy 148.83874 64.4855) (xy 148.83874 64.49923) (xy 148.83874 64.51296)
			(xy 148.83874 64.52669) (xy 148.83874 64.54042) (xy 148.83874 64.55416) (xy 148.83874 64.56789) (xy 148.83874 64.58162)
			(xy 148.83874 64.59535) (xy 148.83874 64.60908) (xy 148.83874 64.62281) (xy 148.83874 64.63655) (xy 148.83874 64.65028)
			(xy 148.83874 64.66401) (xy 148.83874 64.67774) (xy 148.83874 64.69147) (xy 148.83874 64.7052) (xy 148.83874 64.71894)
			(xy 148.83874 64.73267) (xy 148.83874 64.7464) (xy 148.83874 64.76013) (xy 148.83874 64.77386) (xy 148.83874 64.78759)
			(xy 148.83874 64.80133) (xy 148.83874 64.81506) (xy 148.83874 64.82879) (xy 148.83874 64.84252) (xy 148.83874 64.85625)
			(xy 148.83874 64.86998) (xy 148.83874 64.88372) (xy 148.83874 64.89745) (xy 148.83874 64.91118) (xy 148.83874 64.92491)
			(xy 148.83874 64.93864) (xy 148.83874 64.95238) (xy 148.83874 64.96611) (xy 148.83874 64.97984) (xy 148.83874 64.99357)
			(xy 148.83874 65.0073) (xy 148.83874 65.02104) (xy 148.83874 65.03477) (xy 148.83874 65.0485) (xy 148.83874 65.06223)
			(xy 148.83874 65.07596) (xy 148.83874 65.08969) (xy 148.83874 65.10343) (xy 148.83874 65.11716) (xy 148.83874 65.13089)
			(xy 148.83874 65.14462) (xy 148.83874 65.15835) (xy 148.83874 65.17208) (xy 148.83874 65.18582) (xy 148.83874 65.19955)
			(xy 148.83874 65.21328) (xy 148.83874 65.22701) (xy 148.83874 65.24074) (xy 148.83874 65.25447) (xy 148.83874 65.26821)
			(xy 148.83874 65.28194) (xy 148.83874 65.29567) (xy 148.83874 65.3094) (xy 148.83874 65.32313) (xy 148.83874 65.33686)
			(xy 148.83874 65.3506) (xy 148.83874 65.36433) (xy 148.83874 65.37806) (xy 148.83874 65.39179) (xy 148.83874 65.40552)
			(xy 148.83874 65.41925) (xy 148.83874 65.43299) (xy 148.83874 65.44672) (xy 148.83874 65.46045) (xy 148.83874 65.47418)
			(xy 148.83874 65.48791) (xy 148.83874 65.50165) (xy 148.83874 65.51538) (xy 148.83874 65.52911) (xy 148.83874 65.54284)
			(xy 148.83874 65.55657) (xy 148.83874 65.57031) (xy 148.83874 65.58404) (xy 148.83874 65.59777) (xy 148.83874 65.6115)
			(xy 148.83874 65.62523) (xy 148.83874 65.63896) (xy 148.83874 65.6527) (xy 148.83874 65.66643) (xy 148.83874 65.68016)
			(xy 148.83874 65.69389) (xy 148.83874 65.70762) (xy 148.83874 65.72135) (xy 148.83874 65.73509) (xy 148.83874 65.74882)
			(xy 148.83874 65.76255) (xy 148.83874 65.77628) (xy 148.83874 65.79001) (xy 148.83874 65.80374) (xy 148.83874 65.81748)
			(xy 148.83874 65.83121) (xy 148.83874 65.84494) (xy 148.83874 65.85867) (xy 148.83874 65.8724) (xy 148.83874 65.88613)
			(xy 148.83874 65.89987) (xy 148.83874 65.9136) (xy 148.83874 65.92733) (xy 149.84115 65.92733) (xy 149.84115 65.9136)
			(xy 149.84115 65.89987) (xy 149.84115 65.88613) (xy 149.84115 65.8724) (xy 149.84115 65.85867) (xy 149.84115 65.84494)
			(xy 149.84115 65.83121) (xy 149.84115 65.81748) (xy 149.84115 65.80374) (xy 149.84115 65.79001) (xy 149.84115 65.77628)
			(xy 149.84115 65.76255) (xy 149.84115 65.74882) (xy 149.84115 65.73509) (xy 149.84115 65.72135) (xy 149.84115 65.70762)
			(xy 149.84115 65.69389) (xy 149.84115 65.68016) (xy 149.84115 65.66643) (xy 149.84115 65.6527) (xy 149.84115 65.63896)
			(xy 149.84115 65.62523) (xy 149.84115 65.6115) (xy 149.84115 65.59777) (xy 149.84115 65.58404) (xy 149.84115 65.57031)
			(xy 149.84115 65.55657) (xy 149.84115 65.54284) (xy 149.84115 65.52911) (xy 149.84115 65.51538) (xy 149.84115 65.50165)
			(xy 149.84115 65.48791) (xy 149.84115 65.47418) (xy 149.84115 65.46045) (xy 149.84115 65.44672) (xy 149.84115 65.43299)
			(xy 149.84115 65.41925) (xy 149.84115 65.40552) (xy 149.84115 65.39179) (xy 149.84115 65.37806) (xy 149.84115 65.36433)
			(xy 149.84115 65.3506) (xy 149.84115 65.33686) (xy 149.84115 65.32313) (xy 149.84115 65.3094) (xy 149.84115 65.29567)
			(xy 149.84115 65.28194) (xy 149.84115 65.26821) (xy 149.84115 65.25447) (xy 149.84115 65.24074) (xy 149.84115 65.22701)
			(xy 149.84115 65.21328) (xy 149.84115 65.19955) (xy 149.84115 65.18582) (xy 149.84115 65.17208) (xy 149.84115 65.15835)
			(xy 149.84115 65.14462) (xy 149.84115 65.13089) (xy 149.84115 65.11716) (xy 149.84115 65.10343) (xy 149.84115 65.08969)
			(xy 149.84115 65.07596) (xy 149.84115 65.06223) (xy 149.84115 65.0485) (xy 149.84115 65.03477) (xy 149.84115 65.02104)
			(xy 149.84115 65.0073) (xy 149.84115 64.99357) (xy 149.84115 64.97984) (xy 149.84115 64.96611) (xy 149.84115 64.95238)
			(xy 149.84115 64.93864) (xy 149.84115 64.92491) (xy 149.84115 64.91118) (xy 149.84115 64.89745) (xy 149.84115 64.88372)
			(xy 149.84115 64.86998) (xy 149.84115 64.85625) (xy 149.84115 64.84252) (xy 149.84115 64.82879) (xy 149.84115 64.81506)
			(xy 149.84115 64.80133) (xy 149.84115 64.78759) (xy 149.84115 64.77386) (xy 149.84115 64.76013) (xy 149.84115 64.7464)
			(xy 149.84115 64.73267) (xy 149.84115 64.71894) (xy 149.84115 64.7052) (xy 149.84115 64.69147) (xy 149.84115 64.67774)
			(xy 149.84115 64.66401) (xy 149.84115 64.65028) (xy 149.84115 64.63655) (xy 149.84115 64.62281) (xy 149.84115 64.60908)
			(xy 149.84115 64.59535) (xy 149.84115 64.58162) (xy 149.84115 64.56789) (xy 149.84115 64.55416) (xy 149.84115 64.54042)
			(xy 149.84115 64.52669) (xy 149.84115 64.51296) (xy 149.84115 64.49923) (xy 149.84115 64.4855) (xy 149.84115 64.47176)
			(xy 149.84115 64.45803) (xy 149.84115 64.4443) (xy 149.84115 64.43057) (xy 149.84115 64.41684) (xy 149.84115 64.4031)
			(xy 149.82742 64.4031) (xy 149.82742 64.38937) (xy 149.81369 64.38937) (xy 149.81369 64.4031) (xy 148.92113 64.4031)
			(xy 148.92113 64.38937) (xy 148.9074 64.38937) (xy 148.9074 64.4031) (xy 148.87993 64.4031) (xy 148.87993 64.38937)
			(xy 148.8662 64.38937)
		)
		(stroke
			(width 0)
			(type default)
		)
		(fill yes)
		(layer "B.Cu")
	)
	(gr_poly
		(pts
			(xy 162.87259 62.82395) (xy 162.81766 62.82395) (xy 162.81766 62.83769) (xy 162.77646 62.83769) (xy 162.77646 62.85142)
			(xy 162.749 62.85142) (xy 162.749 62.86515) (xy 162.72154 62.86515) (xy 162.72154 62.87888) (xy 162.70781 62.87888)
			(xy 162.70781 62.89261) (xy 162.68034 62.89261) (xy 162.68034 62.90635) (xy 162.66661 62.90635) (xy 162.66661 62.92008)
			(xy 162.63915 62.92008) (xy 162.63915 62.93381) (xy 162.62542 62.93381) (xy 162.62542 62.94754) (xy 162.61168 62.94754)
			(xy 162.61168 62.96127) (xy 162.59795 62.96127) (xy 162.59795 62.97501) (xy 162.58422 62.97501) (xy 162.58422 62.98874)
			(xy 162.57049 62.98874) (xy 162.57049 63.00247) (xy 162.57049 63.0162) (xy 162.55676 63.0162) (xy 162.55676 63.02993)
			(xy 162.54302 63.02993) (xy 162.54302 63.04366) (xy 162.54302 63.0574) (xy 162.52929 63.0574) (xy 162.52929 63.07113)
			(xy 162.51556 63.07113) (xy 162.51556 63.08486) (xy 162.51556 63.09859) (xy 162.50183 63.09859) (xy 162.50183 63.11232)
			(xy 162.50183 63.12605) (xy 162.50183 63.13979) (xy 162.4881 63.13979) (xy 162.4881 63.15352) (xy 162.4881 63.16725)
			(xy 162.4881 63.18098) (xy 162.47436 63.18098) (xy 162.47436 63.19471) (xy 162.47436 63.20844) (xy 162.47436 63.22218)
			(xy 162.47436 63.23591) (xy 162.46063 63.23591) (xy 162.46063 63.24964) (xy 162.46063 63.26337) (xy 162.46063 63.2771)
			(xy 162.46063 63.29083) (xy 162.46063 63.30457) (xy 162.46063 63.3183) (xy 162.46063 63.33203) (xy 162.46063 63.34576)
			(xy 162.46063 63.35949) (xy 162.46063 63.37322) (xy 162.46063 63.38696) (xy 162.46063 63.40069) (xy 162.46063 63.41442)
			(xy 162.47436 63.41442) (xy 162.47436 63.42815) (xy 162.47436 63.44188) (xy 162.47436 63.45562) (xy 162.47436 63.46935)
			(xy 162.4881 63.46935) (xy 162.4881 63.48308) (xy 162.4881 63.49681) (xy 162.4881 63.51054) (xy 162.50183 63.51054)
			(xy 162.50183 63.52428) (xy 162.50183 63.53801) (xy 162.51556 63.53801) (xy 162.51556 63.55174) (xy 162.51556 63.56547)
			(xy 162.52929 63.56547) (xy 162.52929 63.5792) (xy 162.52929 63.59293) (xy 162.54302 63.59293) (xy 162.54302 63.60667)
			(xy 162.55676 63.60667) (xy 162.55676 63.6204) (xy 162.55676 63.63413) (xy 162.57049 63.63413) (xy 162.57049 63.64786)
			(xy 162.58422 63.64786) (xy 162.58422 63.66159) (xy 162.59795 63.66159) (xy 162.59795 63.67532) (xy 162.61168 63.67532)
			(xy 162.61168 63.68906) (xy 162.62542 63.68906) (xy 162.62542 63.70279) (xy 162.63915 63.70279) (xy 162.63915 63.71652)
			(xy 162.65288 63.71652) (xy 162.65288 63.73025) (xy 162.66661 63.73025) (xy 162.66661 63.74398) (xy 162.69407 63.74398)
			(xy 162.69407 63.75771) (xy 162.70781 63.75771) (xy 162.70781 63.77145) (xy 162.73527 63.77145) (xy 162.73527 63.78518)
			(xy 162.76273 63.78518) (xy 162.76273 63.79891) (xy 162.80393 63.79891) (xy 162.80393 63.81264) (xy 162.84512 63.81264)
			(xy 162.84512 63.82637) (xy 162.92751 63.82637) (xy 162.92751 63.8401) (xy 163.02363 63.8401) (xy 163.02363 63.82637)
			(xy 163.10603 63.82637) (xy 163.10603 63.81264) (xy 163.14722 63.81264) (xy 163.14722 63.79891) (xy 163.17468 63.79891)
			(xy 163.17468 63.78518) (xy 163.21588 63.78518) (xy 163.21588 63.77145) (xy 163.22961 63.77145) (xy 163.22961 63.75771)
			(xy 163.25707 63.75771) (xy 163.25707 63.74398) (xy 163.27081 63.74398) (xy 163.27081 63.73025) (xy 163.29827 63.73025)
			(xy 163.29827 63.71652) (xy 163.312 63.71652) (xy 163.312 63.70279) (xy 163.32573 63.70279) (xy 163.32573 63.68906)
			(xy 163.33946 63.68906) (xy 163.33946 63.67532) (xy 163.3532 63.67532) (xy 163.3532 63.66159) (xy 163.36693 63.66159)
			(xy 163.36693 63.64786) (xy 163.38066 63.64786) (xy 163.38066 63.63413) (xy 163.39439 63.63413) (xy 163.39439 63.6204)
			(xy 163.39439 63.60667) (xy 163.40812 63.60667) (xy 163.40812 63.59293) (xy 163.40812 63.5792) (xy 163.42185 63.5792)
			(xy 163.42185 63.56547) (xy 163.43559 63.56547) (xy 163.43559 63.55174) (xy 163.43559 63.53801) (xy 163.44932 63.53801)
			(xy 163.44932 63.52428) (xy 163.44932 63.51054) (xy 163.44932 63.49681) (xy 163.46305 63.49681) (xy 163.46305 63.48308)
			(xy 163.46305 63.46935) (xy 163.46305 63.45562) (xy 163.47678 63.45562) (xy 163.47678 63.44188) (xy 163.47678 63.42815)
			(xy 163.47678 63.41442) (xy 163.47678 63.40069) (xy 163.47678 63.38696) (xy 163.49051 63.38696) (xy 163.49051 63.37322)
			(xy 163.49051 63.35949) (xy 163.49051 63.34576) (xy 163.49051 63.33203) (xy 163.49051 63.3183) (xy 163.49051 63.30457)
			(xy 163.49051 63.29083) (xy 163.49051 63.2771) (xy 163.49051 63.26337) (xy 163.49051 63.24964) (xy 163.47678 63.24964)
			(xy 163.47678 63.23591) (xy 163.47678 63.22218) (xy 163.47678 63.20844) (xy 163.47678 63.19471) (xy 163.47678 63.18098)
			(xy 163.46305 63.18098) (xy 163.46305 63.16725) (xy 163.46305 63.15352) (xy 163.46305 63.13979) (xy 163.44932 63.13979)
			(xy 163.44932 63.12605) (xy 163.44932 63.11232) (xy 163.43559 63.11232) (xy 163.43559 63.09859) (xy 163.43559 63.08486)
			(xy 163.42185 63.08486) (xy 163.42185 63.07113) (xy 163.42185 63.0574) (xy 163.40812 63.0574) (xy 163.40812 63.04366)
			(xy 163.40812 63.02993) (xy 163.39439 63.02993) (xy 163.39439 63.0162) (xy 163.38066 63.0162) (xy 163.38066 63.00247)
			(xy 163.36693 63.00247) (xy 163.36693 62.98874) (xy 163.36693 62.97501) (xy 163.3532 62.97501) (xy 163.3532 62.96127)
			(xy 163.33946 62.96127) (xy 163.33946 62.94754) (xy 163.32573 62.94754) (xy 163.32573 62.93381) (xy 163.29827 62.93381)
			(xy 163.29827 62.92008) (xy 163.28454 62.92008) (xy 163.28454 62.90635) (xy 163.27081 62.90635) (xy 163.27081 62.89261)
			(xy 163.24334 62.89261) (xy 163.24334 62.87888) (xy 163.22961 62.87888) (xy 163.22961 62.86515) (xy 163.20215 62.86515)
			(xy 163.20215 62.85142) (xy 163.16095 62.85142) (xy 163.16095 62.83769) (xy 163.13349 62.83769) (xy 163.13349 62.82395)
			(xy 163.07856 62.82395) (xy 163.07856 62.81022) (xy 162.87259 62.81022)
		)
		(stroke
			(width 0)
			(type default)
		)
		(fill yes)
		(layer "B.Cu")
	)
	(gr_poly
		(pts
			(xy 162.88632 64.67774) (xy 162.83139 64.67774) (xy 162.83139 64.69147) (xy 162.7902 64.69147) (xy 162.7902 64.7052)
			(xy 162.76273 64.7052) (xy 162.76273 64.71894) (xy 162.73527 64.71894) (xy 162.73527 64.73267) (xy 162.70781 64.73267)
			(xy 162.70781 64.7464) (xy 162.68034 64.7464) (xy 162.68034 64.76013) (xy 162.66661 64.76013) (xy 162.66661 64.77386)
			(xy 162.65288 64.77386) (xy 162.65288 64.78759) (xy 162.62542 64.78759) (xy 162.62542 64.80133) (xy 162.61168 64.80133)
			(xy 162.61168 64.81506) (xy 162.59795 64.81506) (xy 162.59795 64.82879) (xy 162.58422 64.82879) (xy 162.58422 64.84252)
			(xy 162.58422 64.85625) (xy 162.57049 64.85625) (xy 162.57049 64.86998) (xy 162.55676 64.86998) (xy 162.55676 64.88372)
			(xy 162.54302 64.88372) (xy 162.54302 64.89745) (xy 162.54302 64.91118) (xy 162.52929 64.91118) (xy 162.52929 64.92491)
			(xy 162.52929 64.93864) (xy 162.51556 64.93864) (xy 162.51556 64.95238) (xy 162.51556 64.96611) (xy 162.50183 64.96611)
			(xy 162.50183 64.97984) (xy 162.50183 64.99357) (xy 162.4881 64.99357) (xy 162.4881 65.0073) (xy 162.4881 65.02104)
			(xy 162.4881 65.03477) (xy 162.47436 65.03477) (xy 162.47436 65.0485) (xy 162.47436 65.06223) (xy 162.47436 65.07596)
			(xy 162.47436 65.08969) (xy 162.46063 65.08969) (xy 162.46063 65.10343) (xy 162.46063 65.11716) (xy 162.46063 65.13089)
			(xy 162.46063 65.14462) (xy 162.46063 65.15835) (xy 162.46063 65.17208) (xy 162.46063 65.18582) (xy 162.46063 65.19955)
			(xy 162.46063 65.21328) (xy 162.46063 65.22701) (xy 162.46063 65.24074) (xy 162.46063 65.25447) (xy 162.46063 65.26821)
			(xy 162.47436 65.26821) (xy 162.47436 65.28194) (xy 162.47436 65.29567) (xy 162.47436 65.3094) (xy 162.47436 65.32313)
			(xy 162.4881 65.32313) (xy 162.4881 65.33686) (xy 162.4881 65.3506) (xy 162.4881 65.36433) (xy 162.50183 65.36433)
			(xy 162.50183 65.37806) (xy 162.50183 65.39179) (xy 162.51556 65.39179) (xy 162.51556 65.40552) (xy 162.51556 65.41925)
			(xy 162.52929 65.41925) (xy 162.52929 65.43299) (xy 162.52929 65.44672) (xy 162.54302 65.44672) (xy 162.54302 65.46045)
			(xy 162.54302 65.47418) (xy 162.55676 65.47418) (xy 162.55676 65.48791) (xy 162.57049 65.48791) (xy 162.57049 65.50165)
			(xy 162.58422 65.50165) (xy 162.58422 65.51538) (xy 162.58422 65.52911) (xy 162.59795 65.52911) (xy 162.59795 65.54284)
			(xy 162.61168 65.54284) (xy 162.61168 65.55657) (xy 162.63915 65.55657) (xy 162.63915 65.57031) (xy 162.65288 65.57031)
			(xy 162.65288 65.58404) (xy 162.66661 65.58404) (xy 162.66661 65.59777) (xy 162.68034 65.59777) (xy 162.68034 65.6115)
			(xy 162.70781 65.6115) (xy 162.70781 65.62523) (xy 162.73527 65.62523) (xy 162.73527 65.63896) (xy 162.76273 65.63896)
			(xy 162.76273 65.6527) (xy 162.7902 65.6527) (xy 162.7902 65.66643) (xy 162.83139 65.66643) (xy 162.83139 65.68016)
			(xy 162.90005 65.68016) (xy 162.90005 65.69389) (xy 163.0511 65.69389) (xy 163.0511 65.68016) (xy 163.11976 65.68016)
			(xy 163.11976 65.66643) (xy 163.16095 65.66643) (xy 163.16095 65.6527) (xy 163.18842 65.6527) (xy 163.18842 65.63896)
			(xy 163.21588 65.63896) (xy 163.21588 65.62523) (xy 163.24334 65.62523) (xy 163.24334 65.6115) (xy 163.25707 65.6115)
			(xy 163.25707 65.59777) (xy 163.28454 65.59777) (xy 163.28454 65.58404) (xy 163.29827 65.58404) (xy 163.29827 65.57031)
			(xy 163.312 65.57031) (xy 163.312 65.55657) (xy 163.32573 65.55657) (xy 163.32573 65.54284) (xy 163.33946 65.54284)
			(xy 163.33946 65.52911) (xy 163.3532 65.52911) (xy 163.3532 65.51538) (xy 163.36693 65.51538) (xy 163.36693 65.50165)
			(xy 163.38066 65.50165) (xy 163.38066 65.48791) (xy 163.39439 65.48791) (xy 163.39439 65.47418) (xy 163.39439 65.46045)
			(xy 163.40812 65.46045) (xy 163.40812 65.44672) (xy 163.42185 65.44672) (xy 163.42185 65.43299) (xy 163.42185 65.41925)
			(xy 163.43559 65.41925) (xy 163.43559 65.40552) (xy 163.43559 65.39179) (xy 163.44932 65.39179) (xy 163.44932 65.37806)
			(xy 163.44932 65.36433) (xy 163.44932 65.3506) (xy 163.46305 65.3506) (xy 163.46305 65.33686) (xy 163.46305 65.32313)
			(xy 163.46305 65.3094) (xy 163.47678 65.3094) (xy 163.47678 65.29567) (xy 163.47678 65.28194) (xy 163.47678 65.26821)
			(xy 163.47678 65.25447) (xy 163.49051 65.25447) (xy 163.49051 65.24074) (xy 163.49051 65.22701) (xy 163.49051 65.21328)
			(xy 163.49051 65.19955) (xy 163.49051 65.18582) (xy 163.49051 65.17208) (xy 163.49051 65.15835) (xy 163.49051 65.14462)
			(xy 163.49051 65.13089) (xy 163.49051 65.11716) (xy 163.49051 65.10343) (xy 163.47678 65.10343) (xy 163.47678 65.08969)
			(xy 163.47678 65.07596) (xy 163.47678 65.06223) (xy 163.47678 65.0485) (xy 163.46305 65.0485) (xy 163.46305 65.03477)
			(xy 163.46305 65.02104) (xy 163.46305 65.0073) (xy 163.46305 64.99357) (xy 163.44932 64.99357) (xy 163.44932 64.97984)
			(xy 163.44932 64.96611) (xy 163.43559 64.96611) (xy 163.43559 64.95238) (xy 163.43559 64.93864) (xy 163.42185 64.93864)
			(xy 163.42185 64.92491) (xy 163.42185 64.91118) (xy 163.40812 64.91118) (xy 163.40812 64.89745) (xy 163.39439 64.89745)
			(xy 163.39439 64.88372) (xy 163.39439 64.86998) (xy 163.38066 64.86998) (xy 163.38066 64.85625) (xy 163.36693 64.85625)
			(xy 163.36693 64.84252) (xy 163.3532 64.84252) (xy 163.3532 64.82879) (xy 163.33946 64.82879) (xy 163.33946 64.81506)
			(xy 163.32573 64.81506) (xy 163.32573 64.80133) (xy 163.312 64.80133) (xy 163.312 64.78759) (xy 163.29827 64.78759)
			(xy 163.29827 64.77386) (xy 163.28454 64.77386) (xy 163.28454 64.76013) (xy 163.25707 64.76013) (xy 163.25707 64.7464)
			(xy 163.24334 64.7464) (xy 163.24334 64.73267) (xy 163.21588 64.73267) (xy 163.21588 64.71894) (xy 163.18842 64.71894)
			(xy 163.18842 64.7052) (xy 163.16095 64.7052) (xy 163.16095 64.69147) (xy 163.11976 64.69147) (xy 163.11976 64.67774)
			(xy 163.0511 64.67774) (xy 163.0511 64.66401) (xy 162.88632 64.66401)
		)
		(stroke
			(width 0)
			(type default)
		)
		(fill yes)
		(layer "B.Cu")
	)
	(gr_poly
		(pts
			(xy 162.91378 66.53153) (xy 162.84512 66.53153) (xy 162.84512 66.54526) (xy 162.80393 66.54526) (xy 162.80393 66.55899)
			(xy 162.76273 66.55899) (xy 162.76273 66.57272) (xy 162.73527 66.57272) (xy 162.73527 66.58645) (xy 162.70781 66.58645)
			(xy 162.70781 66.60019) (xy 162.69407 66.60019) (xy 162.69407 66.61392) (xy 162.66661 66.61392) (xy 162.66661 66.62765)
			(xy 162.65288 66.62765) (xy 162.65288 66.64138) (xy 162.63915 66.64138) (xy 162.63915 66.65511) (xy 162.62542 66.65511)
			(xy 162.62542 66.66885) (xy 162.61168 66.66885) (xy 162.61168 66.68258) (xy 162.59795 66.68258) (xy 162.59795 66.69631)
			(xy 162.58422 66.69631) (xy 162.58422 66.71004) (xy 162.57049 66.71004) (xy 162.57049 66.72377) (xy 162.55676 66.72377)
			(xy 162.55676 66.7375) (xy 162.55676 66.75124) (xy 162.54302 66.75124) (xy 162.54302 66.76497) (xy 162.52929 66.76497)
			(xy 162.52929 66.7787) (xy 162.52929 66.79243) (xy 162.51556 66.79243) (xy 162.51556 66.80616) (xy 162.51556 66.81989)
			(xy 162.50183 66.81989) (xy 162.50183 66.83363) (xy 162.50183 66.84736) (xy 162.4881 66.84736) (xy 162.4881 66.86109)
			(xy 162.4881 66.87482) (xy 162.4881 66.88855) (xy 162.47436 66.88855) (xy 162.47436 66.90228) (xy 162.47436 66.91602)
			(xy 162.47436 66.92975) (xy 162.47436 66.94348) (xy 162.46063 66.94348) (xy 162.46063 66.95721) (xy 162.46063 66.97094)
			(xy 162.46063 66.98467) (xy 162.46063 66.99841) (xy 162.46063 67.01214) (xy 162.46063 67.02587) (xy 162.46063 67.0396)
			(xy 162.46063 67.05333) (xy 162.46063 67.06707) (xy 162.46063 67.0808) (xy 162.46063 67.09453) (xy 162.46063 67.10826)
			(xy 162.46063 67.12199) (xy 162.47436 67.12199) (xy 162.47436 67.13573) (xy 162.47436 67.14946) (xy 162.47436 67.16319)
			(xy 162.47436 67.17692) (xy 162.4881 67.17692) (xy 162.4881 67.19065) (xy 162.4881 67.20438) (xy 162.4881 67.21812)
			(xy 162.50183 67.21812) (xy 162.50183 67.23185) (xy 162.50183 67.24558) (xy 162.50183 67.25931) (xy 162.51556 67.25931)
			(xy 162.51556 67.27304) (xy 162.51556 67.28677) (xy 162.52929 67.28677) (xy 162.52929 67.30051) (xy 162.54302 67.30051)
			(xy 162.54302 67.31424) (xy 162.54302 67.32797) (xy 162.55676 67.32797) (xy 162.55676 67.3417) (xy 162.57049 67.3417)
			(xy 162.57049 67.35543) (xy 162.57049 67.36916) (xy 162.58422 67.36916) (xy 162.58422 67.3829) (xy 162.59795 67.3829)
			(xy 162.59795 67.39663) (xy 162.61168 67.39663) (xy 162.61168 67.41036) (xy 162.62542 67.41036) (xy 162.62542 67.42409)
			(xy 162.63915 67.42409) (xy 162.63915 67.43782) (xy 162.66661 67.43782) (xy 162.66661 67.45155) (xy 162.68034 67.45155)
			(xy 162.68034 67.46529) (xy 162.70781 67.46529) (xy 162.70781 67.47902) (xy 162.72154 67.47902) (xy 162.72154 67.49275)
			(xy 162.749 67.49275) (xy 162.749 67.50648) (xy 162.7902 67.50648) (xy 162.7902 67.52021) (xy 162.81766 67.52021)
			(xy 162.81766 67.53394) (xy 162.87259 67.53394) (xy 162.87259 67.54768) (xy 163.07856 67.54768) (xy 163.07856 67.53394)
			(xy 163.11976 67.53394) (xy 163.11976 67.52021) (xy 163.16095 67.52021) (xy 163.16095 67.50648) (xy 163.20215 67.50648)
			(xy 163.20215 67.49275) (xy 163.21588 67.49275) (xy 163.21588 67.47902) (xy 163.24334 67.47902) (xy 163.24334 67.46529)
			(xy 163.27081 67.46529) (xy 163.27081 67.45155) (xy 163.28454 67.45155) (xy 163.28454 67.43782) (xy 163.29827 67.43782)
			(xy 163.29827 67.42409) (xy 163.32573 67.42409) (xy 163.32573 67.41036) (xy 163.33946 67.41036) (xy 163.33946 67.39663)
			(xy 163.3532 67.39663) (xy 163.3532 67.3829) (xy 163.36693 67.3829) (xy 163.36693 67.36916) (xy 163.36693 67.35543)
			(xy 163.38066 67.35543) (xy 163.38066 67.3417) (xy 163.39439 67.3417) (xy 163.39439 67.32797) (xy 163.40812 67.32797)
			(xy 163.40812 67.31424) (xy 163.40812 67.30051) (xy 163.42185 67.30051) (xy 163.42185 67.28677) (xy 163.42185 67.27304)
			(xy 163.43559 67.27304) (xy 163.43559 67.25931) (xy 163.43559 67.24558) (xy 163.44932 67.24558) (xy 163.44932 67.23185)
			(xy 163.44932 67.21812) (xy 163.46305 67.21812) (xy 163.46305 67.20438) (xy 163.46305 67.19065) (xy 163.46305 67.17692)
			(xy 163.47678 67.17692) (xy 163.47678 67.16319) (xy 163.47678 67.14946) (xy 163.47678 67.13573) (xy 163.47678 67.12199)
			(xy 163.47678 67.10826) (xy 163.49051 67.10826) (xy 163.49051 67.09453) (xy 163.49051 67.0808) (xy 163.49051 67.06707)
			(xy 163.49051 67.05333) (xy 163.49051 67.0396) (xy 163.49051 67.02587) (xy 163.49051 67.01214) (xy 163.49051 66.99841)
			(xy 163.49051 66.98467) (xy 163.49051 66.97094) (xy 163.47678 66.97094) (xy 163.47678 66.95721) (xy 163.47678 66.94348)
			(xy 163.47678 66.92975) (xy 163.47678 66.91602) (xy 163.47678 66.90228) (xy 163.46305 66.90228) (xy 163.46305 66.88855)
			(xy 163.46305 66.87482) (xy 163.46305 66.86109) (xy 163.44932 66.86109) (xy 163.44932 66.84736) (xy 163.44932 66.83363)
			(xy 163.44932 66.81989) (xy 163.43559 66.81989) (xy 163.43559 66.80616) (xy 163.43559 66.79243) (xy 163.42185 66.79243)
			(xy 163.42185 66.7787) (xy 163.42185 66.76497) (xy 163.40812 66.76497) (xy 163.40812 66.75124) (xy 163.39439 66.75124)
			(xy 163.39439 66.7375) (xy 163.39439 66.72377) (xy 163.38066 66.72377) (xy 163.38066 66.71004) (xy 163.36693 66.71004)
			(xy 163.36693 66.69631) (xy 163.3532 66.69631) (xy 163.3532 66.68258) (xy 163.33946 66.68258) (xy 163.33946 66.66885)
			(xy 163.32573 66.66885) (xy 163.32573 66.65511) (xy 163.312 66.65511) (xy 163.312 66.64138) (xy 163.29827 66.64138)
			(xy 163.29827 66.62765) (xy 163.28454 66.62765) (xy 163.28454 66.61392) (xy 163.25707 66.61392) (xy 163.25707 66.60019)
			(xy 163.22961 66.60019) (xy 163.22961 66.58645) (xy 163.21588 66.58645) (xy 163.21588 66.57272) (xy 163.18842 66.57272)
			(xy 163.18842 66.55899) (xy 163.14722 66.55899) (xy 163.14722 66.54526) (xy 163.10603 66.54526) (xy 163.10603 66.53153)
			(xy 163.03737 66.53153) (xy 163.03737 66.51779) (xy 162.91378 66.51779)
		)
		(stroke
			(width 0)
			(type default)
		)
		(fill yes)
		(layer "B.Cu")
	)
	(gr_poly
		(pts
			(xy 142.06898 57.08408) (xy 141.93166 57.08408) (xy 141.93166 57.09781) (xy 141.86301 57.09781) (xy 141.86301 57.11155)
			(xy 141.80808 57.11155) (xy 141.80808 57.12528) (xy 141.78062 57.12528) (xy 141.78062 57.13901) (xy 141.73942 57.13901)
			(xy 141.73942 57.15274) (xy 141.71196 57.15274) (xy 141.71196 57.16647) (xy 141.67076 57.16647) (xy 141.67076 57.18021)
			(xy 141.65703 57.18021) (xy 141.65703 57.19394) (xy 141.62957 57.19394) (xy 141.62957 57.20767) (xy 141.6021 57.20767)
			(xy 141.6021 57.2214) (xy 141.58837 57.2214) (xy 141.58837 57.23513) (xy 141.56091 57.23513) (xy 141.56091 57.24886)
			(xy 141.54718 57.24886) (xy 141.54718 57.2626) (xy 141.51971 57.2626) (xy 141.51971 57.27633) (xy 141.50598 57.27633)
			(xy 141.50598 57.29006) (xy 141.49225 57.29006) (xy 141.49225 57.30379) (xy 141.47852 57.30379) (xy 141.47852 57.31752)
			(xy 141.46479 57.31752) (xy 141.46479 57.33125) (xy 141.45105 57.33125) (xy 141.45105 57.34499) (xy 141.43732 57.34499)
			(xy 141.43732 57.35872) (xy 141.42359 57.35872) (xy 141.42359 57.37245) (xy 141.40986 57.37245) (xy 141.40986 57.38618)
			(xy 141.39613 57.38618) (xy 141.39613 57.39991) (xy 141.38239 57.39991) (xy 141.38239 57.41364) (xy 141.36866 57.41364)
			(xy 141.36866 57.42738) (xy 141.36866 57.44111) (xy 141.35493 57.44111) (xy 141.35493 57.45484) (xy 141.3412 57.45484)
			(xy 141.3412 57.46857) (xy 141.3412 57.4823) (xy 141.32747 57.4823) (xy 141.32747 57.49603) (xy 141.31374 57.49603)
			(xy 141.31374 57.50977) (xy 141.31374 57.5235) (xy 141.3 57.5235) (xy 141.3 57.53723) (xy 141.3 57.55096)
			(xy 141.28627 57.55096) (xy 141.28627 57.56469) (xy 141.27254 57.56469) (xy 141.27254 57.57842) (xy 141.27254 57.59216)
			(xy 141.25881 57.59216) (xy 141.25881 57.60589) (xy 141.25881 57.61962) (xy 141.25881 57.63335) (xy 141.24508 57.63335)
			(xy 141.24508 57.64708) (xy 141.24508 57.66082) (xy 141.23135 57.66082) (xy 141.23135 57.67455) (xy 141.23135 57.68828)
			(xy 141.23135 57.70201) (xy 141.21761 57.70201) (xy 141.21761 57.71574) (xy 141.21761 57.72948) (xy 141.21761 57.74321)
			(xy 141.21761 57.75694) (xy 141.20388 57.75694) (xy 141.20388 57.77067) (xy 141.20388 57.7844) (xy 141.20388 57.79813)
			(xy 141.20388 57.81187) (xy 141.19015 57.81187) (xy 141.19015 57.8256) (xy 141.19015 57.83933) (xy 141.19015 57.85306)
			(xy 141.19015 57.86679) (xy 141.19015 57.88052) (xy 141.19015 57.89426) (xy 141.19015 57.90799) (xy 141.19015 57.92172)
			(xy 141.19015 57.93545) (xy 141.19015 57.94918) (xy 141.17642 57.94918) (xy 141.17642 57.96291) (xy 141.17642 57.97665)
			(xy 141.17642 57.99038) (xy 141.17642 58.00411) (xy 141.19015 58.00411) (xy 141.19015 58.01784) (xy 141.19015 58.03157)
			(xy 141.19015 58.0453) (xy 141.19015 58.05904) (xy 141.19015 58.07277) (xy 141.19015 58.0865) (xy 141.19015 58.10023)
			(xy 141.19015 58.11396) (xy 141.19015 58.1277) (xy 141.20388 58.1277) (xy 141.20388 58.14143) (xy 141.20388 58.15516)
			(xy 141.20388 58.16889) (xy 141.20388 58.18262) (xy 141.20388 58.19636) (xy 141.21761 58.19636) (xy 141.21761 58.21009)
			(xy 141.21761 58.22382) (xy 141.21761 58.23755) (xy 141.23135 58.23755) (xy 141.23135 58.25128) (xy 141.23135 58.26501)
			(xy 141.23135 58.27875) (xy 141.24508 58.27875) (xy 141.24508 58.29248) (xy 141.24508 58.30621) (xy 141.24508 58.31994)
			(xy 141.25881 58.31994) (xy 141.25881 58.33367) (xy 141.25881 58.3474) (xy 141.27254 58.3474) (xy 141.27254 58.36114)
			(xy 141.27254 58.37487) (xy 141.28627 58.37487) (xy 141.28627 58.3886) (xy 141.28627 58.40233) (xy 141.3 58.40233)
			(xy 141.3 58.41606) (xy 141.3 58.42979) (xy 141.31374 58.42979) (xy 141.31374 58.44353) (xy 141.31374 58.45726)
			(xy 141.32747 58.45726) (xy 141.32747 58.47099) (xy 141.3412 58.47099) (xy 141.3412 58.48472) (xy 141.3412 58.49845)
			(xy 141.35493 58.49845) (xy 141.35493 58.51218) (xy 141.36866 58.51218) (xy 141.36866 58.52592) (xy 141.38239 58.52592)
			(xy 141.38239 58.53965) (xy 141.38239 58.55338) (xy 141.39613 58.55338) (xy 141.39613 58.56711) (xy 141.40986 58.56711)
			(xy 141.40986 58.58084) (xy 141.42359 58.58084) (xy 141.42359 58.59457) (xy 141.43732 58.59457) (xy 141.43732 58.60831)
			(xy 141.45105 58.60831) (xy 141.45105 58.62204) (xy 141.46479 58.62204) (xy 141.46479 58.63577) (xy 141.47852 58.63577)
			(xy 141.47852 58.6495) (xy 141.49225 58.6495) (xy 141.49225 58.66323) (xy 141.51971 58.66323) (xy 141.51971 58.67697)
			(xy 141.53345 58.67697) (xy 141.53345 58.6907) (xy 141.54718 58.6907) (xy 141.54718 58.70443) (xy 141.56091 58.70443)
			(xy 141.56091 58.71816) (xy 141.58837 58.71816) (xy 141.58837 58.73189) (xy 141.6021 58.73189) (xy 141.6021 58.74563)
			(xy 141.62957 58.74563) (xy 141.62957 58.75936) (xy 141.65703 58.75936) (xy 141.65703 58.77309) (xy 141.68449 58.77309)
			(xy 141.68449 58.78682) (xy 141.71196 58.78682) (xy 141.71196 58.80055) (xy 141.73942 58.80055) (xy 141.73942 58.81428)
			(xy 141.78062 58.81428) (xy 141.78062 58.82802) (xy 141.82181 58.82802) (xy 141.82181 58.84175) (xy 141.87674 58.84175)
			(xy 141.87674 58.85548) (xy 141.9454 58.85548) (xy 141.9454 58.86921) (xy 143.27738 58.86921) (xy 143.27738 58.85548)
			(xy 143.34604 58.85548) (xy 143.34604 58.84175) (xy 143.38723 58.84175) (xy 143.38723 58.82802) (xy 143.42843 58.82802)
			(xy 143.42843 58.81428) (xy 143.46962 58.81428) (xy 143.46962 58.80055) (xy 143.49708 58.80055) (xy 143.49708 58.78682)
			(xy 143.53828 58.78682) (xy 143.53828 58.77309) (xy 143.55201 58.77309) (xy 143.55201 58.75936) (xy 143.57948 58.75936)
			(xy 143.57948 58.74563) (xy 143.60694 58.74563) (xy 143.60694 58.73189) (xy 143.62067 58.73189) (xy 143.62067 58.71816)
			(xy 143.64814 58.71816) (xy 143.64814 58.70443) (xy 143.66187 58.70443) (xy 143.66187 58.6907) (xy 143.68933 58.6907)
			(xy 143.68933 58.67697) (xy 143.70306 58.67697) (xy 143.70306 58.66323) (xy 143.71679 58.66323) (xy 143.71679 58.6495)
			(xy 143.73053 58.6495) (xy 143.73053 58.63577) (xy 143.74426 58.63577) (xy 143.74426 58.62204) (xy 143.75799 58.62204)
			(xy 143.75799 58.60831) (xy 143.77172 58.60831) (xy 143.77172 58.59457) (xy 143.78545 58.59457) (xy 143.78545 58.58084)
			(xy 143.79918 58.58084) (xy 143.79918 58.56711) (xy 143.81292 58.56711) (xy 143.81292 58.55338) (xy 143.82665 58.55338)
			(xy 143.82665 58.53965) (xy 143.84038 58.53965) (xy 143.84038 58.52592) (xy 143.84038 58.51218) (xy 143.85411 58.51218)
			(xy 143.85411 58.49845) (xy 143.86784 58.49845) (xy 143.86784 58.48472) (xy 143.88157 58.48472) (xy 143.88157 58.47099)
			(xy 143.88157 58.45726) (xy 143.89531 58.45726) (xy 143.89531 58.44353) (xy 143.89531 58.42979) (xy 143.90904 58.42979)
			(xy 143.90904 58.41606) (xy 143.92277 58.41606) (xy 143.92277 58.40233) (xy 143.92277 58.3886) (xy 143.9365 58.3886)
			(xy 143.9365 58.37487) (xy 143.9365 58.36114) (xy 143.95023 58.36114) (xy 143.95023 58.3474) (xy 143.95023 58.33367)
			(xy 143.96396 58.33367) (xy 143.96396 58.31994) (xy 143.96396 58.30621) (xy 143.96396 58.29248) (xy 143.9777 58.29248)
			(xy 143.9777 58.27875) (xy 143.9777 58.26501) (xy 143.9777 58.25128) (xy 143.99143 58.25128) (xy 143.99143 58.23755)
			(xy 143.99143 58.22382) (xy 143.99143 58.21009) (xy 144.00516 58.21009) (xy 144.00516 58.19636) (xy 144.00516 58.18262)
			(xy 144.00516 58.16889) (xy 144.00516 58.15516) (xy 144.00516 58.14143) (xy 144.01889 58.14143) (xy 144.01889 58.1277)
			(xy 144.01889 58.11396) (xy 144.01889 58.10023) (xy 144.01889 58.0865) (xy 144.01889 58.07277) (xy 144.03262 58.07277)
			(xy 144.03262 58.05904) (xy 144.03262 58.0453) (xy 144.03262 58.03157) (xy 144.03262 58.01784) (xy 144.03262 58.00411)
			(xy 144.03262 57.99038) (xy 144.03262 57.97665) (xy 144.03262 57.96291) (xy 144.03262 57.94918) (xy 144.03262 57.93545)
			(xy 144.03262 57.92172) (xy 144.03262 57.90799) (xy 144.03262 57.89426) (xy 144.01889 57.89426) (xy 144.01889 57.88052)
			(xy 144.01889 57.86679) (xy 144.01889 57.85306) (xy 144.01889 57.83933) (xy 144.01889 57.8256) (xy 144.01889 57.81187)
			(xy 144.01889 57.79813) (xy 144.00516 57.79813) (xy 144.00516 57.7844) (xy 144.00516 57.77067) (xy 144.00516 57.75694)
			(xy 144.00516 57.74321) (xy 143.99143 57.74321) (xy 143.99143 57.72948) (xy 143.99143 57.71574) (xy 143.99143 57.70201)
			(xy 143.99143 57.68828) (xy 143.9777 57.68828) (xy 143.9777 57.67455) (xy 143.9777 57.66082) (xy 143.96396 57.66082)
			(xy 143.96396 57.64708) (xy 143.96396 57.63335) (xy 143.96396 57.61962) (xy 143.95023 57.61962) (xy 143.95023 57.60589)
			(xy 143.95023 57.59216) (xy 143.9365 57.59216) (xy 143.9365 57.57842) (xy 143.9365 57.56469) (xy 143.92277 57.56469)
			(xy 143.92277 57.55096) (xy 143.92277 57.53723) (xy 143.90904 57.53723) (xy 143.90904 57.5235) (xy 143.90904 57.50977)
			(xy 143.89531 57.50977) (xy 143.89531 57.49603) (xy 143.88157 57.49603) (xy 143.88157 57.4823) (xy 143.88157 57.46857)
			(xy 143.86784 57.46857) (xy 143.86784 57.45484) (xy 143.85411 57.45484) (xy 143.85411 57.44111) (xy 143.85411 57.42738)
			(xy 143.84038 57.42738) (xy 143.84038 57.41364) (xy 143.82665 57.41364) (xy 143.82665 57.39991) (xy 143.81292 57.39991)
			(xy 143.81292 57.38618) (xy 143.79918 57.38618) (xy 143.79918 57.37245) (xy 143.78545 57.37245) (xy 143.78545 57.35872)
			(xy 143.77172 57.35872) (xy 143.77172 57.34499) (xy 143.75799 57.34499) (xy 143.75799 57.33125) (xy 143.74426 57.33125)
			(xy 143.74426 57.31752) (xy 143.73053 57.31752) (xy 143.73053 57.30379) (xy 143.71679 57.30379) (xy 143.71679 57.29006)
			(xy 143.70306 57.29006) (xy 143.70306 57.27633) (xy 143.68933 57.27633) (xy 143.68933 57.2626) (xy 143.6756 57.2626)
			(xy 143.6756 57.24886) (xy 143.64814 57.24886) (xy 143.64814 57.23513) (xy 143.6344 57.23513) (xy 143.6344 57.2214)
			(xy 143.60694 57.2214) (xy 143.60694 57.20767) (xy 143.59321 57.20767) (xy 143.59321 57.19394) (xy 143.56574 57.19394)
			(xy 143.56574 57.18021) (xy 143.53828 57.18021) (xy 143.53828 57.16647) (xy 143.51082 57.16647) (xy 143.51082 57.15274)
			(xy 143.46962 57.15274) (xy 143.46962 57.13901) (xy 143.44216 57.13901) (xy 143.44216 57.12528) (xy 143.40096 57.12528)
			(xy 143.40096 57.11155) (xy 143.34604 57.11155) (xy 143.34604 57.09781) (xy 143.29111 57.09781) (xy 143.29111 57.08408)
			(xy 143.14006 57.08408) (xy 143.14006 57.07035) (xy 142.09645 57.07035) (xy 142.09645 57.08408) (xy 142.08272 57.08408)
			(xy 142.08272 57.07035) (xy 142.06898 57.07035)
		)
		(stroke
			(width 0)
			(type default)
		)
		(fill yes)
		(layer "B.Cu")
	)
	(gr_poly
		(pts
			(xy 138.91068 64.25206) (xy 138.82829 64.25206) (xy 138.82829 64.26579) (xy 138.77336 64.26579) (xy 138.77336 64.27952)
			(xy 138.73217 64.27952) (xy 138.73217 64.29325) (xy 138.69097 64.29325) (xy 138.69097 64.30698) (xy 138.66351 64.30698)
			(xy 138.66351 64.32071) (xy 138.62231 64.32071) (xy 138.62231 64.33445) (xy 138.59485 64.33445) (xy 138.59485 64.34818)
			(xy 138.58112 64.34818) (xy 138.58112 64.36191) (xy 138.55365 64.36191) (xy 138.55365 64.37564) (xy 138.52619 64.37564)
			(xy 138.52619 64.38937) (xy 138.51246 64.38937) (xy 138.51246 64.4031) (xy 138.485 64.4031) (xy 138.485 64.41684)
			(xy 138.47126 64.41684) (xy 138.47126 64.43057) (xy 138.45753 64.43057) (xy 138.45753 64.4443) (xy 138.4438 64.4443)
			(xy 138.4438 64.45803) (xy 138.41634 64.45803) (xy 138.41634 64.47176) (xy 138.40261 64.47176) (xy 138.40261 64.4855)
			(xy 138.38887 64.4855) (xy 138.38887 64.49923) (xy 138.37514 64.49923) (xy 138.37514 64.51296) (xy 138.36141 64.51296)
			(xy 138.36141 64.52669) (xy 138.34768 64.52669) (xy 138.34768 64.54042) (xy 138.33395 64.54042) (xy 138.33395 64.55416)
			(xy 138.32022 64.55416) (xy 138.32022 64.56789) (xy 138.32022 64.58162) (xy 138.30648 64.58162) (xy 138.30648 64.59535)
			(xy 138.29275 64.59535) (xy 138.29275 64.60908) (xy 138.27902 64.60908) (xy 138.27902 64.62281) (xy 138.27902 64.63655)
			(xy 138.26529 64.63655) (xy 138.26529 64.65028) (xy 138.25156 64.65028) (xy 138.25156 64.66401) (xy 138.25156 64.67774)
			(xy 138.23782 64.67774) (xy 138.23782 64.69147) (xy 138.23782 64.7052) (xy 138.22409 64.7052) (xy 138.22409 64.71894)
			(xy 138.21036 64.71894) (xy 138.21036 64.73267) (xy 138.21036 64.7464) (xy 138.19663 64.7464) (xy 138.19663 64.76013)
			(xy 138.19663 64.77386) (xy 138.19663 64.78759) (xy 138.1829 64.78759) (xy 138.1829 64.80133) (xy 138.1829 64.81506)
			(xy 138.16916 64.81506) (xy 138.16916 64.82879) (xy 138.16916 64.84252) (xy 138.16916 64.85625) (xy 138.15543 64.85625)
			(xy 138.15543 64.86998) (xy 138.15543 64.88372) (xy 138.15543 64.89745) (xy 138.1417 64.89745) (xy 138.1417 64.91118)
			(xy 138.1417 64.92491) (xy 138.1417 64.93864) (xy 138.1417 64.95238) (xy 138.12797 64.95238) (xy 138.12797 64.96611)
			(xy 138.12797 64.97984) (xy 138.12797 64.99357) (xy 138.12797 65.0073) (xy 138.12797 65.02104) (xy 138.12797 65.03477)
			(xy 138.11424 65.03477) (xy 138.11424 65.0485) (xy 138.11424 65.06223) (xy 138.11424 65.07596) (xy 138.11424 65.08969)
			(xy 138.11424 65.10343) (xy 138.11424 65.11716) (xy 138.11424 65.13089) (xy 138.11424 65.14462) (xy 138.11424 65.15835)
			(xy 138.11424 65.17208) (xy 138.11424 65.18582) (xy 138.11424 65.19955) (xy 138.11424 65.21328) (xy 138.11424 65.22701)
			(xy 138.11424 65.24074) (xy 138.12797 65.24074) (xy 138.12797 65.25447) (xy 138.12797 65.26821) (xy 138.12797 65.28194)
			(xy 138.12797 65.29567) (xy 138.12797 65.3094) (xy 138.12797 65.32313) (xy 138.1417 65.32313) (xy 138.1417 65.33686)
			(xy 138.1417 65.3506) (xy 138.1417 65.36433) (xy 138.1417 65.37806) (xy 138.15543 65.37806) (xy 138.15543 65.39179)
			(xy 138.15543 65.40552) (xy 138.15543 65.41925) (xy 138.16916 65.41925) (xy 138.16916 65.43299) (xy 138.16916 65.44672)
			(xy 138.16916 65.46045) (xy 138.1829 65.46045) (xy 138.1829 65.47418) (xy 138.1829 65.48791) (xy 138.19663 65.48791)
			(xy 138.19663 65.50165) (xy 138.19663 65.51538) (xy 138.21036 65.51538) (xy 138.21036 65.52911) (xy 138.21036 65.54284)
			(xy 138.22409 65.54284) (xy 138.22409 65.55657) (xy 138.22409 65.57031) (xy 138.23782 65.57031) (xy 138.23782 65.58404)
			(xy 138.23782 65.59777) (xy 138.25156 65.59777) (xy 138.25156 65.6115) (xy 138.26529 65.6115) (xy 138.26529 65.62523)
			(xy 138.26529 65.63896) (xy 138.27902 65.63896) (xy 138.27902 65.6527) (xy 138.29275 65.6527) (xy 138.29275 65.66643)
			(xy 138.29275 65.68016) (xy 138.30648 65.68016) (xy 138.30648 65.69389) (xy 138.32022 65.69389) (xy 138.32022 65.70762)
			(xy 138.33395 65.70762) (xy 138.33395 65.72135) (xy 138.34768 65.72135) (xy 138.34768 65.73509) (xy 138.36141 65.73509)
			(xy 138.36141 65.74882) (xy 138.37514 65.74882) (xy 138.37514 65.76255) (xy 138.38887 65.76255) (xy 138.38887 65.77628)
			(xy 138.40261 65.77628) (xy 138.40261 65.79001) (xy 138.41634 65.79001) (xy 138.41634 65.80374) (xy 138.43007 65.80374)
			(xy 138.43007 65.81748) (xy 138.4438 65.81748) (xy 138.4438 65.83121) (xy 138.45753 65.83121) (xy 138.45753 65.84494)
			(xy 138.485 65.84494) (xy 138.485 65.85867) (xy 138.49873 65.85867) (xy 138.49873 65.8724) (xy 138.51246 65.8724)
			(xy 138.51246 65.88613) (xy 138.53992 65.88613) (xy 138.53992 65.89987) (xy 138.56739 65.89987) (xy 138.56739 65.9136)
			(xy 138.58112 65.9136) (xy 138.58112 65.92733) (xy 138.60858 65.92733) (xy 138.60858 65.94106) (xy 138.63604 65.94106)
			(xy 138.63604 65.95479) (xy 138.67724 65.95479) (xy 138.67724 65.96852) (xy 138.7047 65.96852) (xy 138.7047 65.98226)
			(xy 138.7459 65.98226) (xy 138.7459 65.99599) (xy 138.80083 65.99599) (xy 138.80083 66.00972) (xy 138.86949 66.00972)
			(xy 138.86949 66.02345) (xy 138.95188 66.02345) (xy 138.95188 66.03718) (xy 138.96561 66.03718) (xy 138.96561 66.02345)
			(xy 138.97934 66.02345) (xy 138.97934 66.03718) (xy 138.99307 66.03718) (xy 138.99307 66.02345) (xy 139.0068 66.02345)
			(xy 139.0068 66.03718) (xy 139.10292 66.03718) (xy 139.10292 66.02345) (xy 139.19905 66.02345) (xy 139.19905 66.00972)
			(xy 139.2677 66.00972) (xy 139.2677 65.99599) (xy 139.3089 65.99599) (xy 139.3089 65.98226) (xy 139.3501 65.98226)
			(xy 139.3501 65.96852) (xy 139.39129 65.96852) (xy 139.39129 65.95479) (xy 139.41876 65.95479) (xy 139.41876 65.94106)
			(xy 139.44622 65.94106) (xy 139.44622 65.92733) (xy 139.47368 65.92733) (xy 139.47368 65.9136) (xy 139.50115 65.9136)
			(xy 139.50115 65.89987) (xy 139.51488 65.89987) (xy 139.51488 65.88613) (xy 139.54234 65.88613) (xy 139.54234 65.8724)
			(xy 139.55607 65.8724) (xy 139.55607 65.85867) (xy 139.58354 65.85867) (xy 139.58354 65.84494) (xy 139.59727 65.84494)
			(xy 139.59727 65.83121) (xy 139.611 65.83121) (xy 139.611 65.81748) (xy 139.62473 65.81748) (xy 139.62473 65.80374)
			(xy 139.65219 65.80374) (xy 139.65219 65.79001) (xy 139.66593 65.79001) (xy 139.66593 65.77628) (xy 139.67966 65.77628)
			(xy 139.67966 65.76255) (xy 139.69339 65.76255) (xy 139.69339 65.74882) (xy 139.70712 65.74882) (xy 139.70712 65.73509)
			(xy 139.72085 65.73509) (xy 139.72085 65.72135) (xy 139.72085 65.70762) (xy 139.73458 65.70762) (xy 139.73458 65.69389)
			(xy 139.74832 65.69389) (xy 139.74832 65.68016) (xy 139.76205 65.68016) (xy 139.76205 65.66643) (xy 139.77578 65.66643)
			(xy 139.77578 65.6527) (xy 139.77578 65.63896) (xy 139.78951 65.63896) (xy 139.78951 65.62523) (xy 139.80324 65.62523)
			(xy 139.80324 65.6115) (xy 139.80324 65.59777) (xy 139.81697 65.59777) (xy 139.81697 65.58404) (xy 139.81697 65.57031)
			(xy 139.83071 65.57031) (xy 139.83071 65.55657) (xy 139.84444 65.55657) (xy 139.84444 65.54284) (xy 139.84444 65.52911)
			(xy 139.85817 65.52911) (xy 139.85817 65.51538) (xy 139.85817 65.50165) (xy 139.8719 65.50165) (xy 139.8719 65.48791)
			(xy 139.8719 65.47418) (xy 139.8719 65.46045) (xy 139.88563 65.46045) (xy 139.88563 65.44672) (xy 139.88563 65.43299)
			(xy 139.89937 65.43299) (xy 139.89937 65.41925) (xy 139.89937 65.40552) (xy 139.89937 65.39179) (xy 139.9131 65.39179)
			(xy 139.9131 65.37806) (xy 139.9131 65.36433) (xy 139.9131 65.3506) (xy 139.9131 65.33686) (xy 139.92683 65.33686)
			(xy 139.92683 65.32313) (xy 139.92683 65.3094) (xy 139.92683 65.29567) (xy 139.92683 65.28194) (xy 139.92683 65.26821)
			(xy 139.94056 65.26821) (xy 139.94056 65.25447) (xy 139.94056 65.24074) (xy 139.94056 65.22701) (xy 139.94056 65.21328)
			(xy 139.94056 65.19955) (xy 139.94056 65.18582) (xy 139.94056 65.17208) (xy 139.94056 65.15835) (xy 139.94056 65.14462)
			(xy 139.94056 65.13089) (xy 139.94056 65.11716) (xy 139.94056 65.10343) (xy 139.94056 65.08969) (xy 139.94056 65.07596)
			(xy 139.94056 65.06223) (xy 139.94056 65.0485) (xy 139.94056 65.03477) (xy 139.94056 65.02104) (xy 139.94056 65.0073)
			(xy 139.92683 65.0073) (xy 139.92683 64.99357) (xy 139.92683 64.97984) (xy 139.92683 64.96611) (xy 139.92683 64.95238)
			(xy 139.92683 64.93864) (xy 139.9131 64.93864) (xy 139.9131 64.92491) (xy 139.9131 64.91118) (xy 139.9131 64.89745)
			(xy 139.9131 64.88372) (xy 139.89937 64.88372) (xy 139.89937 64.86998) (xy 139.89937 64.85625) (xy 139.89937 64.84252)
			(xy 139.88563 64.84252) (xy 139.88563 64.82879) (xy 139.88563 64.81506) (xy 139.88563 64.80133) (xy 139.8719 64.80133)
			(xy 139.8719 64.78759) (xy 139.8719 64.77386) (xy 139.85817 64.77386) (xy 139.85817 64.76013) (xy 139.85817 64.7464)
			(xy 139.84444 64.7464) (xy 139.84444 64.73267) (xy 139.84444 64.71894) (xy 139.83071 64.71894) (xy 139.83071 64.7052)
			(xy 139.83071 64.69147) (xy 139.81697 64.69147) (xy 139.81697 64.67774) (xy 139.81697 64.66401) (xy 139.80324 64.66401)
			(xy 139.80324 64.65028) (xy 139.78951 64.65028) (xy 139.78951 64.63655) (xy 139.78951 64.62281) (xy 139.77578 64.62281)
			(xy 139.77578 64.60908) (xy 139.76205 64.60908) (xy 139.76205 64.59535) (xy 139.74832 64.59535) (xy 139.74832 64.58162)
			(xy 139.74832 64.56789) (xy 139.73458 64.56789) (xy 139.73458 64.55416) (xy 139.72085 64.55416) (xy 139.72085 64.54042)
			(xy 139.70712 64.54042) (xy 139.70712 64.52669) (xy 139.69339 64.52669) (xy 139.69339 64.51296) (xy 139.67966 64.51296)
			(xy 139.67966 64.49923) (xy 139.66593 64.49923) (xy 139.66593 64.4855) (xy 139.65219 64.4855) (xy 139.65219 64.47176)
			(xy 139.63846 64.47176) (xy 139.63846 64.45803) (xy 139.62473 64.45803) (xy 139.62473 64.4443) (xy 139.611 64.4443)
			(xy 139.611 64.43057) (xy 139.58354 64.43057) (xy 139.58354 64.41684) (xy 139.5698 64.41684) (xy 139.5698 64.4031)
			(xy 139.54234 64.4031) (xy 139.54234 64.38937) (xy 139.52861 64.38937) (xy 139.52861 64.37564) (xy 139.50115 64.37564)
			(xy 139.50115 64.36191) (xy 139.48741 64.36191) (xy 139.48741 64.34818) (xy 139.45995 64.34818) (xy 139.45995 64.33445)
			(xy 139.43249 64.33445) (xy 139.43249 64.32071) (xy 139.40502 64.32071) (xy 139.40502 64.30698) (xy 139.36383 64.30698)
			(xy 139.36383 64.29325) (xy 139.32263 64.29325) (xy 139.32263 64.27952) (xy 139.28144 64.27952) (xy 139.28144 64.26579)
			(xy 139.22651 64.26579) (xy 139.22651 64.25206) (xy 139.15785 64.25206) (xy 139.15785 64.23833) (xy 138.91068 64.23833)
		)
		(stroke
			(width 0)
			(type default)
		)
		(fill yes)
		(layer "B.Cu")
	)
	(gr_poly
		(pts
			(xy 164.86369 57.08408) (xy 164.72637 57.08408) (xy 164.72637 57.09781) (xy 164.67145 57.09781) (xy 164.67145 57.11155)
			(xy 164.61652 57.11155) (xy 164.61652 57.12528) (xy 164.58905 57.12528) (xy 164.58905 57.13901) (xy 164.54786 57.13901)
			(xy 164.54786 57.15274) (xy 164.52039 57.15274) (xy 164.52039 57.16647) (xy 164.49293 57.16647) (xy 164.49293 57.18021)
			(xy 164.46547 57.18021) (xy 164.46547 57.19394) (xy 164.438 57.19394) (xy 164.438 57.20767) (xy 164.42427 57.20767)
			(xy 164.42427 57.2214) (xy 164.39681 57.2214) (xy 164.39681 57.23513) (xy 164.38308 57.23513) (xy 164.38308 57.24886)
			(xy 164.36935 57.24886) (xy 164.36935 57.2626) (xy 164.34188 57.2626) (xy 164.34188 57.27633) (xy 164.32815 57.27633)
			(xy 164.32815 57.29006) (xy 164.31442 57.29006) (xy 164.31442 57.30379) (xy 164.30069 57.30379) (xy 164.30069 57.31752)
			(xy 164.28696 57.31752) (xy 164.28696 57.33125) (xy 164.27322 57.33125) (xy 164.27322 57.34499) (xy 164.25949 57.34499)
			(xy 164.25949 57.35872) (xy 164.24576 57.35872) (xy 164.24576 57.37245) (xy 164.23203 57.37245) (xy 164.23203 57.38618)
			(xy 164.23203 57.39991) (xy 164.2183 57.39991) (xy 164.2183 57.41364) (xy 164.20457 57.41364) (xy 164.20457 57.42738)
			(xy 164.19083 57.42738) (xy 164.19083 57.44111) (xy 164.19083 57.45484) (xy 164.1771 57.45484) (xy 164.1771 57.46857)
			(xy 164.16337 57.46857) (xy 164.16337 57.4823) (xy 164.16337 57.49603) (xy 164.14964 57.49603) (xy 164.14964 57.50977)
			(xy 164.14964 57.5235) (xy 164.13591 57.5235) (xy 164.13591 57.53723) (xy 164.13591 57.55096) (xy 164.12218 57.55096)
			(xy 164.12218 57.56469) (xy 164.12218 57.57842) (xy 164.10844 57.57842) (xy 164.10844 57.59216) (xy 164.10844 57.60589)
			(xy 164.10844 57.61962) (xy 164.09471 57.61962) (xy 164.09471 57.63335) (xy 164.09471 57.64708) (xy 164.08098 57.64708)
			(xy 164.08098 57.66082) (xy 164.08098 57.67455) (xy 164.08098 57.68828) (xy 164.08098 57.70201) (xy 164.06725 57.70201)
			(xy 164.06725 57.71574) (xy 164.06725 57.72948) (xy 164.06725 57.74321) (xy 164.06725 57.75694) (xy 164.06725 57.77067)
			(xy 164.05352 57.77067) (xy 164.05352 57.7844) (xy 164.05352 57.79813) (xy 164.05352 57.81187) (xy 164.05352 57.8256)
			(xy 164.05352 57.83933) (xy 164.05352 57.85306) (xy 164.05352 57.86679) (xy 164.05352 57.88052) (xy 164.05352 57.89426)
			(xy 164.05352 57.90799) (xy 164.05352 57.92172) (xy 164.05352 57.93545) (xy 164.05352 57.94918) (xy 164.05352 57.96291)
			(xy 164.05352 57.97665) (xy 164.05352 57.99038) (xy 164.05352 58.00411) (xy 164.05352 58.01784) (xy 164.05352 58.03157)
			(xy 164.05352 58.0453) (xy 164.05352 58.05904) (xy 164.05352 58.07277) (xy 164.05352 58.0865) (xy 164.05352 58.10023)
			(xy 164.05352 58.11396) (xy 164.05352 58.1277) (xy 164.05352 58.14143) (xy 164.05352 58.15516) (xy 164.05352 58.16889)
			(xy 164.05352 58.18262) (xy 164.05352 58.19636) (xy 164.05352 58.21009) (xy 164.05352 58.22382) (xy 164.05352 58.23755)
			(xy 164.05352 58.25128) (xy 164.05352 58.26501) (xy 164.05352 58.27875) (xy 164.05352 58.29248) (xy 164.05352 58.30621)
			(xy 164.05352 58.31994) (xy 164.05352 58.33367) (xy 164.05352 58.3474) (xy 164.05352 58.36114) (xy 164.05352 58.37487)
			(xy 164.05352 58.3886) (xy 164.05352 58.40233) (xy 164.05352 58.41606) (xy 164.05352 58.42979) (xy 164.05352 58.44353)
			(xy 164.05352 58.45726) (xy 164.05352 58.47099) (xy 164.05352 58.48472) (xy 164.05352 58.49845) (xy 164.05352 58.51218)
			(xy 164.05352 58.52592) (xy 164.05352 58.53965) (xy 164.05352 58.55338) (xy 164.05352 58.56711) (xy 164.05352 58.58084)
			(xy 164.05352 58.59457) (xy 164.05352 58.60831) (xy 164.05352 58.62204) (xy 164.05352 58.63577) (xy 164.05352 58.6495)
			(xy 164.05352 58.66323) (xy 164.05352 58.67697) (xy 164.05352 58.6907) (xy 164.05352 58.70443) (xy 164.05352 58.71816)
			(xy 164.05352 58.73189) (xy 164.05352 58.74563) (xy 164.05352 58.75936) (xy 164.05352 58.77309) (xy 164.05352 58.78682)
			(xy 164.05352 58.80055) (xy 164.05352 58.81428) (xy 164.05352 58.82802) (xy 164.05352 58.84175) (xy 164.05352 58.85548)
			(xy 164.05352 58.86921) (xy 164.05352 58.88294) (xy 164.05352 58.89667) (xy 164.05352 58.91041) (xy 164.05352 58.92414)
			(xy 164.05352 58.93787) (xy 164.05352 58.9516) (xy 164.05352 58.96533) (xy 164.05352 58.97906) (xy 164.05352 58.9928)
			(xy 164.05352 59.00653) (xy 164.05352 59.02026) (xy 164.05352 59.03399) (xy 164.05352 59.04772) (xy 164.05352 59.06145)
			(xy 164.05352 59.07519) (xy 164.05352 59.08892) (xy 164.05352 59.10265) (xy 164.05352 59.11638) (xy 164.05352 59.13011)
			(xy 164.05352 59.14384) (xy 164.05352 59.15758) (xy 164.05352 59.17131) (xy 164.05352 59.18504) (xy 164.05352 59.19877)
			(xy 164.05352 59.2125) (xy 164.05352 59.22624) (xy 164.05352 59.23997) (xy 164.05352 59.2537) (xy 164.05352 59.26743)
			(xy 164.05352 59.28116) (xy 164.05352 59.2949) (xy 164.05352 59.30863) (xy 164.05352 59.32236) (xy 164.05352 59.33609)
			(xy 164.05352 59.34982) (xy 164.05352 59.36355) (xy 164.05352 59.37729) (xy 164.05352 59.39102) (xy 164.05352 59.40475)
			(xy 164.05352 59.41848) (xy 164.05352 59.43221) (xy 164.05352 59.44594) (xy 164.05352 59.45968) (xy 164.05352 59.47341)
			(xy 164.05352 59.48714) (xy 164.05352 59.50087) (xy 164.05352 59.5146) (xy 164.05352 59.52833) (xy 164.05352 59.54207)
			(xy 164.05352 59.5558) (xy 164.05352 59.56953) (xy 164.05352 59.58326) (xy 164.05352 59.59699) (xy 164.05352 59.61072)
			(xy 164.05352 59.62446) (xy 164.05352 59.63819) (xy 164.05352 59.65192) (xy 164.05352 59.66565) (xy 164.05352 59.67938)
			(xy 164.05352 59.69311) (xy 164.05352 59.70685) (xy 164.05352 59.72058) (xy 164.05352 59.73431) (xy 164.05352 59.74804)
			(xy 164.05352 59.76177) (xy 164.05352 59.77551) (xy 164.05352 59.78924) (xy 164.05352 59.80297) (xy 164.05352 59.8167)
			(xy 164.05352 59.83043) (xy 164.05352 59.84417) (xy 164.05352 59.8579) (xy 164.05352 59.87163) (xy 164.05352 59.88536)
			(xy 164.05352 59.89909) (xy 164.05352 59.91282) (xy 164.05352 59.92656) (xy 164.05352 59.94029) (xy 164.05352 59.95402)
			(xy 164.05352 59.96775) (xy 164.05352 59.98148) (xy 164.05352 59.99521) (xy 164.05352 60.00895) (xy 164.05352 60.02268)
			(xy 164.05352 60.03641) (xy 164.05352 60.05014) (xy 164.05352 60.06387) (xy 164.05352 60.0776) (xy 164.05352 60.09134)
			(xy 164.05352 60.10507) (xy 164.05352 60.1188) (xy 164.05352 60.13253) (xy 164.05352 60.14626) (xy 164.05352 60.15999)
			(xy 164.05352 60.17373) (xy 164.05352 60.18746) (xy 164.05352 60.20119) (xy 164.05352 60.21492) (xy 164.05352 60.22865)
			(xy 164.05352 60.24239) (xy 164.05352 60.25612) (xy 164.05352 60.26985) (xy 164.05352 60.28358) (xy 164.05352 60.29731)
			(xy 164.05352 60.31105) (xy 164.05352 60.32478) (xy 164.05352 60.33851) (xy 164.05352 60.35224) (xy 164.05352 60.36597)
			(xy 164.05352 60.3797) (xy 164.05352 60.39344) (xy 164.05352 60.40717) (xy 164.05352 60.4209) (xy 164.05352 60.43463)
			(xy 164.05352 60.44836) (xy 164.05352 60.46209) (xy 164.05352 60.47583) (xy 164.05352 60.48956) (xy 164.05352 60.50329)
			(xy 164.05352 60.51702) (xy 164.05352 60.53075) (xy 164.05352 60.54448) (xy 164.05352 60.55822) (xy 164.05352 60.57195)
			(xy 164.05352 60.58568) (xy 164.05352 60.59941) (xy 164.05352 60.61314) (xy 164.05352 60.62687) (xy 164.05352 60.64061)
			(xy 164.05352 60.65434) (xy 164.05352 60.66807) (xy 164.05352 60.6818) (xy 164.05352 60.69553) (xy 164.05352 60.70926)
			(xy 164.05352 60.723) (xy 164.05352 60.73673) (xy 164.05352 60.75046) (xy 164.05352 60.76419) (xy 164.05352 60.77792)
			(xy 164.05352 60.79166) (xy 164.05352 60.80539) (xy 164.05352 60.81912) (xy 164.05352 60.83285) (xy 164.05352 60.84658)
			(xy 164.05352 60.86032) (xy 164.05352 60.87405) (xy 164.05352 60.88778) (xy 164.05352 60.90151) (xy 164.05352 60.91524)
			(xy 164.05352 60.92897) (xy 164.05352 60.94271) (xy 164.05352 60.95644) (xy 164.05352 60.97017) (xy 164.05352 60.9839)
			(xy 164.05352 60.99763) (xy 164.05352 61.01136) (xy 164.05352 61.0251) (xy 164.05352 61.03883) (xy 164.05352 61.05256)
			(xy 164.05352 61.06629) (xy 164.05352 61.08002) (xy 164.05352 61.09375) (xy 164.05352 61.10749) (xy 164.05352 61.12122)
			(xy 164.05352 61.13495) (xy 164.05352 61.14868) (xy 164.05352 61.16241) (xy 164.05352 61.17614) (xy 164.05352 61.18988)
			(xy 164.05352 61.20361) (xy 164.05352 61.21734) (xy 164.05352 61.23107) (xy 164.05352 61.2448) (xy 164.05352 61.25853)
			(xy 164.05352 61.27227) (xy 164.05352 61.286) (xy 164.05352 61.29973) (xy 164.05352 61.31346) (xy 164.05352 61.32719)
			(xy 164.05352 61.34093) (xy 164.05352 61.35466) (xy 164.05352 61.36839) (xy 164.05352 61.38212) (xy 164.05352 61.39585)
			(xy 164.05352 61.40959) (xy 164.05352 61.42332) (xy 164.05352 61.43705) (xy 164.05352 61.45078) (xy 164.05352 61.46451)
			(xy 164.05352 61.47824) (xy 164.05352 61.49198) (xy 164.05352 61.50571) (xy 164.05352 61.51944) (xy 164.05352 61.53317)
			(xy 164.05352 61.5469) (xy 164.05352 61.56063) (xy 164.05352 61.57437) (xy 164.05352 61.5881) (xy 164.05352 61.60183)
			(xy 164.05352 61.61556) (xy 164.05352 61.62929) (xy 164.05352 61.64302) (xy 164.05352 61.65676) (xy 164.05352 61.67049)
			(xy 164.05352 61.68422) (xy 164.05352 61.69795) (xy 164.05352 61.71168) (xy 164.05352 61.72541) (xy 164.05352 61.73915)
			(xy 164.05352 61.75288) (xy 164.05352 61.76661) (xy 164.05352 61.78034) (xy 164.05352 61.79407) (xy 164.05352 61.8078)
			(xy 164.05352 61.82154) (xy 164.05352 61.83527) (xy 164.05352 61.849) (xy 164.05352 61.86273) (xy 164.05352 61.87646)
			(xy 164.05352 61.8902) (xy 164.05352 61.90393) (xy 164.05352 61.91766) (xy 164.05352 61.93139) (xy 164.05352 61.94512)
			(xy 164.05352 61.95886) (xy 164.05352 61.97259) (xy 164.05352 61.98632) (xy 164.05352 62.00005) (xy 164.05352 62.01378)
			(xy 164.05352 62.02751) (xy 164.05352 62.04125) (xy 164.05352 62.05498) (xy 164.05352 62.06871) (xy 164.05352 62.08244)
			(xy 164.05352 62.09617) (xy 164.05352 62.1099) (xy 164.05352 62.12364) (xy 164.05352 62.13737) (xy 164.05352 62.1511)
			(xy 164.05352 62.16483) (xy 164.05352 62.17856) (xy 164.05352 62.19229) (xy 164.05352 62.20603) (xy 164.05352 62.21976)
			(xy 164.05352 62.23349) (xy 164.05352 62.24722) (xy 164.05352 62.26095) (xy 164.05352 62.27468) (xy 164.05352 62.28842)
			(xy 164.05352 62.30215) (xy 164.05352 62.31588) (xy 164.05352 62.32961) (xy 164.05352 62.34334) (xy 164.05352 62.35708)
			(xy 164.05352 62.37081) (xy 164.05352 62.38454) (xy 164.05352 62.39827) (xy 164.05352 62.412) (xy 164.05352 62.42574)
			(xy 164.05352 62.43947) (xy 164.05352 62.4532) (xy 164.05352 62.46693) (xy 164.05352 62.48066) (xy 164.05352 62.49439)
			(xy 164.05352 62.50813) (xy 164.05352 62.52186) (xy 164.05352 62.53559) (xy 164.05352 62.54932) (xy 164.05352 62.56305)
			(xy 164.05352 62.57678) (xy 164.05352 62.59052) (xy 164.05352 62.60425) (xy 164.05352 62.61798) (xy 164.05352 62.63171)
			(xy 164.05352 62.64544) (xy 164.05352 62.65917) (xy 164.05352 62.67291) (xy 164.05352 62.68664) (xy 164.05352 62.70037)
			(xy 164.05352 62.7141) (xy 164.05352 62.72783) (xy 164.05352 62.74156) (xy 164.05352 62.7553) (xy 164.05352 62.76903)
			(xy 164.05352 62.78276) (xy 164.05352 62.79649) (xy 164.05352 62.81022) (xy 164.05352 62.82395) (xy 164.05352 62.83769)
			(xy 164.05352 62.85142) (xy 164.05352 62.86515) (xy 164.05352 62.87888) (xy 164.05352 62.89261) (xy 164.05352 62.90635)
			(xy 164.05352 62.92008) (xy 164.05352 62.93381) (xy 164.05352 62.94754) (xy 164.05352 62.96127) (xy 164.05352 62.97501)
			(xy 164.05352 62.98874) (xy 164.05352 63.00247) (xy 164.05352 63.0162) (xy 164.05352 63.02993) (xy 164.05352 63.04366)
			(xy 164.05352 63.0574) (xy 164.05352 63.07113) (xy 164.05352 63.08486) (xy 164.05352 63.09859) (xy 164.05352 63.11232)
			(xy 164.05352 63.12605) (xy 164.05352 63.13979) (xy 164.05352 63.15352) (xy 164.05352 63.16725) (xy 164.05352 63.18098)
			(xy 164.05352 63.19471) (xy 164.05352 63.20844) (xy 164.05352 63.22218) (xy 164.05352 63.23591) (xy 164.05352 63.24964)
			(xy 164.05352 63.26337) (xy 164.05352 63.2771) (xy 164.05352 63.29083) (xy 164.05352 63.30457) (xy 164.05352 63.3183)
			(xy 164.05352 63.33203) (xy 164.05352 63.34576) (xy 164.05352 63.35949) (xy 164.05352 63.37322) (xy 164.05352 63.38696)
			(xy 164.05352 63.40069) (xy 164.05352 63.41442) (xy 164.05352 63.42815) (xy 164.05352 63.44188) (xy 164.05352 63.45562)
			(xy 164.05352 63.46935) (xy 164.05352 63.48308) (xy 164.05352 63.49681) (xy 164.05352 63.51054) (xy 164.05352 63.52428)
			(xy 164.05352 63.53801) (xy 164.05352 63.55174) (xy 164.05352 63.56547) (xy 164.05352 63.5792) (xy 164.05352 63.59293)
			(xy 164.05352 63.60667) (xy 164.05352 63.6204) (xy 164.05352 63.63413) (xy 164.05352 63.64786) (xy 164.05352 63.66159)
			(xy 164.05352 63.67532) (xy 164.05352 63.68906) (xy 164.05352 63.70279) (xy 164.05352 63.71652) (xy 164.05352 63.73025)
			(xy 164.05352 63.74398) (xy 164.05352 63.75771) (xy 164.05352 63.77145) (xy 164.05352 63.78518) (xy 164.05352 63.79891)
			(xy 164.05352 63.81264) (xy 164.05352 63.82637) (xy 164.05352 63.8401) (xy 164.05352 63.85384) (xy 164.05352 63.86757)
			(xy 164.05352 63.8813) (xy 164.05352 63.89503) (xy 164.05352 63.90876) (xy 164.05352 63.92249) (xy 164.05352 63.93623)
			(xy 164.05352 63.94996) (xy 164.05352 63.96369) (xy 164.05352 63.97742) (xy 164.05352 63.99115) (xy 164.05352 64.00489)
			(xy 164.05352 64.01862) (xy 164.05352 64.03235) (xy 164.05352 64.04608) (xy 164.05352 64.05981) (xy 164.05352 64.07355)
			(xy 164.05352 64.08728) (xy 164.05352 64.10101) (xy 164.05352 64.11474) (xy 164.05352 64.12847) (xy 164.05352 64.1422)
			(xy 164.05352 64.15594) (xy 164.05352 64.16967) (xy 164.05352 64.1834) (xy 164.05352 64.19713) (xy 164.05352 64.21086)
			(xy 164.05352 64.22459) (xy 164.05352 64.23833) (xy 164.05352 64.25206) (xy 164.05352 64.26579) (xy 164.05352 64.27952)
			(xy 164.05352 64.29325) (xy 164.05352 64.30698) (xy 164.05352 64.32071) (xy 164.05352 64.33445) (xy 164.05352 64.34818)
			(xy 164.05352 64.36191) (xy 164.05352 64.37564) (xy 164.05352 64.38937) (xy 164.05352 64.4031) (xy 164.05352 64.41684)
			(xy 164.05352 64.43057) (xy 164.05352 64.4443) (xy 164.05352 64.45803) (xy 164.05352 64.47176) (xy 164.05352 64.4855)
			(xy 164.05352 64.49923) (xy 164.05352 64.51296) (xy 164.05352 64.52669) (xy 164.05352 64.54042) (xy 164.05352 64.55416)
			(xy 164.05352 64.56789) (xy 164.05352 64.58162) (xy 164.05352 64.59535) (xy 164.05352 64.60908) (xy 164.05352 64.62281)
			(xy 164.05352 64.63655) (xy 164.05352 64.65028) (xy 164.05352 64.66401) (xy 164.05352 64.67774) (xy 164.05352 64.69147)
			(xy 164.05352 64.7052) (xy 164.05352 64.71894) (xy 164.05352 64.73267) (xy 164.05352 64.7464) (xy 164.05352 64.76013)
			(xy 164.05352 64.77386) (xy 164.05352 64.78759) (xy 164.05352 64.80133) (xy 164.05352 64.81506) (xy 164.05352 64.82879)
			(xy 164.05352 64.84252) (xy 164.05352 64.85625) (xy 164.05352 64.86998) (xy 164.05352 64.88372) (xy 164.05352 64.89745)
			(xy 164.05352 64.91118) (xy 164.05352 64.92491) (xy 164.05352 64.93864) (xy 164.05352 64.95238) (xy 164.05352 64.96611)
			(xy 164.05352 64.97984) (xy 164.05352 64.99357) (xy 164.05352 65.0073) (xy 164.05352 65.02104) (xy 164.05352 65.03477)
			(xy 164.05352 65.0485) (xy 164.05352 65.06223) (xy 164.05352 65.07596) (xy 164.05352 65.08969) (xy 164.05352 65.10343)
			(xy 164.05352 65.11716) (xy 164.05352 65.13089) (xy 164.05352 65.14462) (xy 164.05352 65.15835) (xy 164.05352 65.17208)
			(xy 164.05352 65.18582) (xy 164.05352 65.19955) (xy 164.05352 65.21328) (xy 164.05352 65.22701) (xy 164.05352 65.24074)
			(xy 164.05352 65.25447) (xy 164.05352 65.26821) (xy 164.05352 65.28194) (xy 164.05352 65.29567) (xy 164.05352 65.3094)
			(xy 164.05352 65.32313) (xy 164.05352 65.33686) (xy 164.05352 65.3506) (xy 164.05352 65.36433) (xy 164.05352 65.37806)
			(xy 164.05352 65.39179) (xy 164.05352 65.40552) (xy 164.05352 65.41925) (xy 164.05352 65.43299) (xy 164.05352 65.44672)
			(xy 164.05352 65.46045) (xy 164.05352 65.47418) (xy 164.05352 65.48791) (xy 164.05352 65.50165) (xy 164.05352 65.51538)
			(xy 164.05352 65.52911) (xy 164.05352 65.54284) (xy 164.05352 65.55657) (xy 164.05352 65.57031) (xy 164.05352 65.58404)
			(xy 164.05352 65.59777) (xy 164.05352 65.6115) (xy 164.05352 65.62523) (xy 164.05352 65.63896) (xy 164.05352 65.6527)
			(xy 164.05352 65.66643) (xy 164.05352 65.68016) (xy 164.05352 65.69389) (xy 164.05352 65.70762) (xy 164.05352 65.72135)
			(xy 164.05352 65.73509) (xy 164.05352 65.74882) (xy 164.05352 65.76255) (xy 164.05352 65.77628) (xy 164.05352 65.79001)
			(xy 164.05352 65.80374) (xy 164.05352 65.81748) (xy 164.05352 65.83121) (xy 164.05352 65.84494) (xy 164.05352 65.85867)
			(xy 164.05352 65.8724) (xy 164.05352 65.88613) (xy 164.05352 65.89987) (xy 164.05352 65.9136) (xy 164.05352 65.92733)
			(xy 164.05352 65.94106) (xy 164.05352 65.95479) (xy 164.05352 65.96852) (xy 164.05352 65.98226) (xy 164.05352 65.99599)
			(xy 164.05352 66.00972) (xy 164.05352 66.02345) (xy 164.05352 66.03718) (xy 164.05352 66.05092) (xy 164.05352 66.06465)
			(xy 164.05352 66.07838) (xy 164.05352 66.09211) (xy 164.05352 66.10584) (xy 164.05352 66.11958) (xy 164.05352 66.13331)
			(xy 164.05352 66.14704) (xy 164.05352 66.16077) (xy 164.05352 66.1745) (xy 164.05352 66.18823) (xy 164.05352 66.20197)
			(xy 164.05352 66.2157) (xy 164.05352 66.22943) (xy 164.05352 66.24316) (xy 164.05352 66.25689) (xy 164.05352 66.27062)
			(xy 164.05352 66.28436) (xy 164.05352 66.29809) (xy 164.05352 66.31182) (xy 164.05352 66.32555) (xy 164.05352 66.33928)
			(xy 164.05352 66.35301) (xy 164.05352 66.36675) (xy 164.05352 66.38048) (xy 164.05352 66.39421) (xy 164.05352 66.40794)
			(xy 164.05352 66.42167) (xy 164.05352 66.4354) (xy 164.05352 66.44914) (xy 164.05352 66.46287) (xy 164.05352 66.4766)
			(xy 164.05352 66.49033) (xy 164.05352 66.50406) (xy 164.05352 66.51779) (xy 164.05352 66.53153) (xy 164.05352 66.54526)
			(xy 164.05352 66.55899) (xy 164.05352 66.57272) (xy 164.05352 66.58645) (xy 164.05352 66.60019) (xy 164.05352 66.61392)
			(xy 164.05352 66.62765) (xy 164.05352 66.64138) (xy 164.05352 66.65511) (xy 164.05352 66.66885) (xy 164.05352 66.68258)
			(xy 164.05352 66.69631) (xy 164.05352 66.71004) (xy 164.05352 66.72377) (xy 164.05352 66.7375) (xy 164.05352 66.75124)
			(xy 164.05352 66.76497) (xy 164.05352 66.7787) (xy 164.05352 66.79243) (xy 164.05352 66.80616) (xy 164.05352 66.81989)
			(xy 164.05352 66.83363) (xy 164.05352 66.84736) (xy 164.05352 66.86109) (xy 164.05352 66.87482) (xy 164.05352 66.88855)
			(xy 164.05352 66.90228) (xy 164.05352 66.91602) (xy 164.05352 66.92975) (xy 164.05352 66.94348) (xy 164.05352 66.95721)
			(xy 164.05352 66.97094) (xy 164.05352 66.98467) (xy 164.05352 66.99841) (xy 164.05352 67.01214) (xy 164.05352 67.02587)
			(xy 164.05352 67.0396) (xy 164.05352 67.05333) (xy 164.05352 67.06707) (xy 164.05352 67.0808) (xy 164.05352 67.09453)
			(xy 164.05352 67.10826) (xy 164.05352 67.12199) (xy 164.05352 67.13573) (xy 164.05352 67.14946) (xy 164.05352 67.16319)
			(xy 164.05352 67.17692) (xy 164.05352 67.19065) (xy 164.05352 67.20438) (xy 164.05352 67.21812) (xy 164.05352 67.23185)
			(xy 164.05352 67.24558) (xy 164.05352 67.25931) (xy 164.05352 67.27304) (xy 164.05352 67.28677) (xy 164.05352 67.30051)
			(xy 164.05352 67.31424) (xy 164.05352 67.32797) (xy 164.05352 67.3417) (xy 164.05352 67.35543) (xy 164.05352 67.36916)
			(xy 164.05352 67.3829) (xy 164.05352 67.39663) (xy 164.05352 67.41036) (xy 164.05352 67.42409) (xy 164.05352 67.43782)
			(xy 164.05352 67.45155) (xy 164.05352 67.46529) (xy 164.05352 67.47902) (xy 164.05352 67.49275) (xy 164.05352 67.50648)
			(xy 164.05352 67.52021) (xy 164.05352 67.53394) (xy 164.05352 67.54768) (xy 164.05352 67.56141) (xy 164.05352 67.57514)
			(xy 164.05352 67.58887) (xy 164.05352 67.6026) (xy 164.05352 67.61634) (xy 164.05352 67.63007) (xy 164.05352 67.6438)
			(xy 164.05352 67.65753) (xy 164.05352 67.67126) (xy 164.05352 67.685) (xy 164.05352 67.69873) (xy 164.05352 67.71246)
			(xy 164.05352 67.72619) (xy 164.05352 67.73992) (xy 164.05352 67.75365) (xy 164.05352 67.76739) (xy 164.05352 67.78112)
			(xy 164.05352 67.79485) (xy 164.05352 67.80858) (xy 164.05352 67.82231) (xy 164.05352 67.83604) (xy 164.05352 67.84978)
			(xy 164.05352 67.86351) (xy 164.05352 67.87724) (xy 164.05352 67.89097) (xy 164.05352 67.9047) (xy 164.05352 67.91843)
			(xy 164.05352 67.93217) (xy 164.05352 67.9459) (xy 164.05352 67.95963) (xy 164.05352 67.97336) (xy 164.05352 67.98709)
			(xy 164.05352 68.00082) (xy 164.05352 68.01456) (xy 164.05352 68.02829) (xy 164.05352 68.04202) (xy 164.05352 68.05575)
			(xy 164.05352 68.06948) (xy 164.05352 68.08321) (xy 164.05352 68.09695) (xy 164.05352 68.11068) (xy 164.05352 68.12441)
			(xy 164.05352 68.13814) (xy 164.05352 68.15187) (xy 164.05352 68.16561) (xy 164.05352 68.17934) (xy 164.05352 68.19307)
			(xy 164.05352 68.2068) (xy 164.05352 68.22053) (xy 164.05352 68.23427) (xy 164.05352 68.248) (xy 164.05352 68.26173)
			(xy 164.05352 68.27546) (xy 164.05352 68.28919) (xy 164.05352 68.30292) (xy 164.05352 68.31666) (xy 164.05352 68.33039)
			(xy 164.05352 68.34412) (xy 164.05352 68.35785) (xy 164.05352 68.37158) (xy 164.05352 68.38531) (xy 164.05352 68.39905)
			(xy 164.05352 68.41278) (xy 164.05352 68.42651) (xy 164.05352 68.44024) (xy 164.05352 68.45397) (xy 164.05352 68.4677)
			(xy 164.05352 68.48144) (xy 164.05352 68.49517) (xy 164.05352 68.5089) (xy 164.05352 68.52263) (xy 164.05352 68.53636)
			(xy 164.05352 68.55009) (xy 164.05352 68.56383) (xy 164.05352 68.57756) (xy 164.05352 68.59129) (xy 164.05352 68.60502)
			(xy 164.05352 68.61875) (xy 164.05352 68.63248) (xy 164.05352 68.64622) (xy 164.05352 68.65995) (xy 164.05352 68.67368)
			(xy 164.05352 68.68741) (xy 164.05352 68.70114) (xy 164.05352 68.71488) (xy 164.05352 68.72861) (xy 164.05352 68.74234)
			(xy 164.05352 68.75607) (xy 164.05352 68.7698) (xy 164.05352 68.78354) (xy 164.05352 68.79727) (xy 164.05352 68.811)
			(xy 164.05352 68.82473) (xy 164.05352 68.83846) (xy 164.05352 68.85219) (xy 164.05352 68.86593) (xy 164.05352 68.87966)
			(xy 164.05352 68.89339) (xy 164.05352 68.90712) (xy 164.05352 68.92085) (xy 164.05352 68.93458) (xy 164.05352 68.94832)
			(xy 164.05352 68.96205) (xy 164.05352 68.97578) (xy 164.05352 68.98951) (xy 164.05352 69.00324) (xy 164.05352 69.01697)
			(xy 164.05352 69.03071) (xy 164.05352 69.04444) (xy 164.05352 69.05817) (xy 164.05352 69.0719) (xy 164.05352 69.08563)
			(xy 164.05352 69.09936) (xy 164.05352 69.1131) (xy 164.05352 69.12683) (xy 164.05352 69.14056) (xy 164.05352 69.15429)
			(xy 164.05352 69.16802) (xy 164.05352 69.18175) (xy 164.05352 69.19549) (xy 164.05352 69.20922) (xy 164.05352 69.22295)
			(xy 164.05352 69.23668) (xy 164.05352 69.25041) (xy 164.05352 69.26415) (xy 164.05352 69.27788) (xy 164.05352 69.29161)
			(xy 164.05352 69.30534) (xy 164.05352 69.31907) (xy 164.05352 69.33281) (xy 164.05352 69.34654) (xy 164.05352 69.36027)
			(xy 164.05352 69.374) (xy 164.05352 69.38773) (xy 164.05352 69.40146) (xy 164.05352 69.4152) (xy 164.05352 69.42893)
			(xy 164.05352 69.44266) (xy 164.05352 69.45639) (xy 164.05352 69.47012) (xy 164.05352 69.48385) (xy 164.05352 69.49759)
			(xy 164.05352 69.51132) (xy 164.05352 69.52505) (xy 164.05352 69.53878) (xy 164.05352 69.55251) (xy 164.05352 69.56624)
			(xy 164.05352 69.57998) (xy 164.05352 69.59371) (xy 164.05352 69.60744) (xy 164.05352 69.62117) (xy 164.05352 69.6349)
			(xy 164.05352 69.64863) (xy 164.05352 69.66237) (xy 164.05352 69.6761) (xy 164.05352 69.68983) (xy 164.05352 69.70356)
			(xy 164.05352 69.71729) (xy 164.05352 69.73103) (xy 164.05352 69.74476) (xy 164.05352 69.75849) (xy 164.05352 69.77222)
			(xy 164.05352 69.78595) (xy 164.05352 69.79969) (xy 164.05352 69.81342) (xy 164.05352 69.82715) (xy 164.05352 69.84088)
			(xy 164.05352 69.85461) (xy 164.05352 69.86834) (xy 164.05352 69.88208) (xy 164.05352 69.89581) (xy 164.05352 69.90954)
			(xy 164.05352 69.92327) (xy 164.05352 69.937) (xy 164.05352 69.95073) (xy 164.05352 69.96447) (xy 164.05352 69.9782)
			(xy 164.05352 69.99193) (xy 164.05352 70.00566) (xy 164.05352 70.01939) (xy 164.05352 70.03312) (xy 164.05352 70.04686)
			(xy 164.05352 70.06059) (xy 164.05352 70.07432) (xy 164.05352 70.08805) (xy 164.05352 70.10178) (xy 164.05352 70.11551)
			(xy 164.05352 70.12925) (xy 164.05352 70.14298) (xy 164.05352 70.15671) (xy 164.05352 70.17044) (xy 164.05352 70.18417)
			(xy 164.05352 70.1979) (xy 164.05352 70.21164) (xy 164.05352 70.22537) (xy 164.05352 70.2391) (xy 164.05352 70.25283)
			(xy 164.05352 70.26656) (xy 164.05352 70.2803) (xy 164.05352 70.29403) (xy 164.05352 70.30776) (xy 164.05352 70.32149)
			(xy 164.05352 70.33522) (xy 164.05352 70.34896) (xy 164.05352 70.36269) (xy 164.05352 70.37642) (xy 164.05352 70.39015)
			(xy 164.05352 70.40388) (xy 164.05352 70.41761) (xy 164.05352 70.43135) (xy 164.05352 70.44508) (xy 164.05352 70.45881)
			(xy 164.05352 70.47254) (xy 164.05352 70.48627) (xy 164.05352 70.5) (xy 164.05352 70.51374) (xy 164.05352 70.52747)
			(xy 164.05352 70.5412) (xy 164.05352 70.55493) (xy 164.05352 70.56866) (xy 164.05352 70.58239) (xy 164.05352 70.59613)
			(xy 164.05352 70.60986) (xy 164.05352 70.62359) (xy 164.05352 70.63732) (xy 164.05352 70.65105) (xy 164.05352 70.66478)
			(xy 164.05352 70.67852) (xy 164.05352 70.69225) (xy 164.05352 70.70598) (xy 164.05352 70.71971) (xy 164.05352 70.73344)
			(xy 164.05352 70.74717) (xy 164.05352 70.76091) (xy 164.05352 70.77464) (xy 164.05352 70.78837) (xy 164.05352 70.8021)
			(xy 164.05352 70.81583) (xy 164.05352 70.82957) (xy 164.05352 70.8433) (xy 164.05352 70.85703) (xy 164.05352 70.87076)
			(xy 164.05352 70.88449) (xy 164.05352 70.89823) (xy 164.05352 70.91196) (xy 164.05352 70.92569) (xy 164.05352 70.93942)
			(xy 164.05352 70.95315) (xy 164.05352 70.96688) (xy 164.05352 70.98062) (xy 164.05352 70.99435) (xy 164.05352 71.00808)
			(xy 164.05352 71.02181) (xy 164.05352 71.03554) (xy 164.05352 71.04927) (xy 164.05352 71.06301) (xy 164.05352 71.07674)
			(xy 164.05352 71.09047) (xy 164.05352 71.1042) (xy 164.05352 71.11793) (xy 164.05352 71.13166) (xy 164.05352 71.1454)
			(xy 164.05352 71.15913) (xy 164.05352 71.17286) (xy 164.05352 71.18659) (xy 164.05352 71.20032) (xy 164.05352 71.21405)
			(xy 164.05352 71.22779) (xy 164.05352 71.24152) (xy 164.05352 71.25525) (xy 164.05352 71.26898) (xy 164.05352 71.28271)
			(xy 164.05352 71.29644) (xy 164.05352 71.31018) (xy 164.05352 71.32391) (xy 164.05352 71.33764) (xy 164.05352 71.35137)
			(xy 164.05352 71.3651) (xy 164.05352 71.37884) (xy 164.05352 71.39257) (xy 164.05352 71.4063) (xy 164.05352 71.42003)
			(xy 164.05352 71.43376) (xy 164.05352 71.4475) (xy 164.05352 71.46123) (xy 164.05352 71.47496) (xy 164.05352 71.48869)
			(xy 164.05352 71.50242) (xy 164.05352 71.51615) (xy 164.05352 71.52989) (xy 164.05352 71.54362) (xy 164.05352 71.55735)
			(xy 164.05352 71.57108) (xy 164.05352 71.58481) (xy 164.05352 71.59854) (xy 164.05352 71.61228) (xy 164.05352 71.62601)
			(xy 164.05352 71.63974) (xy 164.05352 71.65347) (xy 164.05352 71.6672) (xy 164.05352 71.68093) (xy 164.05352 71.69467)
			(xy 164.05352 71.7084) (xy 164.05352 71.72213) (xy 164.05352 71.73586) (xy 164.05352 71.74959) (xy 164.05352 71.76332)
			(xy 164.05352 71.77706) (xy 164.05352 71.79079) (xy 164.05352 71.80452) (xy 164.05352 71.81825) (xy 164.05352 71.83198)
			(xy 164.05352 71.84572) (xy 164.05352 71.85945) (xy 164.05352 71.87318) (xy 164.05352 71.88691) (xy 164.05352 71.90064)
			(xy 164.05352 71.91438) (xy 164.05352 71.92811) (xy 164.05352 71.94184) (xy 164.05352 71.95557) (xy 164.05352 71.9693)
			(xy 164.05352 71.98303) (xy 164.05352 71.99677) (xy 164.05352 72.0105) (xy 164.05352 72.02423) (xy 164.05352 72.03796)
			(xy 164.05352 72.05169) (xy 164.05352 72.06542) (xy 164.05352 72.07916) (xy 164.05352 72.09289) (xy 164.05352 72.10662)
			(xy 164.05352 72.12035) (xy 164.05352 72.13408) (xy 164.05352 72.14781) (xy 164.05352 72.16155) (xy 164.05352 72.17528)
			(xy 164.05352 72.18901) (xy 164.05352 72.20274) (xy 164.05352 72.21647) (xy 164.05352 72.2302) (xy 164.05352 72.24394)
			(xy 164.05352 72.25767) (xy 164.05352 72.2714) (xy 164.05352 72.28513) (xy 164.05352 72.29886) (xy 164.05352 72.31259)
			(xy 164.05352 72.32633) (xy 164.05352 72.34006) (xy 164.05352 72.35379) (xy 164.05352 72.36752) (xy 164.05352 72.38125)
			(xy 164.05352 72.39499) (xy 164.05352 72.40872) (xy 164.05352 72.42245) (xy 164.05352 72.43618) (xy 164.05352 72.44991)
			(xy 164.05352 72.46365) (xy 164.05352 72.47738) (xy 164.05352 72.49111) (xy 164.05352 72.50484) (xy 164.05352 72.51857)
			(xy 164.05352 72.5323) (xy 164.05352 72.54604) (xy 164.05352 72.55977) (xy 164.05352 72.5735) (xy 164.05352 72.58723)
			(xy 164.05352 72.60096) (xy 164.05352 72.61469) (xy 164.05352 72.62843) (xy 164.05352 72.64216) (xy 164.05352 72.65589)
			(xy 164.05352 72.66962) (xy 164.05352 72.68335) (xy 164.05352 72.69708) (xy 164.05352 72.71082) (xy 164.05352 72.72455)
			(xy 164.05352 72.73828) (xy 164.05352 72.75201) (xy 164.05352 72.76574) (xy 164.56159 72.76574) (xy 164.56159 72.75201)
			(xy 164.56159 72.73828) (xy 164.56159 72.72455) (xy 164.56159 72.71082) (xy 164.56159 72.69708) (xy 164.56159 72.68335)
			(xy 164.56159 72.66962) (xy 164.56159 72.65589) (xy 164.56159 72.64216) (xy 164.56159 72.62843) (xy 164.56159 72.61469)
			(xy 164.56159 72.60096) (xy 164.56159 72.58723) (xy 164.56159 72.5735) (xy 164.56159 72.55977) (xy 164.56159 72.54604)
			(xy 164.56159 72.5323) (xy 164.56159 72.51857) (xy 164.56159 72.50484) (xy 164.56159 72.49111) (xy 164.56159 72.47738)
			(xy 164.56159 72.46365) (xy 164.56159 72.44991) (xy 164.56159 72.43618) (xy 164.56159 72.42245) (xy 164.56159 72.40872)
			(xy 164.56159 72.39499) (xy 164.56159 72.38125) (xy 164.56159 72.36752) (xy 164.56159 72.35379) (xy 164.56159 72.34006)
			(xy 164.56159 72.32633) (xy 164.56159 72.31259) (xy 164.56159 72.29886) (xy 164.56159 72.28513) (xy 164.56159 72.2714)
			(xy 164.56159 72.25767) (xy 164.56159 72.24394) (xy 164.56159 72.2302) (xy 164.56159 72.21647) (xy 164.56159 72.20274)
			(xy 164.56159 72.18901) (xy 164.56159 72.17528) (xy 164.56159 72.16155) (xy 164.56159 72.14781) (xy 164.56159 72.13408)
			(xy 164.56159 72.12035) (xy 164.56159 72.10662) (xy 164.56159 72.09289) (xy 164.56159 72.07916) (xy 164.56159 72.06542)
			(xy 164.56159 72.05169) (xy 164.56159 72.03796) (xy 164.56159 72.02423) (xy 164.56159 72.0105) (xy 164.56159 71.99677)
			(xy 164.56159 71.98303) (xy 164.56159 71.9693) (xy 164.56159 71.95557) (xy 164.56159 71.94184) (xy 164.56159 71.92811)
			(xy 164.56159 71.91438) (xy 164.56159 71.90064) (xy 164.56159 71.88691) (xy 164.56159 71.87318) (xy 164.56159 71.85945)
			(xy 164.56159 71.84572) (xy 164.56159 71.83198) (xy 164.56159 71.81825) (xy 164.56159 71.80452) (xy 164.56159 71.79079)
			(xy 164.56159 71.77706) (xy 164.56159 71.76332) (xy 164.56159 71.74959) (xy 164.56159 71.73586) (xy 164.56159 71.72213)
			(xy 164.56159 71.7084) (xy 164.56159 71.69467) (xy 164.56159 71.68093) (xy 164.56159 71.6672) (xy 164.56159 71.65347)
			(xy 164.56159 71.63974) (xy 164.56159 71.62601) (xy 164.56159 71.61228) (xy 164.56159 71.59854) (xy 164.56159 71.58481)
			(xy 164.56159 71.57108) (xy 164.56159 71.55735) (xy 164.56159 71.54362) (xy 164.56159 71.52989) (xy 164.56159 71.51615)
			(xy 164.56159 71.50242) (xy 164.56159 71.48869) (xy 164.56159 71.47496) (xy 164.56159 71.46123) (xy 164.56159 71.4475)
			(xy 164.56159 71.43376) (xy 164.56159 71.42003) (xy 164.56159 71.4063) (xy 164.56159 71.39257) (xy 164.56159 71.37884)
			(xy 164.56159 71.3651) (xy 164.56159 71.35137) (xy 164.56159 71.33764) (xy 164.56159 71.32391) (xy 164.56159 71.31018)
			(xy 164.56159 71.29644) (xy 164.56159 71.28271) (xy 164.56159 71.26898) (xy 164.56159 71.25525) (xy 164.56159 71.24152)
			(xy 164.56159 71.22779) (xy 164.56159 71.21405) (xy 164.56159 71.20032) (xy 164.56159 71.18659) (xy 164.56159 71.17286)
			(xy 164.56159 71.15913) (xy 164.56159 71.1454) (xy 164.56159 71.13166) (xy 164.56159 71.11793) (xy 164.56159 71.1042)
			(xy 164.56159 71.09047) (xy 164.56159 71.07674) (xy 164.56159 71.06301) (xy 164.56159 71.04927) (xy 164.56159 71.03554)
			(xy 164.56159 71.02181) (xy 164.56159 71.00808) (xy 164.56159 70.99435) (xy 164.56159 70.98062) (xy 164.56159 70.96688)
			(xy 164.56159 70.95315) (xy 164.56159 70.93942) (xy 164.56159 70.92569) (xy 164.56159 70.91196) (xy 164.56159 70.89823)
			(xy 164.56159 70.88449) (xy 164.56159 70.87076) (xy 164.56159 70.85703) (xy 164.56159 70.8433) (xy 164.56159 70.82957)
			(xy 164.56159 70.81583) (xy 164.56159 70.8021) (xy 164.56159 70.78837) (xy 164.56159 70.77464) (xy 164.56159 70.76091)
			(xy 164.56159 70.74717) (xy 164.56159 70.73344) (xy 164.56159 70.71971) (xy 164.56159 70.70598) (xy 164.56159 70.69225)
			(xy 164.56159 70.67852) (xy 164.56159 70.66478) (xy 164.56159 70.65105) (xy 164.56159 70.63732) (xy 164.56159 70.62359)
			(xy 164.56159 70.60986) (xy 164.56159 70.59613) (xy 164.56159 70.58239) (xy 164.56159 70.56866) (xy 164.56159 70.55493)
			(xy 164.56159 70.5412) (xy 164.56159 70.52747) (xy 164.56159 70.51374) (xy 164.56159 70.5) (xy 164.56159 70.48627)
			(xy 164.56159 70.47254) (xy 164.56159 70.45881) (xy 164.56159 70.44508) (xy 164.56159 70.43135) (xy 164.56159 70.41761)
			(xy 164.56159 70.40388) (xy 164.56159 70.39015) (xy 164.56159 70.37642) (xy 164.56159 70.36269) (xy 164.56159 70.34896)
			(xy 164.56159 70.33522) (xy 164.56159 70.32149) (xy 164.56159 70.30776) (xy 164.56159 70.29403) (xy 164.56159 70.2803)
			(xy 164.56159 70.26656) (xy 164.56159 70.25283) (xy 164.56159 70.2391) (xy 164.56159 70.22537) (xy 164.56159 70.21164)
			(xy 164.56159 70.1979) (xy 164.56159 70.18417) (xy 164.56159 70.17044) (xy 164.56159 70.15671) (xy 164.56159 70.14298)
			(xy 164.56159 70.12925) (xy 164.56159 70.11551) (xy 164.56159 70.10178) (xy 164.56159 70.08805) (xy 164.56159 70.07432)
			(xy 164.56159 70.06059) (xy 164.56159 70.04686) (xy 164.56159 70.03312) (xy 164.56159 70.01939) (xy 164.56159 70.00566)
			(xy 164.56159 69.99193) (xy 164.56159 69.9782) (xy 164.56159 69.96447) (xy 164.56159 69.95073) (xy 164.56159 69.937)
			(xy 164.56159 69.92327) (xy 164.56159 69.90954) (xy 164.56159 69.89581) (xy 164.56159 69.88208) (xy 164.56159 69.86834)
			(xy 164.56159 69.85461) (xy 164.56159 69.84088) (xy 164.56159 69.82715) (xy 164.56159 69.81342) (xy 164.56159 69.79969)
			(xy 164.56159 69.78595) (xy 164.56159 69.77222) (xy 164.56159 69.75849) (xy 164.56159 69.74476) (xy 164.56159 69.73103)
			(xy 164.56159 69.71729) (xy 164.56159 69.70356) (xy 164.56159 69.68983) (xy 164.56159 69.6761) (xy 164.56159 69.66237)
			(xy 164.56159 69.64863) (xy 164.56159 69.6349) (xy 164.56159 69.62117) (xy 164.56159 69.60744) (xy 164.56159 69.59371)
			(xy 164.56159 69.57998) (xy 164.56159 69.56624) (xy 164.56159 69.55251) (xy 164.56159 69.53878) (xy 164.56159 69.52505)
			(xy 164.56159 69.51132) (xy 164.56159 69.49759) (xy 164.56159 69.48385) (xy 164.56159 69.47012) (xy 164.56159 69.45639)
			(xy 164.56159 69.44266) (xy 164.56159 69.42893) (xy 164.56159 69.4152) (xy 164.56159 69.40146) (xy 164.56159 69.38773)
			(xy 164.56159 69.374) (xy 164.56159 69.36027) (xy 164.56159 69.34654) (xy 164.56159 69.33281) (xy 164.56159 69.31907)
			(xy 164.56159 69.30534) (xy 164.56159 69.29161) (xy 164.56159 69.27788) (xy 164.56159 69.26415) (xy 164.56159 69.25041)
			(xy 164.56159 69.23668) (xy 164.56159 69.22295) (xy 164.56159 69.20922) (xy 164.56159 69.19549) (xy 164.56159 69.18175)
			(xy 164.56159 69.16802) (xy 164.56159 69.15429) (xy 164.56159 69.14056) (xy 164.56159 69.12683) (xy 164.56159 69.1131)
			(xy 164.56159 69.09936) (xy 164.56159 69.08563) (xy 164.56159 69.0719) (xy 164.56159 69.05817) (xy 164.56159 69.04444)
			(xy 164.56159 69.03071) (xy 164.56159 69.01697) (xy 164.56159 69.00324) (xy 164.56159 68.98951) (xy 164.56159 68.97578)
			(xy 164.56159 68.96205) (xy 164.56159 68.94832) (xy 164.56159 68.93458) (xy 164.56159 68.92085) (xy 164.56159 68.90712)
			(xy 164.56159 68.89339) (xy 164.56159 68.87966) (xy 164.56159 68.86593) (xy 164.56159 68.85219) (xy 164.56159 68.83846)
			(xy 164.56159 68.82473) (xy 164.56159 68.811) (xy 164.56159 68.79727) (xy 164.56159 68.78354) (xy 164.56159 68.7698)
			(xy 164.56159 68.75607) (xy 164.56159 68.74234) (xy 164.56159 68.72861) (xy 164.56159 68.71488) (xy 164.56159 68.70114)
			(xy 164.56159 68.68741) (xy 164.56159 68.67368) (xy 164.56159 68.65995) (xy 164.56159 68.64622) (xy 164.56159 68.63248)
			(xy 164.56159 68.61875) (xy 164.56159 68.60502) (xy 164.56159 68.59129) (xy 164.56159 68.57756) (xy 164.56159 68.56383)
			(xy 164.56159 68.55009) (xy 164.56159 68.53636) (xy 164.56159 68.52263) (xy 164.56159 68.5089) (xy 164.56159 68.49517)
			(xy 164.56159 68.48144) (xy 164.56159 68.4677) (xy 164.56159 68.45397) (xy 164.56159 68.44024) (xy 164.56159 68.42651)
			(xy 164.56159 68.41278) (xy 164.56159 68.39905) (xy 164.56159 68.38531) (xy 164.56159 68.37158) (xy 164.56159 68.35785)
			(xy 164.56159 68.34412) (xy 164.56159 68.33039) (xy 164.56159 68.31666) (xy 164.56159 68.30292) (xy 164.56159 68.28919)
			(xy 164.56159 68.27546) (xy 164.56159 68.26173) (xy 164.56159 68.248) (xy 164.56159 68.23427) (xy 164.56159 68.22053)
			(xy 164.56159 68.2068) (xy 164.56159 68.19307) (xy 164.56159 68.17934) (xy 164.56159 68.16561) (xy 164.56159 68.15187)
			(xy 164.56159 68.13814) (xy 164.56159 68.12441) (xy 164.56159 68.11068) (xy 164.56159 68.09695) (xy 164.56159 68.08321)
			(xy 164.56159 68.06948) (xy 164.56159 68.05575) (xy 164.56159 68.04202) (xy 164.56159 68.02829) (xy 164.56159 68.01456)
			(xy 164.56159 68.00082) (xy 164.56159 67.98709) (xy 164.56159 67.97336) (xy 164.56159 67.95963) (xy 164.56159 67.9459)
			(xy 164.56159 67.93217) (xy 164.56159 67.91843) (xy 164.56159 67.9047) (xy 164.56159 67.89097) (xy 164.56159 67.87724)
			(xy 164.56159 67.86351) (xy 164.56159 67.84978) (xy 164.56159 67.83604) (xy 164.56159 67.82231) (xy 164.56159 67.80858)
			(xy 164.56159 67.79485) (xy 164.56159 67.78112) (xy 164.56159 67.76739) (xy 164.56159 67.75365) (xy 164.56159 67.73992)
			(xy 164.56159 67.72619) (xy 164.56159 67.71246) (xy 164.56159 67.69873) (xy 164.56159 67.685) (xy 164.56159 67.67126)
			(xy 164.56159 67.65753) (xy 164.56159 67.6438) (xy 164.56159 67.63007) (xy 164.56159 67.61634) (xy 164.56159 67.6026)
			(xy 164.56159 67.58887) (xy 164.56159 67.57514) (xy 164.56159 67.56141) (xy 164.56159 67.54768) (xy 164.56159 67.53394)
			(xy 164.56159 67.52021) (xy 164.56159 67.50648) (xy 164.56159 67.49275) (xy 164.56159 67.47902) (xy 164.56159 67.46529)
			(xy 164.56159 67.45155) (xy 164.56159 67.43782) (xy 164.56159 67.42409) (xy 164.56159 67.41036) (xy 164.56159 67.39663)
			(xy 164.56159 67.3829) (xy 164.56159 67.36916) (xy 164.56159 67.35543) (xy 164.56159 67.3417) (xy 164.56159 67.32797)
			(xy 164.56159 67.31424) (xy 164.56159 67.30051) (xy 164.56159 67.28677) (xy 164.56159 67.27304) (xy 164.56159 67.25931)
			(xy 164.56159 67.24558) (xy 164.56159 67.23185) (xy 164.56159 67.21812) (xy 164.56159 67.20438) (xy 164.56159 67.19065)
			(xy 164.56159 67.17692) (xy 164.56159 67.16319) (xy 164.56159 67.14946) (xy 164.56159 67.13573) (xy 164.56159 67.12199)
			(xy 164.56159 67.10826) (xy 164.56159 67.09453) (xy 164.56159 67.0808) (xy 164.56159 67.06707) (xy 164.56159 67.05333)
			(xy 164.56159 67.0396) (xy 164.56159 67.02587) (xy 164.56159 67.01214) (xy 164.56159 66.99841) (xy 164.56159 66.98467)
			(xy 164.56159 66.97094) (xy 164.56159 66.95721) (xy 164.56159 66.94348) (xy 164.56159 66.92975) (xy 164.56159 66.91602)
			(xy 164.56159 66.90228) (xy 164.56159 66.88855) (xy 164.56159 66.87482) (xy 164.56159 66.86109) (xy 164.56159 66.84736)
			(xy 164.56159 66.83363) (xy 164.56159 66.81989) (xy 164.56159 66.80616) (xy 164.56159 66.79243) (xy 164.56159 66.7787)
			(xy 164.56159 66.76497) (xy 164.56159 66.75124) (xy 164.56159 66.7375) (xy 164.56159 66.72377) (xy 164.56159 66.71004)
			(xy 164.56159 66.69631) (xy 164.56159 66.68258) (xy 164.56159 66.66885) (xy 164.56159 66.65511) (xy 164.56159 66.64138)
			(xy 164.56159 66.62765) (xy 164.56159 66.61392) (xy 164.56159 66.60019) (xy 164.56159 66.58645) (xy 164.56159 66.57272)
			(xy 164.56159 66.55899) (xy 164.56159 66.54526) (xy 164.56159 66.53153) (xy 164.56159 66.51779) (xy 164.56159 66.50406)
			(xy 164.56159 66.49033) (xy 164.56159 66.4766) (xy 164.56159 66.46287) (xy 164.56159 66.44914) (xy 164.56159 66.4354)
			(xy 164.56159 66.42167) (xy 164.56159 66.40794) (xy 164.56159 66.39421) (xy 164.56159 66.38048) (xy 164.56159 66.36675)
			(xy 164.56159 66.35301) (xy 164.56159 66.33928) (xy 164.56159 66.32555) (xy 164.56159 66.31182) (xy 164.56159 66.29809)
			(xy 164.56159 66.28436) (xy 164.56159 66.27062) (xy 164.56159 66.25689) (xy 164.56159 66.24316) (xy 164.56159 66.22943)
			(xy 164.56159 66.2157) (xy 164.56159 66.20197) (xy 164.56159 66.18823) (xy 164.56159 66.1745) (xy 164.56159 66.16077)
			(xy 164.56159 66.14704) (xy 164.56159 66.13331) (xy 164.56159 66.11958) (xy 164.56159 66.10584) (xy 164.56159 66.09211)
			(xy 164.56159 66.07838) (xy 164.56159 66.06465) (xy 164.56159 66.05092) (xy 164.56159 66.03718) (xy 164.56159 66.02345)
			(xy 164.56159 66.00972) (xy 164.56159 65.99599) (xy 164.56159 65.98226) (xy 164.56159 65.96852) (xy 164.56159 65.95479)
			(xy 164.56159 65.94106) (xy 164.56159 65.92733) (xy 164.56159 65.9136) (xy 164.56159 65.89987) (xy 164.56159 65.88613)
			(xy 164.56159 65.8724) (xy 164.56159 65.85867) (xy 164.56159 65.84494) (xy 164.56159 65.83121) (xy 164.56159 65.81748)
			(xy 164.56159 65.80374) (xy 164.56159 65.79001) (xy 164.56159 65.77628) (xy 164.56159 65.76255) (xy 164.56159 65.74882)
			(xy 164.56159 65.73509) (xy 164.56159 65.72135) (xy 164.56159 65.70762) (xy 164.56159 65.69389) (xy 164.56159 65.68016)
			(xy 164.56159 65.66643) (xy 164.56159 65.6527) (xy 164.56159 65.63896) (xy 164.56159 65.62523) (xy 164.56159 65.6115)
			(xy 164.56159 65.59777) (xy 164.56159 65.58404) (xy 164.56159 65.57031) (xy 164.56159 65.55657) (xy 164.56159 65.54284)
			(xy 164.56159 65.52911) (xy 164.56159 65.51538) (xy 164.56159 65.50165) (xy 164.56159 65.48791) (xy 164.56159 65.47418)
			(xy 164.56159 65.46045) (xy 164.56159 65.44672) (xy 164.56159 65.43299) (xy 164.56159 65.41925) (xy 164.56159 65.40552)
			(xy 164.56159 65.39179) (xy 164.56159 65.37806) (xy 164.56159 65.36433) (xy 164.56159 65.3506) (xy 164.56159 65.33686)
			(xy 164.56159 65.32313) (xy 164.56159 65.3094) (xy 164.56159 65.29567) (xy 164.56159 65.28194) (xy 164.56159 65.26821)
			(xy 164.56159 65.25447) (xy 164.56159 65.24074) (xy 164.56159 65.22701) (xy 164.56159 65.21328) (xy 164.56159 65.19955)
			(xy 164.56159 65.18582) (xy 164.56159 65.17208) (xy 164.56159 65.15835) (xy 164.56159 65.14462) (xy 164.56159 65.13089)
			(xy 164.56159 65.11716) (xy 164.56159 65.10343) (xy 164.56159 65.08969) (xy 164.56159 65.07596) (xy 164.56159 65.06223)
			(xy 164.56159 65.0485) (xy 164.56159 65.03477) (xy 164.56159 65.02104) (xy 164.56159 65.0073) (xy 164.56159 64.99357)
			(xy 164.56159 64.97984) (xy 164.56159 64.96611) (xy 164.56159 64.95238) (xy 164.56159 64.93864) (xy 164.56159 64.92491)
			(xy 164.56159 64.91118) (xy 164.56159 64.89745) (xy 164.56159 64.88372) (xy 164.56159 64.86998) (xy 164.56159 64.85625)
			(xy 164.56159 64.84252) (xy 164.56159 64.82879) (xy 164.56159 64.81506) (xy 164.56159 64.80133) (xy 164.56159 64.78759)
			(xy 164.56159 64.77386) (xy 164.56159 64.76013) (xy 164.56159 64.7464) (xy 164.56159 64.73267) (xy 164.56159 64.71894)
			(xy 164.56159 64.7052) (xy 164.56159 64.69147) (xy 164.56159 64.67774) (xy 164.56159 64.66401) (xy 164.56159 64.65028)
			(xy 164.56159 64.63655) (xy 164.56159 64.62281) (xy 164.56159 64.60908) (xy 164.56159 64.59535) (xy 164.56159 64.58162)
			(xy 164.56159 64.56789) (xy 164.56159 64.55416) (xy 164.56159 64.54042) (xy 164.56159 64.52669) (xy 164.56159 64.51296)
			(xy 164.56159 64.49923) (xy 164.56159 64.4855) (xy 164.56159 64.47176) (xy 164.56159 64.45803) (xy 164.56159 64.4443)
			(xy 164.56159 64.43057) (xy 164.56159 64.41684) (xy 164.56159 64.4031) (xy 164.56159 64.38937) (xy 164.56159 64.37564)
			(xy 164.56159 64.36191) (xy 164.56159 64.34818) (xy 164.56159 64.33445) (xy 164.56159 64.32071) (xy 164.56159 64.30698)
			(xy 164.56159 64.29325) (xy 164.56159 64.27952) (xy 164.56159 64.26579) (xy 164.56159 64.25206) (xy 164.56159 64.23833)
			(xy 164.56159 64.22459) (xy 164.56159 64.21086) (xy 164.56159 64.19713) (xy 164.56159 64.1834) (xy 164.56159 64.16967)
			(xy 164.56159 64.15594) (xy 164.56159 64.1422) (xy 164.56159 64.12847) (xy 164.56159 64.11474) (xy 164.56159 64.10101)
			(xy 164.56159 64.08728) (xy 164.56159 64.07355) (xy 164.56159 64.05981) (xy 164.56159 64.04608) (xy 164.56159 64.03235)
			(xy 164.56159 64.01862) (xy 164.56159 64.00489) (xy 164.56159 63.99115) (xy 164.56159 63.97742) (xy 164.56159 63.96369)
			(xy 164.56159 63.94996) (xy 164.56159 63.93623) (xy 164.56159 63.92249) (xy 164.56159 63.90876) (xy 164.56159 63.89503)
			(xy 164.56159 63.8813) (xy 164.56159 63.86757) (xy 164.56159 63.85384) (xy 164.56159 63.8401) (xy 164.56159 63.82637)
			(xy 164.56159 63.81264) (xy 164.56159 63.79891) (xy 164.56159 63.78518) (xy 164.56159 63.77145) (xy 164.56159 63.75771)
			(xy 164.56159 63.74398) (xy 164.56159 63.73025) (xy 164.56159 63.71652) (xy 164.56159 63.70279) (xy 164.56159 63.68906)
			(xy 164.56159 63.67532) (xy 164.56159 63.66159) (xy 164.56159 63.64786) (xy 164.56159 63.63413) (xy 164.56159 63.6204)
			(xy 164.56159 63.60667) (xy 164.56159 63.59293) (xy 164.56159 63.5792) (xy 164.56159 63.56547) (xy 164.56159 63.55174)
			(xy 164.56159 63.53801) (xy 164.56159 63.52428) (xy 164.56159 63.51054) (xy 164.56159 63.49681) (xy 164.56159 63.48308)
			(xy 164.56159 63.46935) (xy 164.56159 63.45562) (xy 164.56159 63.44188) (xy 164.56159 63.42815) (xy 164.56159 63.41442)
			(xy 164.56159 63.40069) (xy 164.56159 63.38696) (xy 164.56159 63.37322) (xy 164.56159 63.35949) (xy 164.56159 63.34576)
			(xy 164.56159 63.33203) (xy 164.56159 63.3183) (xy 164.56159 63.30457) (xy 164.56159 63.29083) (xy 164.56159 63.2771)
			(xy 164.56159 63.26337) (xy 164.56159 63.24964) (xy 164.56159 63.23591) (xy 164.56159 63.22218) (xy 164.56159 63.20844)
			(xy 164.56159 63.19471) (xy 164.56159 63.18098) (xy 164.56159 63.16725) (xy 164.56159 63.15352) (xy 164.56159 63.13979)
			(xy 164.56159 63.12605) (xy 164.56159 63.11232) (xy 164.56159 63.09859) (xy 164.56159 63.08486) (xy 164.56159 63.07113)
			(xy 164.56159 63.0574) (xy 164.56159 63.04366) (xy 164.56159 63.02993) (xy 164.56159 63.0162) (xy 164.56159 63.00247)
			(xy 164.56159 62.98874) (xy 164.56159 62.97501) (xy 164.56159 62.96127) (xy 164.56159 62.94754) (xy 164.56159 62.93381)
			(xy 164.56159 62.92008) (xy 164.56159 62.90635) (xy 164.56159 62.89261) (xy 164.56159 62.87888) (xy 164.56159 62.86515)
			(xy 164.56159 62.85142) (xy 164.56159 62.83769) (xy 164.56159 62.82395) (xy 164.56159 62.81022) (xy 164.56159 62.79649)
			(xy 164.56159 62.78276) (xy 164.56159 62.76903) (xy 164.56159 62.7553) (xy 164.56159 62.74156) (xy 164.56159 62.72783)
			(xy 164.56159 62.7141) (xy 164.56159 62.70037) (xy 164.56159 62.68664) (xy 164.56159 62.67291) (xy 164.56159 62.65917)
			(xy 164.56159 62.64544) (xy 164.56159 62.63171) (xy 164.56159 62.61798) (xy 164.56159 62.60425) (xy 164.56159 62.59052)
			(xy 164.56159 62.57678) (xy 164.56159 62.56305) (xy 164.56159 62.54932) (xy 164.56159 62.53559) (xy 164.56159 62.52186)
			(xy 164.56159 62.50813) (xy 164.56159 62.49439) (xy 164.56159 62.48066) (xy 164.56159 62.46693) (xy 164.56159 62.4532)
			(xy 164.56159 62.43947) (xy 164.56159 62.42574) (xy 164.56159 62.412) (xy 164.56159 62.39827) (xy 164.56159 62.38454)
			(xy 164.56159 62.37081) (xy 164.56159 62.35708) (xy 164.56159 62.34334) (xy 164.56159 62.32961) (xy 164.56159 62.31588)
			(xy 164.56159 62.30215) (xy 164.56159 62.28842) (xy 164.56159 62.27468) (xy 164.56159 62.26095) (xy 164.56159 62.24722)
			(xy 164.56159 62.23349) (xy 164.56159 62.21976) (xy 164.56159 62.20603) (xy 164.56159 62.19229) (xy 164.56159 62.17856)
			(xy 164.56159 62.16483) (xy 164.56159 62.1511) (xy 164.56159 62.13737) (xy 164.56159 62.12364) (xy 164.56159 62.1099)
			(xy 164.56159 62.09617) (xy 164.56159 62.08244) (xy 164.56159 62.06871) (xy 164.56159 62.05498) (xy 164.56159 62.04125)
			(xy 164.56159 62.02751) (xy 164.56159 62.01378) (xy 164.56159 62.00005) (xy 164.56159 61.98632) (xy 164.56159 61.97259)
			(xy 164.56159 61.95886) (xy 164.56159 61.94512) (xy 164.56159 61.93139) (xy 164.56159 61.91766) (xy 164.56159 61.90393)
			(xy 164.56159 61.8902) (xy 164.56159 61.87646) (xy 164.56159 61.86273) (xy 164.56159 61.849) (xy 164.56159 61.83527)
			(xy 164.56159 61.82154) (xy 164.56159 61.8078) (xy 164.56159 61.79407) (xy 164.56159 61.78034) (xy 164.56159 61.76661)
			(xy 164.56159 61.75288) (xy 164.56159 61.73915) (xy 164.56159 61.72541) (xy 164.56159 61.71168) (xy 164.56159 61.69795)
			(xy 164.56159 61.68422) (xy 164.56159 61.67049) (xy 164.56159 61.65676) (xy 164.56159 61.64302) (xy 164.56159 61.62929)
			(xy 164.56159 61.61556) (xy 164.56159 61.60183) (xy 164.56159 61.5881) (xy 164.56159 61.57437) (xy 164.56159 61.56063)
			(xy 164.56159 61.5469) (xy 164.56159 61.53317) (xy 164.56159 61.51944) (xy 164.56159 61.50571) (xy 164.56159 61.49198)
			(xy 164.56159 61.47824) (xy 164.56159 61.46451) (xy 164.56159 61.45078) (xy 164.56159 61.43705) (xy 164.56159 61.42332)
			(xy 164.56159 61.40959) (xy 164.56159 61.39585) (xy 164.56159 61.38212) (xy 164.56159 61.36839) (xy 164.56159 61.35466)
			(xy 164.56159 61.34093) (xy 164.56159 61.32719) (xy 164.56159 61.31346) (xy 164.56159 61.29973) (xy 164.56159 61.286)
			(xy 164.56159 61.27227) (xy 164.56159 61.25853) (xy 164.56159 61.2448) (xy 164.56159 61.23107) (xy 164.56159 61.21734)
			(xy 164.56159 61.20361) (xy 164.56159 61.18988) (xy 164.56159 61.17614) (xy 164.56159 61.16241) (xy 164.56159 61.14868)
			(xy 164.56159 61.13495) (xy 164.56159 61.12122) (xy 164.56159 61.10749) (xy 164.56159 61.09375) (xy 164.56159 61.08002)
			(xy 164.56159 61.06629) (xy 164.56159 61.05256) (xy 164.56159 61.03883) (xy 164.56159 61.0251) (xy 164.56159 61.01136)
			(xy 164.56159 60.99763) (xy 164.56159 60.9839) (xy 164.56159 60.97017) (xy 164.56159 60.95644) (xy 164.56159 60.94271)
			(xy 164.56159 60.92897) (xy 164.56159 60.91524) (xy 164.56159 60.90151) (xy 164.56159 60.88778) (xy 164.56159 60.87405)
			(xy 164.56159 60.86032) (xy 164.56159 60.84658) (xy 164.56159 60.83285) (xy 164.56159 60.81912) (xy 164.56159 60.80539)
			(xy 164.56159 60.79166) (xy 164.56159 60.77792) (xy 164.56159 60.76419) (xy 164.56159 60.75046) (xy 164.56159 60.73673)
			(xy 164.56159 60.723) (xy 164.56159 60.70926) (xy 164.56159 60.69553) (xy 164.56159 60.6818) (xy 164.56159 60.66807)
			(xy 164.56159 60.65434) (xy 164.56159 60.64061) (xy 164.56159 60.62687) (xy 164.56159 60.61314) (xy 164.56159 60.59941)
			(xy 164.56159 60.58568) (xy 164.56159 60.57195) (xy 164.56159 60.55822) (xy 164.56159 60.54448) (xy 164.56159 60.53075)
			(xy 164.56159 60.51702) (xy 164.56159 60.50329) (xy 164.56159 60.48956) (xy 164.56159 60.47583) (xy 164.56159 60.46209)
			(xy 164.56159 60.44836) (xy 164.56159 60.43463) (xy 164.56159 60.4209) (xy 164.56159 60.40717) (xy 164.56159 60.39344)
			(xy 164.56159 60.3797) (xy 164.56159 60.36597) (xy 164.56159 60.35224) (xy 164.56159 60.33851) (xy 164.56159 60.32478)
			(xy 164.56159 60.31105) (xy 164.56159 60.29731) (xy 164.56159 60.28358) (xy 164.56159 60.26985) (xy 164.56159 60.25612)
			(xy 164.56159 60.24239) (xy 164.56159 60.22865) (xy 164.56159 60.21492) (xy 164.56159 60.20119) (xy 164.56159 60.18746)
			(xy 164.56159 60.17373) (xy 164.56159 60.15999) (xy 164.56159 60.14626) (xy 164.56159 60.13253) (xy 164.56159 60.1188)
			(xy 164.56159 60.10507) (xy 164.56159 60.09134) (xy 164.56159 60.0776) (xy 164.56159 60.06387) (xy 164.56159 60.05014)
			(xy 164.56159 60.03641) (xy 164.56159 60.02268) (xy 164.56159 60.00895) (xy 164.56159 59.99521) (xy 164.56159 59.98148)
			(xy 164.56159 59.96775) (xy 164.56159 59.95402) (xy 164.56159 59.94029) (xy 164.56159 59.92656) (xy 164.56159 59.91282)
			(xy 164.56159 59.89909) (xy 164.56159 59.88536) (xy 164.56159 59.87163) (xy 164.56159 59.8579) (xy 164.56159 59.84417)
			(xy 164.56159 59.83043) (xy 164.56159 59.8167) (xy 164.56159 59.80297) (xy 164.56159 59.78924) (xy 164.56159 59.77551)
			(xy 164.56159 59.76177) (xy 164.56159 59.74804) (xy 164.56159 59.73431) (xy 164.56159 59.72058) (xy 164.56159 59.70685)
			(xy 164.56159 59.69311) (xy 164.56159 59.67938) (xy 164.56159 59.66565) (xy 164.56159 59.65192) (xy 164.56159 59.63819)
			(xy 164.56159 59.62446) (xy 164.56159 59.61072) (xy 164.56159 59.59699) (xy 164.56159 59.58326) (xy 164.56159 59.56953)
			(xy 164.56159 59.5558) (xy 164.56159 59.54207) (xy 164.56159 59.52833) (xy 164.56159 59.5146) (xy 164.56159 59.50087)
			(xy 164.56159 59.48714) (xy 164.56159 59.47341) (xy 164.56159 59.45968) (xy 164.56159 59.44594) (xy 164.56159 59.43221)
			(xy 164.56159 59.41848) (xy 164.56159 59.40475) (xy 164.56159 59.39102) (xy 164.56159 59.37729) (xy 164.56159 59.36355)
			(xy 164.56159 59.34982) (xy 164.56159 59.33609) (xy 164.56159 59.32236) (xy 164.56159 59.30863) (xy 164.56159 59.2949)
			(xy 164.56159 59.28116) (xy 164.56159 59.26743) (xy 164.56159 59.2537) (xy 164.56159 59.23997) (xy 164.56159 59.22624)
			(xy 164.56159 59.2125) (xy 164.56159 59.19877) (xy 164.56159 59.18504) (xy 164.56159 59.17131) (xy 164.56159 59.15758)
			(xy 164.56159 59.14384) (xy 164.56159 59.13011) (xy 164.56159 59.11638) (xy 164.56159 59.10265) (xy 164.56159 59.08892)
			(xy 164.56159 59.07519) (xy 164.56159 59.06145) (xy 164.56159 59.04772) (xy 164.56159 59.03399) (xy 164.56159 59.02026)
			(xy 164.56159 59.00653) (xy 164.56159 58.9928) (xy 164.56159 58.97906) (xy 164.56159 58.96533) (xy 164.56159 58.9516)
			(xy 164.56159 58.93787) (xy 164.56159 58.92414) (xy 164.56159 58.91041) (xy 164.56159 58.89667) (xy 164.56159 58.88294)
			(xy 164.56159 58.86921) (xy 164.56159 58.85548) (xy 164.56159 58.84175) (xy 164.56159 58.82802) (xy 164.56159 58.81428)
			(xy 164.56159 58.80055) (xy 164.56159 58.78682) (xy 164.56159 58.77309) (xy 164.56159 58.75936) (xy 164.56159 58.74563)
			(xy 164.56159 58.73189) (xy 164.56159 58.71816) (xy 164.56159 58.70443) (xy 164.56159 58.6907) (xy 164.56159 58.67697)
			(xy 164.56159 58.66323) (xy 164.56159 58.6495) (xy 164.56159 58.63577) (xy 164.56159 58.62204) (xy 164.56159 58.60831)
			(xy 164.56159 58.59457) (xy 164.56159 58.58084) (xy 164.56159 58.56711) (xy 164.56159 58.55338) (xy 164.56159 58.53965)
			(xy 164.56159 58.52592) (xy 164.56159 58.51218) (xy 164.56159 58.49845) (xy 164.56159 58.48472) (xy 164.56159 58.47099)
			(xy 164.56159 58.45726) (xy 164.56159 58.44353) (xy 164.56159 58.42979) (xy 164.56159 58.41606) (xy 164.56159 58.40233)
			(xy 164.56159 58.3886) (xy 164.56159 58.37487) (xy 164.56159 58.36114) (xy 164.56159 58.3474) (xy 164.56159 58.33367)
			(xy 164.56159 58.31994) (xy 164.56159 58.30621) (xy 164.56159 58.29248) (xy 164.56159 58.27875) (xy 164.56159 58.26501)
			(xy 164.56159 58.25128) (xy 164.56159 58.23755) (xy 164.56159 58.22382) (xy 164.56159 58.21009) (xy 164.56159 58.19636)
			(xy 164.56159 58.18262) (xy 164.56159 58.16889) (xy 164.56159 58.15516) (xy 164.56159 58.14143) (xy 164.56159 58.1277)
			(xy 164.56159 58.11396) (xy 164.56159 58.10023) (xy 164.56159 58.0865) (xy 164.56159 58.07277) (xy 164.56159 58.05904)
			(xy 164.56159 58.0453) (xy 164.56159 58.03157) (xy 164.56159 58.01784) (xy 164.56159 58.00411) (xy 164.56159 57.99038)
			(xy 164.56159 57.97665) (xy 164.56159 57.96291) (xy 164.56159 57.94918) (xy 164.56159 57.93545) (xy 164.56159 57.92172)
			(xy 164.56159 57.90799) (xy 164.57532 57.90799) (xy 164.57532 57.89426) (xy 164.57532 57.88052) (xy 164.57532 57.86679)
			(xy 164.57532 57.85306) (xy 164.57532 57.83933) (xy 164.58905 57.83933) (xy 164.58905 57.8256) (xy 164.58905 57.81187)
			(xy 164.60279 57.81187) (xy 164.60279 57.79813) (xy 164.60279 57.7844) (xy 164.61652 57.7844) (xy 164.61652 57.77067)
			(xy 164.61652 57.75694) (xy 164.63025 57.75694) (xy 164.63025 57.74321) (xy 164.64398 57.74321) (xy 164.64398 57.72948)
			(xy 164.64398 57.71574) (xy 164.65771 57.71574) (xy 164.65771 57.70201) (xy 164.67145 57.70201) (xy 164.67145 57.68828)
			(xy 164.68518 57.68828) (xy 164.68518 57.67455) (xy 164.71264 57.67455) (xy 164.71264 57.66082) (xy 164.72637 57.66082)
			(xy 164.72637 57.64708) (xy 164.75384 57.64708) (xy 164.75384 57.63335) (xy 164.7813 57.63335) (xy 164.7813 57.61962)
			(xy 164.80876 57.61962) (xy 164.80876 57.60589) (xy 164.86369 57.60589) (xy 164.86369 57.59216) (xy 166.60762 57.59216)
			(xy 166.60762 57.57842) (xy 166.60762 57.56469) (xy 166.60762 57.55096) (xy 166.60762 57.53723) (xy 166.60762 57.5235)
			(xy 166.60762 57.50977) (xy 166.60762 57.49603) (xy 166.60762 57.4823) (xy 166.60762 57.46857) (xy 166.60762 57.45484)
			(xy 166.60762 57.44111) (xy 166.60762 57.42738) (xy 166.60762 57.41364) (xy 166.60762 57.39991) (xy 166.60762 57.38618)
			(xy 166.60762 57.37245) (xy 166.60762 57.35872) (xy 166.60762 57.34499) (xy 166.60762 57.33125) (xy 166.60762 57.31752)
			(xy 166.60762 57.30379) (xy 166.60762 57.29006) (xy 166.60762 57.27633) (xy 166.60762 57.2626) (xy 166.60762 57.24886)
			(xy 166.60762 57.23513) (xy 166.60762 57.2214) (xy 166.60762 57.20767) (xy 166.60762 57.19394) (xy 166.60762 57.18021)
			(xy 166.60762 57.16647) (xy 166.60762 57.15274) (xy 166.60762 57.13901) (xy 166.60762 57.12528) (xy 166.60762 57.11155)
			(xy 166.60762 57.09781) (xy 166.60762 57.08408) (xy 166.60762 57.07035) (xy 164.86369 57.07035)
		)
		(stroke
			(width 0)
			(type default)
		)
		(fill yes)
		(layer "B.Cu")
	)
	(gr_poly
		(pts
			(xy 163.53171 57.08408) (xy 163.54544 57.08408) (xy 163.54544 57.09781) (xy 163.54544 57.11155) (xy 163.54544 57.12528)
			(xy 163.54544 57.13901) (xy 163.54544 57.15274) (xy 163.54544 57.16647) (xy 163.54544 57.18021) (xy 163.54544 57.19394)
			(xy 163.54544 57.20767) (xy 163.54544 57.2214) (xy 163.54544 57.23513) (xy 163.54544 57.24886) (xy 163.54544 57.2626)
			(xy 163.54544 57.27633) (xy 163.54544 57.29006) (xy 163.54544 57.30379) (xy 163.54544 57.31752) (xy 163.54544 57.33125)
			(xy 163.54544 57.34499) (xy 163.54544 57.35872) (xy 163.54544 57.37245) (xy 163.54544 57.38618) (xy 163.54544 57.39991)
			(xy 163.54544 57.41364) (xy 163.54544 57.42738) (xy 163.54544 57.44111) (xy 163.54544 57.45484) (xy 163.54544 57.46857)
			(xy 163.54544 57.4823) (xy 163.54544 57.49603) (xy 163.54544 57.50977) (xy 163.54544 57.5235) (xy 163.54544 57.53723)
			(xy 163.54544 57.55096) (xy 163.54544 57.56469) (xy 163.54544 57.57842) (xy 163.54544 57.59216) (xy 163.54544 57.60589)
			(xy 163.54544 57.61962) (xy 163.54544 57.63335) (xy 163.54544 57.64708) (xy 163.54544 57.66082) (xy 163.54544 57.67455)
			(xy 163.54544 57.68828) (xy 163.54544 57.70201) (xy 163.54544 57.71574) (xy 163.54544 57.72948) (xy 163.54544 57.74321)
			(xy 163.54544 57.75694) (xy 163.54544 57.77067) (xy 163.54544 57.7844) (xy 163.54544 57.79813) (xy 163.54544 57.81187)
			(xy 163.54544 57.8256) (xy 163.54544 57.83933) (xy 163.54544 57.85306) (xy 163.54544 57.86679) (xy 163.54544 57.88052)
			(xy 163.54544 57.89426) (xy 163.54544 57.90799) (xy 163.54544 57.92172) (xy 163.54544 57.93545) (xy 163.54544 57.94918)
			(xy 163.54544 57.96291) (xy 163.54544 57.97665) (xy 163.54544 57.99038) (xy 163.54544 58.00411) (xy 163.54544 58.01784)
			(xy 163.54544 58.03157) (xy 163.54544 58.0453) (xy 163.54544 58.05904) (xy 163.54544 58.07277) (xy 163.54544 58.0865)
			(xy 163.54544 58.10023) (xy 163.54544 58.11396) (xy 163.54544 58.1277) (xy 163.54544 58.14143) (xy 163.54544 58.15516)
			(xy 163.54544 58.16889) (xy 163.54544 58.18262) (xy 163.54544 58.19636) (xy 163.54544 58.21009) (xy 163.54544 58.22382)
			(xy 163.54544 58.23755) (xy 163.54544 58.25128) (xy 163.54544 58.26501) (xy 163.54544 58.27875) (xy 163.54544 58.29248)
			(xy 163.54544 58.30621) (xy 163.54544 58.31994) (xy 163.54544 58.33367) (xy 163.54544 58.3474) (xy 163.54544 58.36114)
			(xy 163.54544 58.37487) (xy 163.54544 58.3886) (xy 163.54544 58.40233) (xy 163.54544 58.41606) (xy 163.54544 58.42979)
			(xy 163.54544 58.44353) (xy 163.54544 58.45726) (xy 163.54544 58.47099) (xy 163.54544 58.48472) (xy 163.54544 58.49845)
			(xy 163.54544 58.51218) (xy 163.54544 58.52592) (xy 163.54544 58.53965) (xy 163.54544 58.55338) (xy 163.54544 58.56711)
			(xy 163.54544 58.58084) (xy 163.54544 58.59457) (xy 163.54544 58.60831) (xy 163.54544 58.62204) (xy 163.54544 58.63577)
			(xy 163.54544 58.6495) (xy 163.54544 58.66323) (xy 163.54544 58.67697) (xy 163.54544 58.6907) (xy 163.54544 58.70443)
			(xy 163.54544 58.71816) (xy 163.54544 58.73189) (xy 163.54544 58.74563) (xy 163.54544 58.75936) (xy 163.54544 58.77309)
			(xy 163.54544 58.78682) (xy 163.54544 58.80055) (xy 163.54544 58.81428) (xy 163.54544 58.82802) (xy 163.54544 58.84175)
			(xy 163.54544 58.85548) (xy 163.54544 58.86921) (xy 163.54544 58.88294) (xy 163.54544 58.89667) (xy 163.54544 58.91041)
			(xy 163.54544 58.92414) (xy 163.54544 58.93787) (xy 163.54544 58.9516) (xy 163.54544 58.96533) (xy 163.54544 58.97906)
			(xy 163.54544 58.9928) (xy 163.54544 59.00653) (xy 163.54544 59.02026) (xy 163.54544 59.03399) (xy 163.54544 59.04772)
			(xy 163.54544 59.06145) (xy 163.54544 59.07519) (xy 163.54544 59.08892) (xy 163.54544 59.10265) (xy 163.54544 59.11638)
			(xy 163.54544 59.13011) (xy 163.54544 59.14384) (xy 163.54544 59.15758) (xy 163.54544 59.17131) (xy 163.54544 59.18504)
			(xy 163.54544 59.19877) (xy 163.54544 59.2125) (xy 163.54544 59.22624) (xy 163.54544 59.23997) (xy 163.54544 59.2537)
			(xy 163.54544 59.26743) (xy 163.54544 59.28116) (xy 163.54544 59.2949) (xy 163.54544 59.30863) (xy 163.54544 59.32236)
			(xy 163.54544 59.33609) (xy 163.54544 59.34982) (xy 163.54544 59.36355) (xy 163.54544 59.37729) (xy 163.54544 59.39102)
			(xy 163.54544 59.40475) (xy 163.54544 59.41848) (xy 163.54544 59.43221) (xy 163.54544 59.44594) (xy 163.54544 59.45968)
			(xy 163.54544 59.47341) (xy 163.54544 59.48714) (xy 163.54544 59.50087) (xy 163.54544 59.5146) (xy 163.54544 59.52833)
			(xy 163.54544 59.54207) (xy 163.54544 59.5558) (xy 163.54544 59.56953) (xy 163.54544 59.58326) (xy 163.54544 59.59699)
			(xy 163.54544 59.61072) (xy 163.54544 59.62446) (xy 163.54544 59.63819) (xy 163.54544 59.65192) (xy 163.54544 59.66565)
			(xy 163.54544 59.67938) (xy 163.54544 59.69311) (xy 163.54544 59.70685) (xy 163.54544 59.72058) (xy 163.54544 59.73431)
			(xy 163.54544 59.74804) (xy 163.54544 59.76177) (xy 163.54544 59.77551) (xy 163.54544 59.78924) (xy 163.54544 59.80297)
			(xy 163.54544 59.8167) (xy 163.54544 59.83043) (xy 163.54544 59.84417) (xy 163.54544 59.8579) (xy 163.54544 59.87163)
			(xy 163.54544 59.88536) (xy 163.54544 59.89909) (xy 163.54544 59.91282) (xy 163.54544 59.92656) (xy 163.54544 59.94029)
			(xy 163.54544 59.95402) (xy 163.54544 59.96775) (xy 163.54544 59.98148) (xy 163.54544 59.99521) (xy 163.54544 60.00895)
			(xy 163.54544 60.02268) (xy 163.54544 60.03641) (xy 163.54544 60.05014) (xy 163.54544 60.06387) (xy 163.54544 60.0776)
			(xy 163.54544 60.09134) (xy 163.54544 60.10507) (xy 163.54544 60.1188) (xy 163.54544 60.13253) (xy 163.54544 60.14626)
			(xy 163.54544 60.15999) (xy 163.54544 60.17373) (xy 163.54544 60.18746) (xy 163.54544 60.20119) (xy 163.54544 60.21492)
			(xy 163.54544 60.22865) (xy 163.54544 60.24239) (xy 163.54544 60.25612) (xy 163.54544 60.26985) (xy 163.54544 60.28358)
			(xy 163.54544 60.29731) (xy 163.54544 60.31105) (xy 163.54544 60.32478) (xy 163.54544 60.33851) (xy 163.54544 60.35224)
			(xy 163.54544 60.36597) (xy 163.54544 60.3797) (xy 163.54544 60.39344) (xy 163.54544 60.40717) (xy 163.54544 60.4209)
			(xy 163.54544 60.43463) (xy 163.54544 60.44836) (xy 163.54544 60.46209) (xy 163.54544 60.47583) (xy 163.54544 60.48956)
			(xy 163.54544 60.50329) (xy 163.54544 60.51702) (xy 163.54544 60.53075) (xy 163.54544 60.54448) (xy 163.54544 60.55822)
			(xy 163.54544 60.57195) (xy 163.54544 60.58568) (xy 163.54544 60.59941) (xy 163.54544 60.61314) (xy 163.54544 60.62687)
			(xy 163.54544 60.64061) (xy 163.54544 60.65434) (xy 163.54544 60.66807) (xy 163.54544 60.6818) (xy 163.54544 60.69553)
			(xy 163.54544 60.70926) (xy 163.54544 60.723) (xy 163.54544 60.73673) (xy 163.54544 60.75046) (xy 163.54544 60.76419)
			(xy 163.54544 60.77792) (xy 163.54544 60.79166) (xy 163.54544 60.80539) (xy 163.54544 60.81912) (xy 163.54544 60.83285)
			(xy 163.54544 60.84658) (xy 163.54544 60.86032) (xy 163.54544 60.87405) (xy 163.54544 60.88778) (xy 163.54544 60.90151)
			(xy 163.54544 60.91524) (xy 163.54544 60.92897) (xy 163.54544 60.94271) (xy 163.54544 60.95644) (xy 163.54544 60.97017)
			(xy 163.54544 60.9839) (xy 163.54544 60.99763) (xy 163.54544 61.01136) (xy 163.54544 61.0251) (xy 163.54544 61.03883)
			(xy 163.54544 61.05256) (xy 163.54544 61.06629) (xy 163.54544 61.08002) (xy 163.54544 61.09375) (xy 163.54544 61.10749)
			(xy 163.54544 61.12122) (xy 163.54544 61.13495) (xy 163.54544 61.14868) (xy 163.54544 61.16241) (xy 163.54544 61.17614)
			(xy 163.54544 61.18988) (xy 163.54544 61.20361) (xy 163.54544 61.21734) (xy 163.54544 61.23107) (xy 163.54544 61.2448)
			(xy 163.54544 61.25853) (xy 163.54544 61.27227) (xy 163.54544 61.286) (xy 163.54544 61.29973) (xy 163.54544 61.31346)
			(xy 163.54544 61.32719) (xy 163.54544 61.34093) (xy 163.54544 61.35466) (xy 163.54544 61.36839) (xy 163.54544 61.38212)
			(xy 163.54544 61.39585) (xy 163.54544 61.40959) (xy 163.54544 61.42332) (xy 163.54544 61.43705) (xy 163.54544 61.45078)
			(xy 163.54544 61.46451) (xy 163.54544 61.47824) (xy 163.54544 61.49198) (xy 163.54544 61.50571) (xy 163.54544 61.51944)
			(xy 163.54544 61.53317) (xy 163.54544 61.5469) (xy 163.54544 61.56063) (xy 163.54544 61.57437) (xy 163.54544 61.5881)
			(xy 163.54544 61.60183) (xy 163.54544 61.61556) (xy 163.54544 61.62929) (xy 163.54544 61.64302) (xy 163.54544 61.65676)
			(xy 163.54544 61.67049) (xy 163.54544 61.68422) (xy 163.54544 61.69795) (xy 163.54544 61.71168) (xy 163.54544 61.72541)
			(xy 163.54544 61.73915) (xy 163.54544 61.75288) (xy 163.54544 61.76661) (xy 163.54544 61.78034) (xy 163.54544 61.79407)
			(xy 163.54544 61.8078) (xy 163.54544 61.82154) (xy 163.54544 61.83527) (xy 163.54544 61.849) (xy 163.54544 61.86273)
			(xy 163.54544 61.87646) (xy 163.54544 61.8902) (xy 163.54544 61.90393) (xy 163.54544 61.91766) (xy 163.54544 61.93139)
			(xy 163.54544 61.94512) (xy 163.54544 61.95886) (xy 163.54544 61.97259) (xy 163.54544 61.98632) (xy 163.54544 62.00005)
			(xy 163.54544 62.01378) (xy 163.54544 62.02751) (xy 163.54544 62.04125) (xy 163.54544 62.05498) (xy 163.54544 62.06871)
			(xy 163.54544 62.08244) (xy 163.54544 62.09617) (xy 163.54544 62.1099) (xy 163.54544 62.12364) (xy 163.54544 62.13737)
			(xy 163.54544 62.1511) (xy 163.54544 62.16483) (xy 163.54544 62.17856) (xy 163.54544 62.19229) (xy 163.54544 62.20603)
			(xy 163.54544 62.21976) (xy 163.54544 62.23349) (xy 163.54544 62.24722) (xy 163.54544 62.26095) (xy 163.54544 62.27468)
			(xy 163.54544 62.28842) (xy 163.54544 62.30215) (xy 163.54544 62.31588) (xy 163.54544 62.32961) (xy 163.54544 62.34334)
			(xy 163.54544 62.35708) (xy 163.54544 62.37081) (xy 163.54544 62.38454) (xy 163.54544 62.39827) (xy 163.54544 62.412)
			(xy 163.54544 62.42574) (xy 163.54544 62.43947) (xy 163.54544 62.4532) (xy 163.54544 62.46693) (xy 163.54544 62.48066)
			(xy 163.54544 62.49439) (xy 163.54544 62.50813) (xy 163.54544 62.52186) (xy 163.54544 62.53559) (xy 163.54544 62.54932)
			(xy 163.54544 62.56305) (xy 162.21346 62.56305) (xy 162.21346 62.57678) (xy 162.21346 62.59052) (xy 162.21346 62.60425)
			(xy 162.21346 62.61798) (xy 162.21346 62.63171) (xy 162.21346 62.64544) (xy 162.21346 62.65917) (xy 162.21346 62.67291)
			(xy 162.21346 62.68664) (xy 162.21346 62.70037) (xy 162.21346 62.7141) (xy 162.21346 62.72783) (xy 162.21346 62.74156)
			(xy 162.21346 62.7553) (xy 162.21346 62.76903) (xy 162.21346 62.78276) (xy 162.21346 62.79649) (xy 162.21346 62.81022)
			(xy 162.21346 62.82395) (xy 162.21346 62.83769) (xy 162.21346 62.85142) (xy 162.21346 62.86515) (xy 162.21346 62.87888)
			(xy 162.21346 62.89261) (xy 162.21346 62.90635) (xy 162.21346 62.92008) (xy 162.21346 62.93381) (xy 162.21346 62.94754)
			(xy 162.21346 62.96127) (xy 162.21346 62.97501) (xy 162.21346 62.98874) (xy 162.21346 63.00247) (xy 162.21346 63.0162)
			(xy 162.21346 63.02993) (xy 162.21346 63.04366) (xy 162.21346 63.0574) (xy 162.21346 63.07113) (xy 162.21346 63.08486)
			(xy 162.21346 63.09859) (xy 162.21346 63.11232) (xy 162.21346 63.12605) (xy 162.21346 63.13979) (xy 162.21346 63.15352)
			(xy 162.21346 63.16725) (xy 162.21346 63.18098) (xy 162.21346 63.19471) (xy 162.21346 63.20844) (xy 162.21346 63.22218)
			(xy 162.21346 63.23591) (xy 162.21346 63.24964) (xy 162.21346 63.26337) (xy 162.21346 63.2771) (xy 162.21346 63.29083)
			(xy 162.21346 63.30457) (xy 162.21346 63.3183) (xy 162.21346 63.33203) (xy 162.21346 63.34576) (xy 162.21346 63.35949)
			(xy 162.21346 63.37322) (xy 162.21346 63.38696) (xy 162.21346 63.40069) (xy 162.21346 63.41442) (xy 162.21346 63.42815)
			(xy 162.21346 63.44188) (xy 162.21346 63.45562) (xy 162.21346 63.46935) (xy 162.21346 63.48308) (xy 162.21346 63.49681)
			(xy 162.21346 63.51054) (xy 162.21346 63.52428) (xy 162.21346 63.53801) (xy 162.21346 63.55174) (xy 162.21346 63.56547)
			(xy 162.21346 63.5792) (xy 162.21346 63.59293) (xy 162.21346 63.60667) (xy 162.21346 63.6204) (xy 162.21346 63.63413)
			(xy 162.21346 63.64786) (xy 162.21346 63.66159) (xy 162.21346 63.67532) (xy 162.21346 63.68906) (xy 162.21346 63.70279)
			(xy 162.21346 63.71652) (xy 162.21346 63.73025) (xy 162.21346 63.74398) (xy 162.21346 63.75771) (xy 162.21346 63.77145)
			(xy 162.21346 63.78518) (xy 162.21346 63.79891) (xy 162.21346 63.81264) (xy 162.21346 63.82637) (xy 162.21346 63.8401)
			(xy 162.21346 63.85384) (xy 162.21346 63.86757) (xy 162.21346 63.8813) (xy 162.21346 63.89503) (xy 162.21346 63.90876)
			(xy 162.21346 63.92249) (xy 162.21346 63.93623) (xy 162.21346 63.94996) (xy 162.21346 63.96369) (xy 162.21346 63.97742)
			(xy 162.21346 63.99115) (xy 162.21346 64.00489) (xy 162.21346 64.01862) (xy 162.21346 64.03235) (xy 162.21346 64.04608)
			(xy 162.21346 64.05981) (xy 162.21346 64.07355) (xy 163.53171 64.07355) (xy 163.53171 64.08728) (xy 163.54544 64.08728)
			(xy 163.54544 64.10101) (xy 163.54544 64.11474) (xy 163.54544 64.12847) (xy 163.54544 64.1422) (xy 163.54544 64.15594)
			(xy 163.54544 64.16967) (xy 163.54544 64.1834) (xy 163.54544 64.19713) (xy 163.54544 64.21086) (xy 163.54544 64.22459)
			(xy 163.54544 64.23833) (xy 163.54544 64.25206) (xy 163.54544 64.26579) (xy 163.54544 64.27952) (xy 163.54544 64.29325)
			(xy 163.54544 64.30698) (xy 163.54544 64.32071) (xy 163.54544 64.33445) (xy 163.54544 64.34818) (xy 163.54544 64.36191)
			(xy 163.54544 64.37564) (xy 163.54544 64.38937) (xy 163.54544 64.4031) (xy 163.54544 64.41684) (xy 162.21346 64.41684)
			(xy 162.21346 64.43057) (xy 162.21346 64.4443) (xy 162.21346 64.45803) (xy 162.21346 64.47176) (xy 162.21346 64.4855)
			(xy 162.21346 64.49923) (xy 162.21346 64.51296) (xy 162.21346 64.52669) (xy 162.21346 64.54042) (xy 162.21346 64.55416)
			(xy 162.21346 64.56789) (xy 162.21346 64.58162) (xy 162.21346 64.59535) (xy 162.21346 64.60908) (xy 162.21346 64.62281)
			(xy 162.21346 64.63655) (xy 162.21346 64.65028) (xy 162.21346 64.66401) (xy 162.21346 64.67774) (xy 162.21346 64.69147)
			(xy 162.21346 64.7052) (xy 162.21346 64.71894) (xy 162.21346 64.73267) (xy 162.21346 64.7464) (xy 162.21346 64.76013)
			(xy 162.21346 64.77386) (xy 162.21346 64.78759) (xy 162.21346 64.80133) (xy 162.21346 64.81506) (xy 162.21346 64.82879)
			(xy 162.21346 64.84252) (xy 162.21346 64.85625) (xy 162.21346 64.86998) (xy 162.21346 64.88372) (xy 162.21346 64.89745)
			(xy 162.21346 64.91118) (xy 162.21346 64.92491) (xy 162.21346 64.93864) (xy 162.21346 64.95238) (xy 162.21346 64.96611)
			(xy 162.21346 64.97984) (xy 162.21346 64.99357) (xy 162.21346 65.0073) (xy 162.21346 65.02104) (xy 162.21346 65.03477)
			(xy 162.21346 65.0485) (xy 162.21346 65.06223) (xy 162.21346 65.07596) (xy 162.21346 65.08969) (xy 162.21346 65.10343)
			(xy 162.21346 65.11716) (xy 162.21346 65.13089) (xy 162.21346 65.14462) (xy 162.21346 65.15835) (xy 162.21346 65.17208)
			(xy 162.21346 65.18582) (xy 162.21346 65.19955) (xy 162.21346 65.21328) (xy 162.21346 65.22701) (xy 162.21346 65.24074)
			(xy 162.21346 65.25447) (xy 162.21346 65.26821) (xy 162.21346 65.28194) (xy 162.21346 65.29567) (xy 162.21346 65.3094)
			(xy 162.21346 65.32313) (xy 162.21346 65.33686) (xy 162.21346 65.3506) (xy 162.21346 65.36433) (xy 162.21346 65.37806)
			(xy 162.21346 65.39179) (xy 162.21346 65.40552) (xy 162.21346 65.41925) (xy 162.21346 65.43299) (xy 162.21346 65.44672)
			(xy 162.21346 65.46045) (xy 162.21346 65.47418) (xy 162.21346 65.48791) (xy 162.21346 65.50165) (xy 162.21346 65.51538)
			(xy 162.21346 65.52911) (xy 162.21346 65.54284) (xy 162.21346 65.55657) (xy 162.21346 65.57031) (xy 162.21346 65.58404)
			(xy 162.21346 65.59777) (xy 162.21346 65.6115) (xy 162.21346 65.62523) (xy 162.21346 65.63896) (xy 162.21346 65.6527)
			(xy 162.21346 65.66643) (xy 162.21346 65.68016) (xy 162.21346 65.69389) (xy 162.21346 65.70762) (xy 162.21346 65.72135)
			(xy 162.21346 65.73509) (xy 162.21346 65.74882) (xy 162.21346 65.76255) (xy 162.21346 65.77628) (xy 162.21346 65.79001)
			(xy 162.21346 65.80374) (xy 162.21346 65.81748) (xy 162.21346 65.83121) (xy 162.21346 65.84494) (xy 162.21346 65.85867)
			(xy 162.21346 65.8724) (xy 162.21346 65.88613) (xy 162.21346 65.89987) (xy 162.21346 65.9136) (xy 162.21346 65.92733)
			(xy 162.21346 65.94106) (xy 163.54544 65.94106) (xy 163.54544 65.95479) (xy 163.54544 65.96852) (xy 163.54544 65.98226)
			(xy 163.54544 65.99599) (xy 163.54544 66.00972) (xy 163.54544 66.02345) (xy 163.54544 66.03718) (xy 163.54544 66.05092)
			(xy 163.54544 66.06465) (xy 163.54544 66.07838) (xy 163.54544 66.09211) (xy 163.54544 66.10584) (xy 163.54544 66.11958)
			(xy 163.54544 66.13331) (xy 163.54544 66.14704) (xy 163.54544 66.16077) (xy 163.54544 66.1745) (xy 163.54544 66.18823)
			(xy 163.54544 66.20197) (xy 163.54544 66.2157) (xy 163.54544 66.22943) (xy 163.54544 66.24316) (xy 163.54544 66.25689)
			(xy 163.54544 66.27062) (xy 163.53171 66.27062) (xy 163.53171 66.28436) (xy 162.21346 66.28436) (xy 162.21346 66.29809)
			(xy 162.21346 66.31182) (xy 162.21346 66.32555) (xy 162.21346 66.33928) (xy 162.21346 66.35301) (xy 162.21346 66.36675)
			(xy 162.21346 66.38048) (xy 162.21346 66.39421) (xy 162.21346 66.40794) (xy 162.21346 66.42167) (xy 162.21346 66.4354)
			(xy 162.21346 66.44914) (xy 162.21346 66.46287) (xy 162.21346 66.4766) (xy 162.21346 66.49033) (xy 162.21346 66.50406)
			(xy 162.21346 66.51779) (xy 162.21346 66.53153) (xy 162.21346 66.54526) (xy 162.21346 66.55899) (xy 162.21346 66.57272)
			(xy 162.21346 66.58645) (xy 162.21346 66.60019) (xy 162.21346 66.61392) (xy 162.21346 66.62765) (xy 162.21346 66.64138)
			(xy 162.21346 66.65511) (xy 162.21346 66.66885) (xy 162.21346 66.68258) (xy 162.21346 66.69631) (xy 162.21346 66.71004)
			(xy 162.21346 66.72377) (xy 162.21346 66.7375) (xy 162.21346 66.75124) (xy 162.21346 66.76497) (xy 162.21346 66.7787)
			(xy 162.21346 66.79243) (xy 162.21346 66.80616) (xy 162.21346 66.81989) (xy 162.21346 66.83363) (xy 162.21346 66.84736)
			(xy 162.21346 66.86109) (xy 162.21346 66.87482) (xy 162.21346 66.88855) (xy 162.21346 66.90228) (xy 162.21346 66.91602)
			(xy 162.21346 66.92975) (xy 162.21346 66.94348) (xy 162.21346 66.95721) (xy 162.21346 66.97094) (xy 162.21346 66.98467)
			(xy 162.21346 66.99841) (xy 162.21346 67.01214) (xy 162.21346 67.02587) (xy 162.21346 67.0396) (xy 162.21346 67.05333)
			(xy 162.21346 67.06707) (xy 162.21346 67.0808) (xy 162.21346 67.09453) (xy 162.21346 67.10826) (xy 162.21346 67.12199)
			(xy 162.21346 67.13573) (xy 162.21346 67.14946) (xy 162.21346 67.16319) (xy 162.21346 67.17692) (xy 162.21346 67.19065)
			(xy 162.21346 67.20438) (xy 162.21346 67.21812) (xy 162.21346 67.23185) (xy 162.21346 67.24558) (xy 162.21346 67.25931)
			(xy 162.21346 67.27304) (xy 162.21346 67.28677) (xy 162.21346 67.30051) (xy 162.21346 67.31424) (xy 162.21346 67.32797)
			(xy 162.21346 67.3417) (xy 162.21346 67.35543) (xy 162.21346 67.36916) (xy 162.21346 67.3829) (xy 162.21346 67.39663)
			(xy 162.21346 67.41036) (xy 162.21346 67.42409) (xy 162.21346 67.43782) (xy 162.21346 67.45155) (xy 162.21346 67.46529)
			(xy 162.21346 67.47902) (xy 162.21346 67.49275) (xy 162.21346 67.50648) (xy 162.21346 67.52021) (xy 162.21346 67.53394)
			(xy 162.21346 67.54768) (xy 162.21346 67.56141) (xy 162.21346 67.57514) (xy 162.21346 67.58887) (xy 162.21346 67.6026)
			(xy 162.21346 67.61634) (xy 162.21346 67.63007) (xy 162.21346 67.6438) (xy 162.21346 67.65753) (xy 162.21346 67.67126)
			(xy 162.21346 67.685) (xy 162.21346 67.69873) (xy 162.21346 67.71246) (xy 162.21346 67.72619) (xy 162.21346 67.73992)
			(xy 162.21346 67.75365) (xy 162.21346 67.76739) (xy 162.21346 67.78112) (xy 162.21346 67.79485) (xy 163.54544 67.79485)
			(xy 163.54544 67.80858) (xy 163.54544 67.82231) (xy 163.54544 67.83604) (xy 163.54544 67.84978) (xy 163.54544 67.86351)
			(xy 163.54544 67.87724) (xy 163.54544 67.89097) (xy 163.54544 67.9047) (xy 163.54544 67.91843) (xy 163.54544 67.93217)
			(xy 163.54544 67.9459) (xy 163.54544 67.95963) (xy 163.54544 67.97336) (xy 163.54544 67.98709) (xy 163.54544 68.00082)
			(xy 163.54544 68.01456) (xy 163.54544 68.02829) (xy 163.54544 68.04202) (xy 163.54544 68.05575) (xy 163.54544 68.06948)
			(xy 163.54544 68.08321) (xy 163.54544 68.09695) (xy 163.54544 68.11068) (xy 163.54544 68.12441) (xy 163.54544 68.13814)
			(xy 162.21346 68.13814) (xy 162.21346 68.15187) (xy 162.21346 68.16561) (xy 162.21346 68.17934) (xy 162.21346 68.19307)
			(xy 162.21346 68.2068) (xy 162.21346 68.22053) (xy 162.21346 68.23427) (xy 162.21346 68.248) (xy 162.21346 68.26173)
			(xy 162.21346 68.27546) (xy 162.21346 68.28919) (xy 162.21346 68.30292) (xy 162.21346 68.31666) (xy 162.21346 68.33039)
			(xy 162.21346 68.34412) (xy 162.21346 68.35785) (xy 162.21346 68.37158) (xy 162.21346 68.38531) (xy 162.21346 68.39905)
			(xy 162.21346 68.41278) (xy 162.21346 68.42651) (xy 162.21346 68.44024) (xy 162.21346 68.45397) (xy 162.21346 68.4677)
			(xy 162.21346 68.48144) (xy 162.21346 68.49517) (xy 162.21346 68.5089) (xy 162.21346 68.52263) (xy 162.21346 68.53636)
			(xy 162.21346 68.55009) (xy 162.21346 68.56383) (xy 162.21346 68.57756) (xy 162.21346 68.59129) (xy 162.21346 68.60502)
			(xy 162.21346 68.61875) (xy 162.21346 68.63248) (xy 162.21346 68.64622) (xy 162.21346 68.65995) (xy 162.21346 68.67368)
			(xy 162.21346 68.68741) (xy 162.21346 68.70114) (xy 162.21346 68.71488) (xy 162.21346 68.72861) (xy 162.21346 68.74234)
			(xy 162.21346 68.75607) (xy 162.21346 68.7698) (xy 162.21346 68.78354) (xy 162.21346 68.79727) (xy 162.21346 68.811)
			(xy 162.21346 68.82473) (xy 162.21346 68.83846) (xy 162.21346 68.85219) (xy 162.21346 68.86593) (xy 162.21346 68.87966)
			(xy 162.21346 68.89339) (xy 162.21346 68.90712) (xy 162.21346 68.92085) (xy 162.21346 68.93458) (xy 162.21346 68.94832)
			(xy 162.21346 68.96205) (xy 162.21346 68.97578) (xy 162.21346 68.98951) (xy 162.21346 69.00324) (xy 162.21346 69.01697)
			(xy 162.21346 69.03071) (xy 162.21346 69.04444) (xy 162.21346 69.05817) (xy 162.21346 69.0719) (xy 162.21346 69.08563)
			(xy 162.21346 69.09936) (xy 162.21346 69.1131) (xy 162.21346 69.12683) (xy 162.21346 69.14056) (xy 162.21346 69.15429)
			(xy 162.21346 69.16802) (xy 162.21346 69.18175) (xy 162.21346 69.19549) (xy 162.21346 69.20922) (xy 162.21346 69.22295)
			(xy 162.21346 69.23668) (xy 162.21346 69.25041) (xy 162.21346 69.26415) (xy 162.21346 69.27788) (xy 162.21346 69.29161)
			(xy 162.21346 69.30534) (xy 162.21346 69.31907) (xy 162.21346 69.33281) (xy 162.21346 69.34654) (xy 162.21346 69.36027)
			(xy 162.21346 69.374) (xy 162.21346 69.38773) (xy 162.21346 69.40146) (xy 162.21346 69.4152) (xy 162.21346 69.42893)
			(xy 162.21346 69.44266) (xy 162.21346 69.45639) (xy 162.21346 69.47012) (xy 162.21346 69.48385) (xy 162.21346 69.49759)
			(xy 162.21346 69.51132) (xy 162.21346 69.52505) (xy 162.21346 69.53878) (xy 162.21346 69.55251) (xy 162.21346 69.56624)
			(xy 162.21346 69.57998) (xy 162.21346 69.59371) (xy 162.21346 69.60744) (xy 162.21346 69.62117) (xy 162.21346 69.6349)
			(xy 162.21346 69.64863) (xy 163.54544 69.64863) (xy 163.54544 69.66237) (xy 163.54544 69.6761) (xy 163.54544 69.68983)
			(xy 163.54544 69.70356) (xy 163.54544 69.71729) (xy 163.54544 69.73103) (xy 163.54544 69.74476) (xy 163.54544 69.75849)
			(xy 163.54544 69.77222) (xy 163.54544 69.78595) (xy 163.54544 69.79969) (xy 163.54544 69.81342) (xy 163.54544 69.82715)
			(xy 163.54544 69.84088) (xy 163.54544 69.85461) (xy 163.54544 69.86834) (xy 163.54544 69.88208) (xy 163.54544 69.89581)
			(xy 163.54544 69.90954) (xy 163.54544 69.92327) (xy 163.54544 69.937) (xy 163.54544 69.95073) (xy 163.54544 69.96447)
			(xy 163.54544 69.9782) (xy 163.54544 69.99193) (xy 163.54544 70.00566) (xy 163.54544 70.01939) (xy 163.54544 70.03312)
			(xy 163.54544 70.04686) (xy 163.54544 70.06059) (xy 163.54544 70.07432) (xy 163.54544 70.08805) (xy 163.54544 70.10178)
			(xy 163.54544 70.11551) (xy 163.54544 70.12925) (xy 163.54544 70.14298) (xy 163.54544 70.15671) (xy 163.54544 70.17044)
			(xy 163.54544 70.18417) (xy 163.54544 70.1979) (xy 163.54544 70.21164) (xy 163.54544 70.22537) (xy 163.54544 70.2391)
			(xy 163.54544 70.25283) (xy 163.54544 70.26656) (xy 163.54544 70.2803) (xy 163.54544 70.29403) (xy 163.54544 70.30776)
			(xy 163.54544 70.32149) (xy 163.54544 70.33522) (xy 163.54544 70.34896) (xy 163.54544 70.36269) (xy 163.54544 70.37642)
			(xy 163.54544 70.39015) (xy 163.54544 70.40388) (xy 163.54544 70.41761) (xy 163.54544 70.43135) (xy 163.54544 70.44508)
			(xy 163.54544 70.45881) (xy 163.54544 70.47254) (xy 163.54544 70.48627) (xy 163.54544 70.5) (xy 163.54544 70.51374)
			(xy 163.54544 70.52747) (xy 163.54544 70.5412) (xy 163.54544 70.55493) (xy 163.54544 70.56866) (xy 163.54544 70.58239)
			(xy 163.54544 70.59613) (xy 163.54544 70.60986) (xy 163.54544 70.62359) (xy 163.54544 70.63732) (xy 163.54544 70.65105)
			(xy 163.54544 70.66478) (xy 163.54544 70.67852) (xy 163.54544 70.69225) (xy 163.54544 70.70598) (xy 163.54544 70.71971)
			(xy 163.54544 70.73344) (xy 163.54544 70.74717) (xy 163.54544 70.76091) (xy 163.54544 70.77464) (xy 163.54544 70.78837)
			(xy 163.54544 70.8021) (xy 163.54544 70.81583) (xy 163.54544 70.82957) (xy 163.54544 70.8433) (xy 163.54544 70.85703)
			(xy 163.54544 70.87076) (xy 163.54544 70.88449) (xy 161.49941 70.88449) (xy 161.49941 70.87076) (xy 161.49941 70.85703)
			(xy 161.49941 70.8433) (xy 161.49941 70.82957) (xy 161.49941 70.81583) (xy 161.49941 70.8021) (xy 161.49941 70.78837)
			(xy 161.49941 70.77464) (xy 161.49941 70.76091) (xy 161.49941 70.74717) (xy 161.49941 70.73344) (xy 161.49941 70.71971)
			(xy 161.49941 70.70598) (xy 161.49941 70.69225) (xy 161.49941 70.67852) (xy 161.49941 70.66478) (xy 161.49941 70.65105)
			(xy 161.49941 70.63732) (xy 161.49941 70.62359) (xy 161.49941 70.60986) (xy 161.49941 70.59613) (xy 161.49941 70.58239)
			(xy 161.49941 70.56866) (xy 161.49941 70.55493) (xy 161.49941 70.5412) (xy 161.49941 70.52747) (xy 161.49941 70.51374)
			(xy 161.49941 70.5) (xy 161.49941 70.48627) (xy 161.49941 70.47254) (xy 161.49941 70.45881) (xy 161.49941 70.44508)
			(xy 161.49941 70.43135) (xy 161.49941 70.41761) (xy 161.49941 70.40388) (xy 161.49941 70.39015) (xy 161.49941 70.37642)
			(xy 161.49941 70.36269) (xy 161.49941 70.34896) (xy 161.49941 70.33522) (xy 161.49941 70.32149) (xy 161.49941 70.30776)
			(xy 161.49941 70.29403) (xy 161.49941 70.2803) (xy 161.49941 70.26656) (xy 161.49941 70.25283) (xy 161.49941 70.2391)
			(xy 161.49941 70.22537) (xy 161.49941 70.21164) (xy 161.49941 70.1979) (xy 161.49941 70.18417) (xy 161.49941 70.17044)
			(xy 161.49941 70.15671) (xy 161.49941 70.14298) (xy 161.49941 70.12925) (xy 161.49941 70.11551) (xy 161.49941 70.10178)
			(xy 161.49941 70.08805) (xy 161.49941 70.07432) (xy 161.49941 70.06059) (xy 161.49941 70.04686) (xy 161.49941 70.03312)
			(xy 161.49941 70.01939) (xy 161.49941 70.00566) (xy 161.49941 69.99193) (xy 161.49941 69.9782) (xy 161.49941 69.96447)
			(xy 161.49941 69.95073) (xy 161.49941 69.937) (xy 161.49941 69.92327) (xy 161.49941 69.90954) (xy 161.49941 69.89581)
			(xy 161.49941 69.88208) (xy 161.49941 69.86834) (xy 161.49941 69.85461) (xy 161.49941 69.84088) (xy 161.49941 69.82715)
			(xy 161.49941 69.81342) (xy 161.49941 69.79969) (xy 161.49941 69.78595) (xy 161.49941 69.77222) (xy 161.49941 69.75849)
			(xy 161.49941 69.74476) (xy 161.49941 69.73103) (xy 161.49941 69.71729) (xy 161.49941 69.70356) (xy 161.49941 69.68983)
			(xy 161.48568 69.68983) (xy 161.48568 69.6761) (xy 161.48568 69.66237) (xy 161.47195 69.66237) (xy 161.47195 69.64863)
			(xy 161.45822 69.64863) (xy 161.45822 69.6349) (xy 161.44448 69.6349) (xy 161.44448 69.62117) (xy 161.41702 69.62117)
			(xy 161.41702 69.60744) (xy 159.2886 69.60744) (xy 159.2886 69.62117) (xy 159.26113 69.62117) (xy 159.26113 69.6349)
			(xy 159.23367 69.6349) (xy 159.23367 69.64863) (xy 159.21994 69.64863) (xy 159.21994 69.66237) (xy 159.21994 69.6761)
			(xy 159.20621 69.6761) (xy 159.20621 69.68983) (xy 159.20621 69.70356) (xy 159.20621 69.71729) (xy 159.20621 69.73103)
			(xy 159.20621 69.74476) (xy 159.20621 69.75849) (xy 159.19248 69.75849) (xy 159.19248 69.77222) (xy 159.20621 69.77222)
			(xy 159.20621 69.78595) (xy 159.19248 69.78595) (xy 159.19248 69.79969) (xy 159.19248 69.81342) (xy 159.20621 69.81342)
			(xy 159.20621 69.82715) (xy 159.20621 69.84088) (xy 159.20621 69.85461) (xy 159.20621 69.86834) (xy 159.20621 69.88208)
			(xy 159.20621 69.89581) (xy 159.20621 69.90954) (xy 159.20621 69.92327) (xy 159.20621 69.937) (xy 159.20621 69.95073)
			(xy 159.20621 69.96447) (xy 159.20621 69.9782) (xy 159.20621 69.99193) (xy 159.20621 70.00566) (xy 159.20621 70.01939)
			(xy 159.20621 70.03312) (xy 159.20621 70.04686) (xy 159.20621 70.06059) (xy 159.20621 70.07432) (xy 159.20621 70.08805)
			(xy 159.20621 70.10178) (xy 159.20621 70.11551) (xy 159.20621 70.12925) (xy 159.20621 70.14298) (xy 159.20621 70.15671)
			(xy 159.20621 70.17044) (xy 159.20621 70.18417) (xy 159.20621 70.1979) (xy 159.20621 70.21164) (xy 159.20621 70.22537)
			(xy 159.20621 70.2391) (xy 159.20621 70.25283) (xy 159.20621 70.26656) (xy 159.20621 70.2803) (xy 159.20621 70.29403)
			(xy 159.20621 70.30776) (xy 159.20621 70.32149) (xy 159.20621 70.33522) (xy 159.20621 70.34896) (xy 159.20621 70.36269)
			(xy 159.20621 70.37642) (xy 159.20621 70.39015) (xy 159.20621 70.40388) (xy 159.20621 70.41761) (xy 159.20621 70.43135)
			(xy 159.20621 70.44508) (xy 159.20621 70.45881) (xy 159.20621 70.47254) (xy 159.20621 70.48627) (xy 159.20621 70.5)
			(xy 159.20621 70.51374) (xy 159.19248 70.51374) (xy 159.19248 70.52747) (xy 159.19248 70.5412) (xy 159.19248 70.55493)
			(xy 159.17874 70.55493) (xy 159.17874 70.56866) (xy 159.16501 70.56866) (xy 159.16501 70.58239) (xy 159.15128 70.58239)
			(xy 159.15128 70.59613) (xy 159.13755 70.59613) (xy 159.13755 70.60986) (xy 159.09635 70.60986) (xy 159.09635 70.62359)
			(xy 158.27245 70.62359) (xy 158.27245 70.60986) (xy 158.23125 70.60986) (xy 158.23125 70.59613) (xy 158.21752 70.59613)
			(xy 158.21752 70.58239) (xy 158.20379 70.58239) (xy 158.20379 70.56866) (xy 158.19006 70.56866) (xy 158.19006 70.55493)
			(xy 158.17633 70.55493) (xy 158.17633 70.5412) (xy 158.17633 70.52747) (xy 158.17633 70.51374) (xy 158.17633 70.5)
			(xy 158.16259 70.5) (xy 158.16259 70.48627) (xy 158.16259 70.47254) (xy 158.16259 70.45881) (xy 158.16259 70.44508)
			(xy 158.16259 70.43135) (xy 158.16259 70.41761) (xy 158.16259 70.40388) (xy 158.16259 70.39015) (xy 158.16259 70.37642)
			(xy 158.16259 70.36269) (xy 158.16259 70.34896) (xy 158.16259 70.33522) (xy 158.16259 70.32149) (xy 158.16259 70.30776)
			(xy 158.16259 70.29403) (xy 158.16259 70.2803) (xy 158.16259 70.26656) (xy 158.16259 70.25283) (xy 158.16259 70.2391)
			(xy 158.16259 70.22537) (xy 158.16259 70.21164) (xy 158.16259 70.1979) (xy 158.16259 70.18417) (xy 158.16259 70.17044)
			(xy 158.16259 70.15671) (xy 158.16259 70.14298) (xy 158.16259 70.12925) (xy 158.16259 70.11551) (xy 158.16259 70.10178)
			(xy 158.16259 70.08805) (xy 158.16259 70.07432) (xy 158.16259 70.06059) (xy 158.16259 70.04686) (xy 158.16259 70.03312)
			(xy 158.16259 70.01939) (xy 158.16259 70.00566) (xy 158.16259 69.99193) (xy 158.16259 69.9782) (xy 158.16259 69.96447)
			(xy 158.16259 69.95073) (xy 158.16259 69.937) (xy 158.16259 69.92327) (xy 158.16259 69.90954) (xy 158.17633 69.90954)
			(xy 158.17633 69.89581) (xy 158.16259 69.89581) (xy 158.16259 69.88208) (xy 158.16259 69.86834) (xy 158.17633 69.86834)
			(xy 158.17633 69.85461) (xy 158.16259 69.85461) (xy 158.16259 69.84088) (xy 158.16259 69.82715) (xy 158.16259 69.81342)
			(xy 158.16259 69.79969) (xy 158.16259 69.78595) (xy 158.16259 69.77222) (xy 158.14886 69.77222) (xy 158.14886 69.75849)
			(xy 158.14886 69.74476) (xy 158.13513 69.74476) (xy 158.13513 69.73103) (xy 158.13513 69.71729) (xy 158.1214 69.71729)
			(xy 158.1214 69.70356) (xy 158.10767 69.70356) (xy 158.10767 69.68983) (xy 158.09394 69.68983) (xy 158.09394 69.6761)
			(xy 158.0802 69.6761) (xy 158.0802 69.66237) (xy 158.06647 69.66237) (xy 158.06647 69.64863) (xy 158.03901 69.64863)
			(xy 158.03901 69.6349) (xy 158.01155 69.6349) (xy 158.01155 69.62117) (xy 157.97035 69.62117) (xy 157.97035 69.60744)
			(xy 157.8605 69.60744) (xy 157.8605 69.62117) (xy 157.8193 69.62117) (xy 157.8193 69.6349) (xy 157.79184 69.6349)
			(xy 157.79184 69.64863) (xy 157.76437 69.64863) (xy 157.76437 69.66237) (xy 157.75064 69.66237) (xy 157.75064 69.6761)
			(xy 157.73691 69.6761) (xy 157.73691 69.68983) (xy 157.72318 69.68983) (xy 157.72318 69.70356) (xy 157.70945 69.70356)
			(xy 157.70945 69.71729) (xy 157.70945 69.73103) (xy 157.69571 69.73103) (xy 157.69571 69.74476) (xy 157.69571 69.75849)
			(xy 157.68198 69.75849) (xy 157.68198 69.77222) (xy 157.68198 69.78595) (xy 157.66825 69.78595) (xy 157.66825 69.79969)
			(xy 157.66825 69.81342) (xy 157.66825 69.82715) (xy 157.66825 69.84088) (xy 157.66825 69.85461) (xy 157.66825 69.86834)
			(xy 157.66825 69.88208) (xy 157.66825 69.89581) (xy 157.66825 69.90954) (xy 157.65452 69.90954) (xy 157.65452 69.92327)
			(xy 157.66825 69.92327) (xy 157.66825 69.937) (xy 157.66825 69.95073) (xy 157.66825 69.96447) (xy 157.66825 69.9782)
			(xy 157.66825 69.99193) (xy 157.66825 70.00566) (xy 157.66825 70.01939) (xy 157.66825 70.03312) (xy 157.66825 70.04686)
			(xy 157.66825 70.06059) (xy 157.66825 70.07432) (xy 157.66825 70.08805) (xy 157.66825 70.10178) (xy 157.66825 70.11551)
			(xy 157.66825 70.12925) (xy 157.66825 70.14298) (xy 157.66825 70.15671) (xy 157.66825 70.17044) (xy 157.66825 70.18417)
			(xy 157.66825 70.1979) (xy 157.66825 70.21164) (xy 157.66825 70.22537) (xy 157.66825 70.2391) (xy 157.66825 70.25283)
			(xy 157.66825 70.26656) (xy 157.66825 70.2803) (xy 157.66825 70.29403) (xy 157.66825 70.30776) (xy 157.66825 70.32149)
			(xy 157.66825 70.33522) (xy 157.66825 70.34896) (xy 157.66825 70.36269) (xy 157.66825 70.37642) (xy 157.66825 70.39015)
			(xy 157.66825 70.40388) (xy 157.66825 70.41761) (xy 157.66825 70.43135) (xy 157.66825 70.44508) (xy 157.66825 70.45881)
			(xy 157.66825 70.47254) (xy 157.66825 70.48627) (xy 157.66825 70.5) (xy 157.66825 70.51374) (xy 157.66825 70.52747)
			(xy 157.66825 70.5412) (xy 157.66825 70.55493) (xy 157.66825 70.56866) (xy 157.66825 70.58239) (xy 157.66825 70.59613)
			(xy 157.66825 70.60986) (xy 157.66825 70.62359) (xy 157.66825 70.63732) (xy 157.66825 70.65105) (xy 157.66825 70.66478)
			(xy 157.66825 70.67852) (xy 157.66825 70.69225) (xy 157.66825 70.70598) (xy 157.66825 70.71971) (xy 157.66825 70.73344)
			(xy 157.66825 70.74717) (xy 157.66825 70.76091) (xy 157.66825 70.77464) (xy 157.66825 70.78837) (xy 157.66825 70.8021)
			(xy 157.66825 70.81583) (xy 157.66825 70.82957) (xy 157.66825 70.8433) (xy 157.66825 70.85703) (xy 157.66825 70.87076)
			(xy 157.66825 70.88449) (xy 157.66825 70.89823) (xy 157.66825 70.91196) (xy 157.66825 70.92569) (xy 157.66825 70.93942)
			(xy 157.66825 70.95315) (xy 157.66825 70.96688) (xy 157.66825 70.98062) (xy 157.66825 70.99435) (xy 157.66825 71.00808)
			(xy 157.66825 71.02181) (xy 157.66825 71.03554) (xy 157.65452 71.03554) (xy 157.65452 71.04927) (xy 157.65452 71.06301)
			(xy 157.65452 71.07674) (xy 157.64079 71.07674) (xy 157.64079 71.09047) (xy 157.64079 71.1042) (xy 157.62706 71.1042)
			(xy 157.62706 71.11793) (xy 157.59959 71.11793) (xy 157.59959 71.13166) (xy 157.57213 71.13166) (xy 157.57213 71.1454)
			(xy 156.22642 71.1454) (xy 156.22642 71.13166) (xy 156.18522 71.13166) (xy 156.18522 71.11793) (xy 156.17149 71.11793)
			(xy 156.17149 71.1042) (xy 156.15776 71.1042) (xy 156.15776 71.09047) (xy 156.14403 71.09047) (xy 156.14403 71.07674)
			(xy 156.13029 71.07674) (xy 156.13029 71.06301) (xy 156.13029 71.04927) (xy 156.13029 71.03554) (xy 156.13029 71.02181)
			(xy 156.13029 71.00808) (xy 156.13029 70.99435) (xy 156.13029 70.98062) (xy 156.13029 70.96688) (xy 156.13029 70.95315)
			(xy 156.13029 70.93942) (xy 156.13029 70.92569) (xy 156.13029 70.91196) (xy 156.13029 70.89823) (xy 156.13029 70.88449)
			(xy 156.13029 70.87076) (xy 156.13029 70.85703) (xy 156.13029 70.8433) (xy 156.13029 70.82957) (xy 156.13029 70.81583)
			(xy 156.13029 70.8021) (xy 156.13029 70.78837) (xy 156.13029 70.77464) (xy 156.13029 70.76091) (xy 156.13029 70.74717)
			(xy 156.13029 70.73344) (xy 156.13029 70.71971) (xy 156.13029 70.70598) (xy 156.13029 70.69225) (xy 156.13029 70.67852)
			(xy 156.13029 70.66478) (xy 156.13029 70.65105) (xy 156.13029 70.63732) (xy 156.13029 70.62359) (xy 156.13029 70.60986)
			(xy 156.13029 70.59613) (xy 156.13029 70.58239) (xy 156.13029 70.56866) (xy 156.13029 70.55493) (xy 156.13029 70.5412)
			(xy 156.13029 70.52747) (xy 156.13029 70.51374) (xy 156.13029 70.5) (xy 156.13029 70.48627) (xy 156.13029 70.47254)
			(xy 156.13029 70.45881) (xy 156.13029 70.44508) (xy 156.13029 70.43135) (xy 156.13029 70.41761) (xy 156.13029 70.40388)
			(xy 156.13029 70.39015) (xy 156.13029 70.37642) (xy 156.13029 70.36269) (xy 156.13029 70.34896) (xy 156.13029 70.33522)
			(xy 156.13029 70.32149) (xy 156.13029 70.30776) (xy 156.13029 70.29403) (xy 156.13029 70.2803) (xy 156.13029 70.26656)
			(xy 156.13029 70.25283) (xy 156.13029 70.2391) (xy 156.11656 70.2391) (xy 156.11656 70.22537) (xy 156.11656 70.21164)
			(xy 156.11656 70.1979) (xy 156.11656 70.18417) (xy 156.10283 70.18417) (xy 156.10283 70.17044) (xy 156.0891 70.17044)
			(xy 156.0891 70.15671) (xy 156.07537 70.15671) (xy 156.07537 70.14298) (xy 156.06164 70.14298) (xy 156.06164 70.12925)
			(xy 156.02044 70.12925) (xy 156.02044 70.11551) (xy 155.97925 70.11551) (xy 155.97925 70.12925) (xy 155.93805 70.12925)
			(xy 155.93805 70.14298) (xy 155.91059 70.14298) (xy 155.91059 70.15671) (xy 155.89686 70.15671) (xy 155.89686 70.17044)
			(xy 155.89686 70.18417) (xy 155.88312 70.18417) (xy 155.88312 70.1979) (xy 155.88312 70.21164) (xy 155.88312 70.22537)
			(xy 155.86939 70.22537) (xy 155.86939 70.2391) (xy 155.86939 70.25283) (xy 155.86939 70.26656) (xy 155.86939 70.2803)
			(xy 155.86939 70.29403) (xy 155.86939 70.30776) (xy 155.86939 70.32149) (xy 155.86939 70.33522) (xy 155.86939 70.34896)
			(xy 155.86939 70.36269) (xy 155.86939 70.37642) (xy 155.86939 70.39015) (xy 155.86939 70.40388) (xy 155.86939 70.41761)
			(xy 155.86939 70.43135) (xy 155.86939 70.44508) (xy 155.86939 70.45881) (xy 155.86939 70.47254) (xy 155.86939 70.48627)
			(xy 155.86939 70.5) (xy 155.86939 70.51374) (xy 155.86939 70.52747) (xy 155.86939 70.5412) (xy 155.86939 70.55493)
			(xy 155.86939 70.56866) (xy 155.86939 70.58239) (xy 155.86939 70.59613) (xy 155.86939 70.60986) (xy 155.86939 70.62359)
			(xy 155.86939 70.63732) (xy 155.86939 70.65105) (xy 155.86939 70.66478) (xy 155.86939 70.67852) (xy 155.86939 70.69225)
			(xy 155.86939 70.70598) (xy 155.86939 70.71971) (xy 155.86939 70.73344) (xy 155.86939 70.74717) (xy 155.86939 70.76091)
			(xy 155.86939 70.77464) (xy 155.86939 70.78837) (xy 155.86939 70.8021) (xy 155.86939 70.81583) (xy 155.86939 70.82957)
			(xy 155.86939 70.8433) (xy 155.86939 70.85703) (xy 155.86939 70.87076) (xy 155.86939 70.88449) (xy 155.86939 70.89823)
			(xy 155.86939 70.91196) (xy 155.86939 70.92569) (xy 155.86939 70.93942) (xy 155.86939 70.95315) (xy 155.86939 70.96688)
			(xy 155.86939 70.98062) (xy 155.86939 70.99435) (xy 155.86939 71.00808) (xy 155.86939 71.02181) (xy 155.86939 71.03554)
			(xy 155.86939 71.04927) (xy 155.86939 71.06301) (xy 155.85566 71.06301) (xy 155.85566 71.07674) (xy 155.85566 71.09047)
			(xy 155.84193 71.09047) (xy 155.84193 71.1042) (xy 155.8282 71.1042) (xy 155.8282 71.11793) (xy 155.81447 71.11793)
			(xy 155.81447 71.13166) (xy 155.77327 71.13166) (xy 155.77327 71.1454) (xy 153.15051 71.1454) (xy 153.15051 71.13166)
			(xy 153.12304 71.13166) (xy 153.12304 71.11793) (xy 153.09558 71.11793) (xy 153.09558 71.1042) (xy 153.08185 71.1042)
			(xy 153.08185 71.09047) (xy 153.08185 71.07674) (xy 153.06812 71.07674) (xy 153.06812 71.06301) (xy 153.06812 71.04927)
			(xy 153.05438 71.04927) (xy 153.05438 71.03554) (xy 153.05438 71.02181) (xy 153.05438 71.00808) (xy 153.05438 70.99435)
			(xy 153.05438 70.98062) (xy 153.05438 70.96688) (xy 153.05438 70.95315) (xy 153.05438 70.93942) (xy 153.05438 70.92569)
			(xy 153.05438 70.91196) (xy 153.05438 70.89823) (xy 153.05438 70.88449) (xy 153.05438 70.87076) (xy 153.05438 70.85703)
			(xy 153.05438 70.8433) (xy 153.05438 70.82957) (xy 153.05438 70.81583) (xy 153.05438 70.8021) (xy 153.05438 70.78837)
			(xy 153.05438 70.77464) (xy 153.05438 70.76091) (xy 153.05438 70.74717) (xy 153.05438 70.73344) (xy 153.05438 70.71971)
			(xy 153.05438 70.70598) (xy 153.05438 70.69225) (xy 153.05438 70.67852) (xy 153.05438 70.66478) (xy 153.05438 70.65105)
			(xy 153.05438 70.63732) (xy 153.05438 70.62359) (xy 153.05438 70.60986) (xy 153.05438 70.59613) (xy 153.05438 70.58239)
			(xy 153.05438 70.56866) (xy 153.05438 70.55493) (xy 153.05438 70.5412) (xy 153.05438 70.52747) (xy 153.05438 70.51374)
			(xy 153.05438 70.5) (xy 153.05438 70.48627) (xy 153.05438 70.47254) (xy 153.05438 70.45881) (xy 153.05438 70.44508)
			(xy 153.05438 70.43135) (xy 153.05438 70.41761) (xy 153.05438 70.40388) (xy 153.05438 70.39015) (xy 153.05438 70.37642)
			(xy 153.05438 70.36269) (xy 153.05438 70.34896) (xy 153.05438 70.33522) (xy 153.05438 70.32149) (xy 153.05438 70.30776)
			(xy 153.05438 70.29403) (xy 153.05438 70.2803) (xy 153.05438 70.26656) (xy 153.05438 70.25283) (xy 153.05438 70.2391)
			(xy 153.05438 70.22537) (xy 153.05438 70.21164) (xy 153.05438 70.1979) (xy 153.05438 70.18417) (xy 153.05438 70.17044)
			(xy 153.05438 70.15671) (xy 153.05438 70.14298) (xy 153.05438 70.12925) (xy 153.05438 70.11551) (xy 153.05438 70.10178)
			(xy 153.05438 70.08805) (xy 153.05438 70.07432) (xy 153.05438 70.06059) (xy 153.05438 70.04686) (xy 153.05438 70.03312)
			(xy 153.05438 70.01939) (xy 153.05438 70.00566) (xy 153.05438 69.99193) (xy 153.05438 69.9782) (xy 153.05438 69.96447)
			(xy 153.05438 69.95073) (xy 153.05438 69.937) (xy 153.05438 69.92327) (xy 153.05438 69.90954) (xy 153.05438 69.89581)
			(xy 153.05438 69.88208) (xy 153.05438 69.86834) (xy 153.05438 69.85461) (xy 153.05438 69.84088) (xy 153.05438 69.82715)
			(xy 153.05438 69.81342) (xy 153.05438 69.79969) (xy 153.05438 69.78595) (xy 153.05438 69.77222) (xy 153.05438 69.75849)
			(xy 153.05438 69.74476) (xy 153.05438 69.73103) (xy 153.05438 69.71729) (xy 153.05438 69.70356) (xy 153.05438 69.68983)
			(xy 153.04065 69.68983) (xy 153.04065 69.6761) (xy 153.04065 69.66237) (xy 153.02692 69.66237) (xy 153.02692 69.64863)
			(xy 153.01319 69.64863) (xy 153.01319 69.6349) (xy 152.99946 69.6349) (xy 152.99946 69.62117) (xy 152.97199 69.62117)
			(xy 152.97199 69.60744) (xy 143.08513 69.60744) (xy 143.08513 69.59371) (xy 143.03021 69.59371) (xy 143.03021 69.57998)
			(xy 142.98901 69.57998) (xy 142.98901 69.56624) (xy 142.96155 69.56624) (xy 142.96155 69.55251) (xy 142.93408 69.55251)
			(xy 142.93408 69.53878) (xy 142.90662 69.53878) (xy 142.90662 69.52505) (xy 142.87916 69.52505) (xy 142.87916 69.51132)
			(xy 142.86542 69.51132) (xy 142.86542 69.49759) (xy 142.83796 69.49759) (xy 142.83796 69.48385) (xy 142.82423 69.48385)
			(xy 142.82423 69.47012) (xy 142.8105 69.47012) (xy 142.8105 69.45639) (xy 142.78303 69.45639) (xy 142.78303 69.44266)
			(xy 142.7693 69.44266) (xy 142.7693 69.42893) (xy 142.75557 69.42893) (xy 142.75557 69.4152) (xy 142.74184 69.4152)
			(xy 142.74184 69.40146) (xy 142.72811 69.40146) (xy 142.72811 69.38773) (xy 142.71438 69.38773) (xy 142.71438 69.374)
			(xy 142.70064 69.374) (xy 142.70064 69.36027) (xy 142.68691 69.36027) (xy 142.68691 69.34654) (xy 142.67318 69.34654)
			(xy 142.67318 69.33281) (xy 142.65945 69.33281) (xy 142.65945 69.31907) (xy 142.64572 69.31907) (xy 142.64572 69.30534)
			(xy 142.64572 69.29161) (xy 142.63199 69.29161) (xy 142.63199 69.27788) (xy 142.61825 69.27788) (xy 142.61825 69.26415)
			(xy 142.60452 69.26415) (xy 142.60452 69.25041) (xy 142.60452 69.23668) (xy 142.59079 69.23668) (xy 142.59079 69.22295)
			(xy 142.57706 69.22295) (xy 142.57706 69.20922) (xy 142.57706 69.19549) (xy 142.56333 69.19549) (xy 142.56333 69.18175)
			(xy 142.5496 69.18175) (xy 142.5496 69.16802) (xy 142.5496 69.15429) (xy 142.53586 69.15429) (xy 142.53586 69.14056)
			(xy 142.53586 69.12683) (xy 142.52213 69.12683) (xy 142.52213 69.1131) (xy 142.52213 69.09936) (xy 142.5084 69.09936)
			(xy 142.5084 69.08563) (xy 142.5084 69.0719) (xy 142.5084 69.05817) (xy 142.49467 69.05817) (xy 142.49467 69.04444)
			(xy 142.49467 69.03071) (xy 142.49467 69.01697) (xy 142.48094 69.01697) (xy 142.48094 69.00324) (xy 142.48094 68.98951)
			(xy 142.48094 68.97578) (xy 142.4672 68.97578) (xy 142.4672 68.96205) (xy 142.4672 68.94832) (xy 142.4672 68.93458)
			(xy 142.45347 68.93458) (xy 142.45347 68.92085) (xy 142.45347 68.90712) (xy 142.45347 68.89339) (xy 142.45347 68.87966)
			(xy 142.45347 68.86593) (xy 142.43974 68.86593) (xy 142.43974 68.85219) (xy 142.43974 68.83846) (xy 142.43974 68.82473)
			(xy 142.43974 68.811) (xy 142.43974 68.79727) (xy 142.43974 68.78354) (xy 142.43974 68.7698) (xy 142.43974 68.75607)
			(xy 142.43974 68.74234) (xy 142.43974 68.72861) (xy 142.42601 68.72861) (xy 142.42601 68.71488) (xy 142.42601 68.70114)
			(xy 142.43974 68.70114) (xy 142.43974 68.68741) (xy 142.43974 68.67368) (xy 142.43974 68.65995) (xy 142.43974 68.64622)
			(xy 142.43974 68.63248) (xy 142.43974 68.61875) (xy 142.43974 68.60502) (xy 142.43974 68.59129) (xy 142.43974 68.57756)
			(xy 142.45347 68.57756) (xy 142.45347 68.56383) (xy 142.45347 68.55009) (xy 142.45347 68.53636) (xy 142.45347 68.52263)
			(xy 142.45347 68.5089) (xy 142.45347 68.49517) (xy 142.4672 68.49517) (xy 142.4672 68.48144) (xy 142.4672 68.4677)
			(xy 142.4672 68.45397) (xy 142.48094 68.45397) (xy 142.48094 68.44024) (xy 142.48094 68.42651) (xy 142.48094 68.41278)
			(xy 142.49467 68.41278) (xy 142.49467 68.39905) (xy 142.49467 68.38531) (xy 142.49467 68.37158) (xy 142.5084 68.37158)
			(xy 142.5084 68.35785) (xy 142.5084 68.34412) (xy 142.52213 68.34412) (xy 142.52213 68.33039) (xy 142.52213 68.31666)
			(xy 142.53586 68.31666) (xy 142.53586 68.30292) (xy 142.53586 68.28919) (xy 142.5496 68.28919) (xy 142.5496 68.27546)
			(xy 142.5496 68.26173) (xy 142.56333 68.26173) (xy 142.56333 68.248) (xy 142.57706 68.248) (xy 142.57706 68.23427)
			(xy 142.57706 68.22053) (xy 142.59079 68.22053) (xy 142.59079 68.2068) (xy 142.60452 68.2068) (xy 142.60452 68.19307)
			(xy 142.60452 68.17934) (xy 142.61825 68.17934) (xy 142.61825 68.16561) (xy 142.63199 68.16561) (xy 142.63199 68.15187)
			(xy 142.64572 68.15187) (xy 142.64572 68.13814) (xy 142.65945 68.13814) (xy 142.65945 68.12441) (xy 142.65945 68.11068)
			(xy 142.67318 68.11068) (xy 142.67318 68.09695) (xy 142.68691 68.09695) (xy 142.68691 68.08321) (xy 142.70064 68.08321)
			(xy 142.70064 68.06948) (xy 142.71438 68.06948) (xy 142.71438 68.05575) (xy 142.72811 68.05575) (xy 142.72811 68.04202)
			(xy 142.75557 68.04202) (xy 142.75557 68.02829) (xy 142.7693 68.02829) (xy 142.7693 68.01456) (xy 142.78303 68.01456)
			(xy 142.78303 68.00082) (xy 142.79677 68.00082) (xy 142.79677 67.98709) (xy 142.82423 67.98709) (xy 142.82423 67.97336)
			(xy 142.83796 67.97336) (xy 142.83796 67.95963) (xy 142.86542 67.95963) (xy 142.86542 67.9459) (xy 142.89289 67.9459)
			(xy 142.89289 67.93217) (xy 142.90662 67.93217) (xy 142.90662 67.91843) (xy 142.93408 67.91843) (xy 142.93408 67.9047)
			(xy 142.96155 67.9047) (xy 142.96155 67.89097) (xy 143.00274 67.89097) (xy 143.00274 67.87724) (xy 143.04394 67.87724)
			(xy 143.04394 67.86351) (xy 143.08513 67.86351) (xy 143.08513 67.84978) (xy 143.12633 67.84978) (xy 143.12633 67.83604)
			(xy 143.19499 67.83604) (xy 143.19499 67.82231) (xy 146.03746 67.82231) (xy 146.03746 67.80858) (xy 146.16104 67.80858)
			(xy 146.16104 67.79485) (xy 146.2297 67.79485) (xy 146.2297 67.78112) (xy 146.28463 67.78112) (xy 146.28463 67.76739)
			(xy 146.31209 67.76739) (xy 146.31209 67.75365) (xy 146.35329 67.75365) (xy 146.35329 67.73992) (xy 146.38075 67.73992)
			(xy 146.38075 67.72619) (xy 146.40822 67.72619) (xy 146.40822 67.71246) (xy 146.43568 67.71246) (xy 146.43568 67.69873)
			(xy 146.46314 67.69873) (xy 146.46314 67.685) (xy 146.49061 67.685) (xy 146.49061 67.67126) (xy 146.50434 67.67126)
			(xy 146.50434 67.65753) (xy 146.5318 67.65753) (xy 146.5318 67.6438) (xy 146.54553 67.6438) (xy 146.54553 67.63007)
			(xy 146.55926 67.63007) (xy 146.55926 67.61634) (xy 146.58673 67.61634) (xy 146.58673 67.6026) (xy 146.60046 67.6026)
			(xy 146.60046 67.58887) (xy 146.61419 67.58887) (xy 146.61419 67.57514) (xy 146.62792 67.57514) (xy 146.62792 67.56141)
			(xy 146.64165 67.56141) (xy 146.64165 67.54768) (xy 146.65539 67.54768) (xy 146.65539 67.53394) (xy 146.66912 67.53394)
			(xy 146.66912 67.52021) (xy 146.68285 67.52021) (xy 146.68285 67.50648) (xy 146.69658 67.50648) (xy 146.69658 67.49275)
			(xy 146.71031 67.49275) (xy 146.71031 67.47902) (xy 146.71031 67.46529) (xy 146.72405 67.46529) (xy 146.72405 67.45155)
			(xy 146.73778 67.45155) (xy 146.73778 67.43782) (xy 146.75151 67.43782) (xy 146.75151 67.42409) (xy 146.75151 67.41036)
			(xy 146.76524 67.41036) (xy 146.76524 67.39663) (xy 146.77897 67.39663) (xy 146.77897 67.3829) (xy 146.77897 67.36916)
			(xy 146.79271 67.36916) (xy 146.79271 67.35543) (xy 146.79271 67.3417) (xy 146.80644 67.3417) (xy 146.80644 67.32797)
			(xy 146.80644 67.31424) (xy 146.82017 67.31424) (xy 146.82017 67.30051) (xy 146.82017 67.28677) (xy 146.8339 67.28677)
			(xy 146.8339 67.27304) (xy 146.8339 67.25931) (xy 146.84763 67.25931) (xy 146.84763 67.24558) (xy 146.84763 67.23185)
			(xy 146.84763 67.21812) (xy 146.86136 67.21812) (xy 146.86136 67.20438) (xy 146.86136 67.19065) (xy 146.86136 67.17692)
			(xy 146.8751 67.17692) (xy 146.8751 67.16319) (xy 146.8751 67.14946) (xy 146.8751 67.13573) (xy 146.88883 67.13573)
			(xy 146.88883 67.12199) (xy 146.88883 67.10826) (xy 146.88883 67.09453) (xy 146.88883 67.0808) (xy 146.88883 67.06707)
			(xy 146.90256 67.06707) (xy 146.90256 67.05333) (xy 146.90256 67.0396) (xy 146.90256 67.02587) (xy 146.90256 67.01214)
			(xy 146.90256 66.99841) (xy 146.90256 66.98467) (xy 146.90256 66.97094) (xy 146.90256 66.95721) (xy 146.90256 66.94348)
			(xy 146.90256 66.92975) (xy 151.00835 66.92975) (xy 151.00835 66.94348) (xy 151.02209 66.94348) (xy 151.02209 66.95721)
			(xy 151.02209 66.97094) (xy 151.03582 66.97094) (xy 151.03582 66.98467) (xy 151.04955 66.98467) (xy 151.04955 66.99841)
			(xy 151.06328 66.99841) (xy 151.06328 67.01214) (xy 151.07701 67.01214) (xy 151.07701 67.02587) (xy 151.09074 67.02587)
			(xy 151.09074 67.0396) (xy 151.10448 67.0396) (xy 151.10448 67.05333) (xy 151.11821 67.05333) (xy 151.11821 67.06707)
			(xy 151.11821 67.0808) (xy 151.13194 67.0808) (xy 151.13194 67.09453) (xy 151.14567 67.09453) (xy 151.14567 67.10826)
			(xy 151.1594 67.10826) (xy 151.1594 67.12199) (xy 151.17313 67.12199) (xy 151.17313 67.13573) (xy 151.18687 67.13573)
			(xy 151.18687 67.14946) (xy 151.2006 67.14946) (xy 151.2006 67.16319) (xy 151.21433 67.16319) (xy 151.21433 67.17692)
			(xy 151.22806 67.17692) (xy 151.22806 67.19065) (xy 151.24179 67.19065) (xy 151.24179 67.20438) (xy 151.25552 67.20438)
			(xy 151.25552 67.21812) (xy 151.26926 67.21812) (xy 151.26926 67.23185) (xy 151.28299 67.23185) (xy 151.28299 67.24558)
			(xy 151.29672 67.24558) (xy 151.29672 67.25931) (xy 151.31045 67.25931) (xy 151.31045 67.27304) (xy 151.32418 67.27304)
			(xy 151.32418 67.28677) (xy 151.33791 67.28677) (xy 151.33791 67.30051) (xy 151.35165 67.30051) (xy 151.35165 67.31424)
			(xy 151.36538 67.31424) (xy 151.36538 67.32797) (xy 151.37911 67.32797) (xy 151.37911 67.3417) (xy 151.39284 67.3417)
			(xy 151.39284 67.35543) (xy 151.40657 67.35543) (xy 151.40657 67.36916) (xy 151.4203 67.36916) (xy 151.4203 67.3829)
			(xy 151.43404 67.3829) (xy 151.43404 67.39663) (xy 151.44777 67.39663) (xy 151.44777 67.41036) (xy 151.4615 67.41036)
			(xy 151.4615 67.42409) (xy 151.47523 67.42409) (xy 151.47523 67.43782) (xy 151.48896 67.43782) (xy 151.48896 67.45155)
			(xy 151.5027 67.45155) (xy 151.5027 67.46529) (xy 151.53016 67.46529) (xy 151.53016 67.47902) (xy 151.54389 67.47902)
			(xy 151.54389 67.49275) (xy 151.55762 67.49275) (xy 151.55762 67.50648) (xy 151.57136 67.50648) (xy 151.57136 67.52021)
			(xy 151.58509 67.52021) (xy 151.58509 67.53394) (xy 151.59882 67.53394) (xy 151.59882 67.54768) (xy 151.61255 67.54768)
			(xy 151.61255 67.56141) (xy 151.64001 67.56141) (xy 151.64001 67.57514) (xy 151.65375 67.57514) (xy 151.65375 67.58887)
			(xy 151.66748 67.58887) (xy 151.66748 67.6026) (xy 151.68121 67.6026) (xy 151.68121 67.61634) (xy 151.69494 67.61634)
			(xy 151.69494 67.63007) (xy 151.7224 67.63007) (xy 151.7224 67.6438) (xy 151.73614 67.6438) (xy 151.73614 67.65753)
			(xy 151.74987 67.65753) (xy 151.74987 67.67126) (xy 151.7636 67.67126) (xy 151.7636 67.685) (xy 151.79106 67.685)
			(xy 151.79106 67.69873) (xy 151.80479 67.69873) (xy 151.80479 67.71246) (xy 151.81853 67.71246) (xy 151.81853 67.72619)
			(xy 151.83226 67.72619) (xy 151.83226 67.73992) (xy 151.85972 67.73992) (xy 151.85972 67.75365) (xy 151.87345 67.75365)
			(xy 151.87345 67.76739) (xy 151.88718 67.76739) (xy 151.88718 67.78112) (xy 151.91465 67.78112) (xy 151.91465 67.79485)
			(xy 151.92838 67.79485) (xy 151.92838 67.80858) (xy 151.94211 67.80858) (xy 151.94211 67.82231) (xy 151.96958 67.82231)
			(xy 151.96958 67.83604) (xy 151.98331 67.83604) (xy 151.98331 67.84978) (xy 152.01077 67.84978) (xy 152.01077 67.86351)
			(xy 152.0245 67.86351) (xy 152.0245 67.87724) (xy 152.05197 67.87724) (xy 152.05197 67.89097) (xy 152.0657 67.89097)
			(xy 152.0657 67.9047) (xy 152.07943 67.9047) (xy 152.07943 67.91843) (xy 152.10689 67.91843) (xy 152.10689 67.93217)
			(xy 152.12063 67.93217) (xy 152.12063 67.9459) (xy 152.14809 67.9459) (xy 152.14809 67.95963) (xy 152.16182 67.95963)
			(xy 152.16182 67.97336) (xy 152.18928 67.97336) (xy 152.18928 67.98709) (xy 152.21675 67.98709) (xy 152.21675 68.00082)
			(xy 152.23048 68.00082) (xy 152.23048 68.01456) (xy 152.25794 68.01456) (xy 152.25794 68.02829) (xy 152.27167 68.02829)
			(xy 152.27167 68.04202) (xy 152.29914 68.04202) (xy 152.29914 68.05575) (xy 152.3266 68.05575) (xy 152.3266 68.06948)
			(xy 152.34033 68.06948) (xy 152.34033 68.08321) (xy 152.3678 68.08321) (xy 152.3678 68.09695) (xy 152.39526 68.09695)
			(xy 152.39526 68.11068) (xy 152.40899 68.11068) (xy 152.40899 68.12441) (xy 152.43645 68.12441) (xy 152.43645 68.13814)
			(xy 152.46392 68.13814) (xy 152.46392 68.15187) (xy 152.49138 68.15187) (xy 152.49138 68.16561) (xy 152.50511 68.16561)
			(xy 152.50511 68.17934) (xy 152.53258 68.17934) (xy 152.53258 68.19307) (xy 152.56004 68.19307) (xy 152.56004 68.2068)
			(xy 152.58751 68.2068) (xy 152.58751 68.22053) (xy 152.61497 68.22053) (xy 152.61497 68.23427) (xy 152.64243 68.23427)
			(xy 152.64243 68.248) (xy 152.6699 68.248) (xy 152.6699 68.26173) (xy 152.69736 68.26173) (xy 152.69736 68.27546)
			(xy 152.72482 68.27546) (xy 152.72482 68.28919) (xy 152.75229 68.28919) (xy 152.75229 68.30292) (xy 152.77975 68.30292)
			(xy 152.77975 68.31666) (xy 152.80721 68.31666) (xy 152.80721 68.33039) (xy 152.83468 68.33039) (xy 152.83468 68.34412)
			(xy 152.86214 68.34412) (xy 152.86214 68.35785) (xy 152.8896 68.35785) (xy 152.8896 68.37158) (xy 152.9308 68.37158)
			(xy 152.9308 68.38531) (xy 152.95826 68.38531) (xy 152.95826 68.39905) (xy 152.98572 68.39905) (xy 152.98572 68.41278)
			(xy 153.02692 68.41278) (xy 153.02692 68.42651) (xy 153.05438 68.42651) (xy 153.05438 68.44024) (xy 153.09558 68.44024)
			(xy 153.09558 68.45397) (xy 153.12304 68.45397) (xy 153.12304 68.4677) (xy 153.16424 68.4677) (xy 153.16424 68.48144)
			(xy 153.1917 68.48144) (xy 153.1917 68.49517) (xy 153.2329 68.49517) (xy 153.2329 68.5089) (xy 153.27409 68.5089)
			(xy 153.27409 68.52263) (xy 153.31529 68.52263) (xy 153.31529 68.53636) (xy 153.35648 68.53636) (xy 153.35648 68.55009)
			(xy 153.39768 68.55009) (xy 153.39768 68.56383) (xy 153.43887 68.56383) (xy 153.43887 68.57756) (xy 153.48007 68.57756)
			(xy 153.48007 68.59129) (xy 153.52126 68.59129) (xy 153.52126 68.60502) (xy 153.56246 68.60502) (xy 153.56246 68.61875)
			(xy 153.61739 68.61875) (xy 153.61739 68.63248) (xy 153.65858 68.63248) (xy 153.65858 68.64622) (xy 153.71351 68.64622)
			(xy 153.71351 68.65995) (xy 153.76844 68.65995) (xy 153.76844 68.67368) (xy 153.82336 68.67368) (xy 153.82336 68.68741)
			(xy 153.89202 68.68741) (xy 153.89202 68.70114) (xy 153.94695 68.70114) (xy 153.94695 68.71488) (xy 154.00187 68.71488)
			(xy 154.00187 68.72861) (xy 154.08427 68.72861) (xy 154.08427 68.74234) (xy 154.15293 68.74234) (xy 154.15293 68.75607)
			(xy 154.23532 68.75607) (xy 154.23532 68.7698) (xy 154.33144 68.7698) (xy 154.33144 68.78354) (xy 154.44129 68.78354)
			(xy 154.44129 68.79727) (xy 154.56488 68.79727) (xy 154.56488 68.811) (xy 154.74339 68.811) (xy 154.74339 68.82473)
			(xy 155.40251 68.82473) (xy 155.40251 68.811) (xy 155.56729 68.811) (xy 155.56729 68.79727) (xy 155.70461 68.79727)
			(xy 155.70461 68.78354) (xy 155.80073 68.78354) (xy 155.80073 68.7698) (xy 155.89686 68.7698) (xy 155.89686 68.75607)
			(xy 155.97925 68.75607) (xy 155.97925 68.74234) (xy 156.06164 68.74234) (xy 156.06164 68.72861) (xy 156.13029 68.72861)
			(xy 156.13029 68.71488) (xy 156.18522 68.71488) (xy 156.18522 68.70114) (xy 156.25388 68.70114) (xy 156.25388 68.68741)
			(xy 156.30881 68.68741) (xy 156.30881 68.67368) (xy 156.36374 68.67368) (xy 156.36374 68.65995) (xy 156.41866 68.65995)
			(xy 156.41866 68.64622) (xy 156.47359 68.64622) (xy 156.47359 68.63248) (xy 156.51478 68.63248) (xy 156.51478 68.61875)
			(xy 156.56971 68.61875) (xy 156.56971 68.60502) (xy 156.61091 68.60502) (xy 156.61091 68.59129) (xy 156.6521 68.59129)
			(xy 156.6521 68.57756) (xy 156.70703 68.57756) (xy 156.70703 68.56383) (xy 156.74823 68.56383) (xy 156.74823 68.55009)
			(xy 156.78942 68.55009) (xy 156.78942 68.53636) (xy 156.81688 68.53636) (xy 156.81688 68.52263) (xy 156.85808 68.52263)
			(xy 156.85808 68.5089) (xy 156.89927 68.5089) (xy 156.89927 68.49517) (xy 156.94047 68.49517) (xy 156.94047 68.48144)
			(xy 156.96793 68.48144) (xy 156.96793 68.4677) (xy 157.00913 68.4677) (xy 157.00913 68.45397) (xy 157.03659 68.45397)
			(xy 157.03659 68.44024) (xy 157.07779 68.44024) (xy 157.07779 68.42651) (xy 157.10525 68.42651) (xy 157.10525 68.41278)
			(xy 157.14644 68.41278) (xy 157.14644 68.39905) (xy 157.17391 68.39905) (xy 157.17391 68.38531) (xy 157.20137 68.38531)
			(xy 157.20137 68.37158) (xy 157.24257 68.37158) (xy 157.24257 68.35785) (xy 157.27003 68.35785) (xy 157.27003 68.34412)
			(xy 157.2975 68.34412) (xy 157.2975 68.33039) (xy 157.32496 68.33039) (xy 157.32496 68.31666) (xy 157.35242 68.31666)
			(xy 157.35242 68.30292) (xy 157.37989 68.30292) (xy 157.37989 68.28919) (xy 157.40735 68.28919) (xy 157.40735 68.27546)
			(xy 157.43481 68.27546) (xy 157.43481 68.26173) (xy 157.46228 68.26173) (xy 157.46228 68.248) (xy 157.48974 68.248)
			(xy 157.48974 68.23427) (xy 157.5172 68.23427) (xy 157.5172 68.22053) (xy 157.54467 68.22053) (xy 157.54467 68.2068)
			(xy 157.57213 68.2068) (xy 157.57213 68.19307) (xy 157.59959 68.19307) (xy 157.59959 68.17934) (xy 157.62706 68.17934)
			(xy 157.62706 68.16561) (xy 157.65452 68.16561) (xy 157.65452 68.15187) (xy 157.66825 68.15187) (xy 157.66825 68.13814)
			(xy 157.69571 68.13814) (xy 157.69571 68.12441) (xy 157.72318 68.12441) (xy 157.72318 68.11068) (xy 157.75064 68.11068)
			(xy 157.75064 68.09695) (xy 157.76437 68.09695) (xy 157.76437 68.08321) (xy 157.79184 68.08321) (xy 157.79184 68.06948)
			(xy 157.8193 68.06948) (xy 157.8193 68.05575) (xy 157.83303 68.05575) (xy 157.83303 68.04202) (xy 157.8605 68.04202)
			(xy 157.8605 68.02829) (xy 157.87423 68.02829) (xy 157.87423 68.01456) (xy 157.90169 68.01456) (xy 157.90169 68.00082)
			(xy 157.92916 68.00082) (xy 157.92916 67.98709) (xy 157.94289 67.98709) (xy 157.94289 67.97336) (xy 157.97035 67.97336)
			(xy 157.97035 67.95963) (xy 157.98408 67.95963) (xy 157.98408 67.9459) (xy 158.01155 67.9459) (xy 158.01155 67.93217)
			(xy 158.02528 67.93217) (xy 158.02528 67.91843) (xy 158.05274 67.91843) (xy 158.05274 67.9047) (xy 158.06647 67.9047)
			(xy 158.06647 67.89097) (xy 158.09394 67.89097) (xy 158.09394 67.87724) (xy 158.10767 67.87724) (xy 158.10767 67.86351)
			(xy 158.1214 67.86351) (xy 158.1214 67.84978) (xy 158.14886 67.84978) (xy 158.14886 67.83604) (xy 158.16259 67.83604)
			(xy 158.16259 67.82231) (xy 158.19006 67.82231) (xy 158.19006 67.80858) (xy 158.20379 67.80858) (xy 158.20379 67.79485)
			(xy 158.21752 67.79485) (xy 158.21752 67.78112) (xy 158.24498 67.78112) (xy 158.24498 67.76739) (xy 158.25872 67.76739)
			(xy 158.25872 67.75365) (xy 158.27245 67.75365) (xy 158.27245 67.73992) (xy 158.29991 67.73992) (xy 158.29991 67.72619)
			(xy 158.31364 67.72619) (xy 158.31364 67.71246) (xy 158.32738 67.71246) (xy 158.32738 67.69873) (xy 158.35484 67.69873)
			(xy 158.35484 67.685) (xy 158.36857 67.685) (xy 158.36857 67.67126) (xy 158.3823 67.67126) (xy 158.3823 67.65753)
			(xy 158.39604 67.65753) (xy 158.39604 67.6438) (xy 158.4235 67.6438) (xy 158.4235 67.63007) (xy 158.43723 67.63007)
			(xy 158.43723 67.61634) (xy 158.45096 67.61634) (xy 158.45096 67.6026) (xy 158.46469 67.6026) (xy 158.46469 67.58887)
			(xy 158.47843 67.58887) (xy 158.47843 67.57514) (xy 158.50589 67.57514) (xy 158.50589 67.56141) (xy 158.51962 67.56141)
			(xy 158.51962 67.54768) (xy 158.53335 67.54768) (xy 158.53335 67.53394) (xy 158.54708 67.53394) (xy 158.54708 67.52021)
			(xy 158.56082 67.52021) (xy 158.56082 67.50648) (xy 158.57455 67.50648) (xy 158.57455 67.49275) (xy 158.58828 67.49275)
			(xy 158.58828 67.47902) (xy 158.61574 67.47902) (xy 158.61574 67.46529) (xy 158.62947 67.46529) (xy 158.62947 67.45155)
			(xy 158.64321 67.45155) (xy 158.64321 67.43782) (xy 158.65694 67.43782) (xy 158.65694 67.42409) (xy 158.67067 67.42409)
			(xy 158.67067 67.41036) (xy 158.6844 67.41036) (xy 158.6844 67.39663) (xy 158.69813 67.39663) (xy 158.69813 67.3829)
			(xy 158.71186 67.3829) (xy 158.71186 67.36916) (xy 158.7256 67.36916) (xy 158.7256 67.35543) (xy 158.73933 67.35543)
			(xy 158.73933 67.3417) (xy 158.75306 67.3417) (xy 158.75306 67.32797) (xy 158.76679 67.32797) (xy 158.76679 67.31424)
			(xy 158.78052 67.31424) (xy 158.78052 67.30051) (xy 158.79426 67.30051) (xy 158.79426 67.28677) (xy 158.80799 67.28677)
			(xy 158.80799 67.27304) (xy 158.82172 67.27304) (xy 158.82172 67.25931) (xy 158.83545 67.25931) (xy 158.83545 67.24558)
			(xy 158.84918 67.24558) (xy 158.84918 67.23185) (xy 158.86292 67.23185) (xy 158.86292 67.21812) (xy 158.87665 67.21812)
			(xy 158.87665 67.20438) (xy 158.89038 67.20438) (xy 158.89038 67.19065) (xy 158.90411 67.19065) (xy 158.90411 67.17692)
			(xy 158.91784 67.17692) (xy 158.91784 67.16319) (xy 158.93157 67.16319) (xy 158.93157 67.14946) (xy 158.94531 67.14946)
			(xy 158.94531 67.13573) (xy 158.95904 67.13573) (xy 158.95904 67.12199) (xy 158.97277 67.12199) (xy 158.97277 67.10826)
			(xy 158.9865 67.10826) (xy 158.9865 67.09453) (xy 159.00023 67.09453) (xy 159.00023 67.0808) (xy 159.01396 67.0808)
			(xy 159.01396 67.06707) (xy 159.0277 67.06707) (xy 159.0277 67.05333) (xy 159.0277 67.0396) (xy 159.04143 67.0396)
			(xy 159.04143 67.02587) (xy 159.05516 67.02587) (xy 159.05516 67.01214) (xy 159.06889 67.01214) (xy 159.06889 66.99841)
			(xy 159.08262 66.99841) (xy 159.08262 66.98467) (xy 159.09635 66.98467) (xy 159.09635 66.97094) (xy 159.11009 66.97094)
			(xy 159.11009 66.95721) (xy 159.12382 66.95721) (xy 159.12382 66.94348) (xy 159.12382 66.92975) (xy 159.13755 66.92975)
			(xy 159.13755 66.91602) (xy 159.15128 66.91602) (xy 159.15128 66.90228) (xy 159.16501 66.90228) (xy 159.16501 66.88855)
			(xy 159.17874 66.88855) (xy 159.17874 66.87482) (xy 159.17874 66.86109) (xy 159.19248 66.86109) (xy 159.19248 66.84736)
			(xy 159.20621 66.84736) (xy 159.20621 66.83363) (xy 159.21994 66.83363) (xy 159.21994 66.81989) (xy 159.23367 66.81989)
			(xy 159.23367 66.80616) (xy 159.23367 66.79243) (xy 159.2474 66.79243) (xy 159.2474 66.7787) (xy 159.26113 66.7787)
			(xy 159.26113 66.76497) (xy 159.27487 66.76497) (xy 159.27487 66.75124) (xy 159.2886 66.75124) (xy 159.2886 66.7375)
			(xy 159.2886 66.72377) (xy 159.30233 66.72377) (xy 159.30233 66.71004) (xy 159.31606 66.71004) (xy 159.31606 66.69631)
			(xy 159.32979 66.69631) (xy 159.32979 66.68258) (xy 159.32979 66.66885) (xy 159.34353 66.66885) (xy 159.34353 66.65511)
			(xy 159.35726 66.65511) (xy 159.35726 66.64138) (xy 159.37099 66.64138) (xy 159.37099 66.62765) (xy 159.37099 66.61392)
			(xy 159.38472 66.61392) (xy 159.38472 66.60019) (xy 159.39845 66.60019) (xy 159.39845 66.58645) (xy 159.39845 66.57272)
			(xy 159.41219 66.57272) (xy 159.41219 66.55899) (xy 159.42592 66.55899) (xy 159.42592 66.54526) (xy 159.43965 66.54526)
			(xy 159.43965 66.53153) (xy 159.43965 66.51779) (xy 159.45338 66.51779) (xy 159.45338 66.50406) (xy 159.46711 66.50406)
			(xy 159.46711 66.49033) (xy 159.46711 66.4766) (xy 159.48084 66.4766) (xy 159.48084 66.46287) (xy 159.49458 66.46287)
			(xy 159.49458 66.44914) (xy 159.49458 66.4354) (xy 159.50831 66.4354) (xy 159.50831 66.42167) (xy 159.52204 66.42167)
			(xy 159.52204 66.40794) (xy 159.52204 66.39421) (xy 159.53577 66.39421) (xy 159.53577 66.38048) (xy 159.5495 66.38048)
			(xy 159.5495 66.36675) (xy 159.5495 66.35301) (xy 159.56323 66.35301) (xy 159.56323 66.33928) (xy 159.56323 66.32555)
			(xy 159.57697 66.32555) (xy 159.57697 66.31182) (xy 159.5907 66.31182) (xy 159.5907 66.29809) (xy 159.5907 66.28436)
			(xy 159.60443 66.28436) (xy 159.60443 66.27062) (xy 159.61816 66.27062) (xy 159.61816 66.25689) (xy 159.61816 66.24316)
			(xy 159.63189 66.24316) (xy 159.63189 66.22943) (xy 159.63189 66.2157) (xy 159.64562 66.2157) (xy 159.64562 66.20197)
			(xy 159.64562 66.18823) (xy 159.65936 66.18823) (xy 159.65936 66.1745) (xy 159.67309 66.1745) (xy 159.67309 66.16077)
			(xy 159.67309 66.14704) (xy 159.68682 66.14704) (xy 159.68682 66.13331) (xy 159.68682 66.11958) (xy 159.70055 66.11958)
			(xy 159.70055 66.10584) (xy 159.70055 66.09211) (xy 159.71428 66.09211) (xy 159.71428 66.07838) (xy 159.71428 66.06465)
			(xy 159.72801 66.06465) (xy 159.72801 66.05092) (xy 159.74175 66.05092) (xy 159.74175 66.03718) (xy 159.74175 66.02345)
			(xy 159.75548 66.02345) (xy 159.75548 66.00972) (xy 159.75548 65.99599) (xy 159.76921 65.99599) (xy 159.76921 65.98226)
			(xy 159.76921 65.96852) (xy 159.78294 65.96852) (xy 159.78294 65.95479) (xy 159.78294 65.94106) (xy 159.79667 65.94106)
			(xy 159.79667 65.92733) (xy 159.79667 65.9136) (xy 159.8104 65.9136) (xy 159.8104 65.89987) (xy 159.8104 65.88613)
			(xy 159.82414 65.88613) (xy 159.82414 65.8724) (xy 159.82414 65.85867) (xy 159.83787 65.85867) (xy 159.83787 65.84494)
			(xy 159.83787 65.83121) (xy 159.8516 65.83121) (xy 159.8516 65.81748) (xy 159.8516 65.80374) (xy 159.86533 65.80374)
			(xy 159.86533 65.79001) (xy 159.86533 65.77628) (xy 159.87906 65.77628) (xy 159.87906 65.76255) (xy 159.87906 65.74882)
			(xy 159.8928 65.74882) (xy 159.8928 65.73509) (xy 159.8928 65.72135) (xy 159.90653 65.72135) (xy 159.90653 65.70762)
			(xy 159.90653 65.69389) (xy 159.92026 65.69389) (xy 159.92026 65.68016) (xy 159.92026 65.66643) (xy 159.92026 65.6527)
			(xy 159.93399 65.6527) (xy 159.93399 65.63896) (xy 159.93399 65.62523) (xy 159.94772 65.62523) (xy 159.94772 65.6115)
			(xy 159.94772 65.59777) (xy 159.96146 65.59777) (xy 159.96146 65.58404) (xy 159.96146 65.57031) (xy 159.96146 65.55657)
			(xy 159.97519 65.55657) (xy 159.97519 65.54284) (xy 159.97519 65.52911) (xy 159.98892 65.52911) (xy 159.98892 65.51538)
			(xy 159.98892 65.50165) (xy 159.98892 65.48791) (xy 160.00265 65.48791) (xy 160.00265 65.47418) (xy 160.00265 65.46045)
			(xy 160.01638 65.46045) (xy 160.01638 65.44672) (xy 160.01638 65.43299) (xy 160.01638 65.41925) (xy 160.03011 65.41925)
			(xy 160.03011 65.40552) (xy 160.03011 65.39179) (xy 160.04385 65.39179) (xy 160.04385 65.37806) (xy 160.04385 65.36433)
			(xy 160.04385 65.3506) (xy 160.05758 65.3506) (xy 160.05758 65.33686) (xy 160.05758 65.32313) (xy 160.05758 65.3094)
			(xy 160.07131 65.3094) (xy 160.07131 65.29567) (xy 160.07131 65.28194) (xy 160.07131 65.26821) (xy 160.08504 65.26821)
			(xy 160.08504 65.25447) (xy 160.08504 65.24074) (xy 160.08504 65.22701) (xy 160.09877 65.22701) (xy 160.09877 65.21328)
			(xy 160.09877 65.19955) (xy 160.09877 65.18582) (xy 160.1125 65.18582) (xy 160.1125 65.17208) (xy 160.1125 65.15835)
			(xy 160.1125 65.14462) (xy 160.12624 65.14462) (xy 160.12624 65.13089) (xy 160.12624 65.11716) (xy 160.12624 65.10343)
			(xy 160.13997 65.10343) (xy 160.13997 65.08969) (xy 160.13997 65.07596) (xy 160.13997 65.06223) (xy 160.1537 65.06223)
			(xy 160.1537 65.0485) (xy 160.1537 65.03477) (xy 160.1537 65.02104) (xy 160.16743 65.02104) (xy 160.16743 65.0073)
			(xy 160.16743 64.99357) (xy 160.16743 64.97984) (xy 160.16743 64.96611) (xy 160.18116 64.96611) (xy 160.18116 64.95238)
			(xy 160.18116 64.93864) (xy 160.18116 64.92491) (xy 160.19489 64.92491) (xy 160.19489 64.91118) (xy 160.19489 64.89745)
			(xy 160.19489 64.88372) (xy 160.19489 64.86998) (xy 160.20863 64.86998) (xy 160.20863 64.85625) (xy 160.20863 64.84252)
			(xy 160.20863 64.82879) (xy 160.20863 64.81506) (xy 160.22236 64.81506) (xy 160.22236 64.80133) (xy 160.22236 64.78759)
			(xy 160.22236 64.77386) (xy 160.22236 64.76013) (xy 160.23609 64.76013) (xy 160.23609 64.7464) (xy 160.23609 64.73267)
			(xy 160.23609 64.71894) (xy 160.23609 64.7052) (xy 160.24982 64.7052) (xy 160.24982 64.69147) (xy 160.24982 64.67774)
			(xy 160.24982 64.66401) (xy 160.24982 64.65028) (xy 160.24982 64.63655) (xy 160.26355 64.63655) (xy 160.26355 64.62281)
			(xy 160.26355 64.60908) (xy 160.26355 64.59535) (xy 160.26355 64.58162) (xy 160.26355 64.56789) (xy 160.27728 64.56789)
			(xy 160.27728 64.55416) (xy 160.27728 64.54042) (xy 160.27728 64.52669) (xy 160.27728 64.51296) (xy 160.27728 64.49923)
			(xy 160.29102 64.49923) (xy 160.29102 64.4855) (xy 160.29102 64.47176) (xy 160.29102 64.45803) (xy 160.29102 64.4443)
			(xy 160.29102 64.43057) (xy 160.30475 64.43057) (xy 160.30475 64.41684) (xy 160.30475 64.4031) (xy 160.30475 64.38937)
			(xy 160.30475 64.37564) (xy 160.30475 64.36191) (xy 160.30475 64.34818) (xy 160.31848 64.34818) (xy 160.31848 64.33445)
			(xy 160.31848 64.32071) (xy 160.31848 64.30698) (xy 160.31848 64.29325) (xy 160.31848 64.27952) (xy 160.31848 64.26579)
			(xy 160.31848 64.25206) (xy 160.33221 64.25206) (xy 160.33221 64.23833) (xy 160.33221 64.22459) (xy 160.33221 64.21086)
			(xy 160.33221 64.19713) (xy 160.33221 64.1834) (xy 160.33221 64.16967) (xy 160.33221 64.15594) (xy 160.33221 64.1422)
			(xy 160.34594 64.1422) (xy 160.34594 64.12847) (xy 160.34594 64.11474) (xy 160.34594 64.10101) (xy 160.34594 64.08728)
			(xy 160.34594 64.07355) (xy 160.34594 64.05981) (xy 160.34594 64.04608) (xy 160.34594 64.03235) (xy 160.34594 64.01862)
			(xy 160.34594 64.00489) (xy 160.35967 64.00489) (xy 160.35967 63.99115) (xy 160.34594 63.99115) (xy 160.34594 63.97742)
			(xy 160.35967 63.97742) (xy 160.35967 63.96369) (xy 160.35967 63.94996) (xy 160.35967 63.93623) (xy 160.35967 63.92249)
			(xy 160.35967 63.90876) (xy 160.35967 63.89503) (xy 160.35967 63.8813) (xy 160.35967 63.86757) (xy 160.35967 63.85384)
			(xy 160.35967 63.8401) (xy 160.35967 63.82637) (xy 160.37341 63.82637) (xy 160.37341 63.81264) (xy 160.37341 63.79891)
			(xy 160.37341 63.78518) (xy 160.37341 63.77145) (xy 160.37341 63.75771) (xy 160.37341 63.74398) (xy 160.37341 63.73025)
			(xy 160.37341 63.71652) (xy 160.37341 63.70279) (xy 160.37341 63.68906) (xy 160.37341 63.67532) (xy 160.20863 63.67532)
			(xy 160.20863 63.68906) (xy 160.20863 63.70279) (xy 160.20863 63.71652) (xy 160.20863 63.73025) (xy 160.20863 63.74398)
			(xy 160.20863 63.75771) (xy 160.19489 63.75771) (xy 160.19489 63.77145) (xy 160.19489 63.78518) (xy 160.19489 63.79891)
			(xy 160.19489 63.81264) (xy 160.19489 63.82637) (xy 160.19489 63.8401) (xy 160.19489 63.85384) (xy 160.19489 63.86757)
			(xy 160.19489 63.8813) (xy 160.19489 63.89503) (xy 160.19489 63.90876) (xy 160.19489 63.92249) (xy 160.19489 63.93623)
			(xy 160.19489 63.94996) (xy 160.19489 63.96369) (xy 160.19489 63.97742) (xy 160.18116 63.97742) (xy 160.18116 63.99115)
			(xy 160.18116 64.00489) (xy 160.18116 64.01862) (xy 160.18116 64.03235) (xy 160.18116 64.04608) (xy 160.18116 64.05981)
			(xy 160.18116 64.07355) (xy 160.18116 64.08728) (xy 160.18116 64.10101) (xy 160.18116 64.11474) (xy 160.16743 64.11474)
			(xy 160.16743 64.12847) (xy 160.16743 64.1422) (xy 160.16743 64.15594) (xy 160.16743 64.16967) (xy 160.16743 64.1834)
			(xy 160.16743 64.19713) (xy 160.16743 64.21086) (xy 160.16743 64.22459) (xy 160.1537 64.22459) (xy 160.1537 64.23833)
			(xy 160.1537 64.25206) (xy 160.1537 64.26579) (xy 160.1537 64.27952) (xy 160.1537 64.29325) (xy 160.1537 64.30698)
			(xy 160.1537 64.32071) (xy 160.13997 64.32071) (xy 160.13997 64.33445) (xy 160.13997 64.34818) (xy 160.13997 64.36191)
			(xy 160.13997 64.37564) (xy 160.13997 64.38937) (xy 160.13997 64.4031) (xy 160.12624 64.4031) (xy 160.12624 64.41684)
			(xy 160.12624 64.43057) (xy 160.12624 64.4443) (xy 160.12624 64.45803) (xy 160.12624 64.47176) (xy 160.1125 64.47176)
			(xy 160.1125 64.4855) (xy 160.1125 64.49923) (xy 160.1125 64.51296) (xy 160.1125 64.52669) (xy 160.1125 64.54042)
			(xy 160.09877 64.54042) (xy 160.09877 64.55416) (xy 160.09877 64.56789) (xy 160.09877 64.58162) (xy 160.09877 64.59535)
			(xy 160.09877 64.60908) (xy 160.08504 64.60908) (xy 160.08504 64.62281) (xy 160.08504 64.63655) (xy 160.08504 64.65028)
			(xy 160.08504 64.66401) (xy 160.08504 64.67774) (xy 160.07131 64.67774) (xy 160.07131 64.69147) (xy 160.07131 64.7052)
			(xy 160.07131 64.71894) (xy 160.07131 64.73267) (xy 160.05758 64.73267) (xy 160.05758 64.7464) (xy 160.05758 64.76013)
			(xy 160.05758 64.77386) (xy 160.05758 64.78759) (xy 160.04385 64.78759) (xy 160.04385 64.80133) (xy 160.04385 64.81506)
			(xy 160.04385 64.82879) (xy 160.04385 64.84252) (xy 160.03011 64.84252) (xy 160.03011 64.85625) (xy 160.03011 64.86998)
			(xy 160.03011 64.88372) (xy 160.03011 64.89745) (xy 160.01638 64.89745) (xy 160.01638 64.91118) (xy 160.01638 64.92491)
			(xy 160.01638 64.93864) (xy 160.00265 64.93864) (xy 160.00265 64.95238) (xy 160.00265 64.96611) (xy 160.00265 64.97984)
			(xy 160.00265 64.99357) (xy 159.98892 64.99357) (xy 159.98892 65.0073) (xy 159.98892 65.02104) (xy 159.98892 65.03477)
			(xy 159.97519 65.03477) (xy 159.97519 65.0485) (xy 159.97519 65.06223) (xy 159.97519 65.07596) (xy 159.96146 65.07596)
			(xy 159.96146 65.08969) (xy 159.96146 65.10343) (xy 159.96146 65.11716) (xy 159.94772 65.11716) (xy 159.94772 65.13089)
			(xy 159.94772 65.14462) (xy 159.94772 65.15835) (xy 159.93399 65.15835) (xy 159.93399 65.17208) (xy 159.93399 65.18582)
			(xy 159.93399 65.19955) (xy 159.92026 65.19955) (xy 159.92026 65.21328) (xy 159.92026 65.22701) (xy 159.92026 65.24074)
			(xy 159.90653 65.24074) (xy 159.90653 65.25447) (xy 159.90653 65.26821) (xy 159.90653 65.28194) (xy 159.8928 65.28194)
			(xy 159.8928 65.29567) (xy 159.8928 65.3094) (xy 159.87906 65.3094) (xy 159.87906 65.32313) (xy 159.87906 65.33686)
			(xy 159.87906 65.3506) (xy 159.86533 65.3506) (xy 159.86533 65.36433) (xy 159.86533 65.37806) (xy 159.86533 65.39179)
			(xy 159.8516 65.39179) (xy 159.8516 65.40552) (xy 159.8516 65.41925) (xy 159.83787 65.41925) (xy 159.83787 65.43299)
			(xy 159.83787 65.44672) (xy 159.83787 65.46045) (xy 159.82414 65.46045) (xy 159.82414 65.47418) (xy 159.82414 65.48791)
			(xy 159.8104 65.48791) (xy 159.8104 65.50165) (xy 159.8104 65.51538) (xy 159.79667 65.51538) (xy 159.79667 65.52911)
			(xy 159.79667 65.54284) (xy 159.79667 65.55657) (xy 159.78294 65.55657) (xy 159.78294 65.57031) (xy 159.78294 65.58404)
			(xy 159.76921 65.58404) (xy 159.76921 65.59777) (xy 159.76921 65.6115) (xy 159.75548 65.6115) (xy 159.75548 65.62523)
			(xy 159.75548 65.63896) (xy 159.75548 65.6527) (xy 159.74175 65.6527) (xy 159.74175 65.66643) (xy 159.74175 65.68016)
			(xy 159.72801 65.68016) (xy 159.72801 65.69389) (xy 159.72801 65.70762) (xy 159.71428 65.70762) (xy 159.71428 65.72135)
			(xy 159.71428 65.73509) (xy 159.70055 65.73509) (xy 159.70055 65.74882) (xy 159.70055 65.76255) (xy 159.68682 65.76255)
			(xy 159.68682 65.77628) (xy 159.68682 65.79001) (xy 159.67309 65.79001) (xy 159.67309 65.80374) (xy 159.67309 65.81748)
			(xy 159.65936 65.81748) (xy 159.65936 65.83121) (xy 159.65936 65.84494) (xy 159.64562 65.84494) (xy 159.64562 65.85867)
			(xy 159.64562 65.8724) (xy 159.63189 65.8724) (xy 159.63189 65.88613) (xy 159.63189 65.89987) (xy 159.61816 65.89987)
			(xy 159.61816 65.9136) (xy 159.61816 65.92733) (xy 159.60443 65.92733) (xy 159.60443 65.94106) (xy 159.60443 65.95479)
			(xy 159.5907 65.95479) (xy 159.5907 65.96852) (xy 159.5907 65.98226) (xy 159.57697 65.98226) (xy 159.57697 65.99599)
			(xy 159.56323 65.99599) (xy 159.56323 66.00972) (xy 159.56323 66.02345) (xy 159.5495 66.02345) (xy 159.5495 66.03718)
			(xy 159.5495 66.05092) (xy 159.53577 66.05092) (xy 159.53577 66.06465) (xy 159.53577 66.07838) (xy 159.52204 66.07838)
			(xy 159.52204 66.09211) (xy 159.50831 66.09211) (xy 159.50831 66.10584) (xy 159.50831 66.11958) (xy 159.49458 66.11958)
			(xy 159.49458 66.13331) (xy 159.49458 66.14704) (xy 159.48084 66.14704) (xy 159.48084 66.16077) (xy 159.48084 66.1745)
			(xy 159.46711 66.1745) (xy 159.46711 66.18823) (xy 159.45338 66.18823) (xy 159.45338 66.20197) (xy 159.45338 66.2157)
			(xy 159.43965 66.2157) (xy 159.43965 66.22943) (xy 159.42592 66.22943) (xy 159.42592 66.24316) (xy 159.42592 66.25689)
			(xy 159.41219 66.25689) (xy 159.41219 66.27062) (xy 159.41219 66.28436) (xy 159.39845 66.28436) (xy 159.39845 66.29809)
			(xy 159.38472 66.29809) (xy 159.38472 66.31182) (xy 159.38472 66.32555) (xy 159.37099 66.32555) (xy 159.37099 66.33928)
			(xy 159.35726 66.33928) (xy 159.35726 66.35301) (xy 159.35726 66.36675) (xy 159.34353 66.36675) (xy 159.34353 66.38048)
			(xy 159.32979 66.38048) (xy 159.32979 66.39421) (xy 159.32979 66.40794) (xy 159.31606 66.40794) (xy 159.31606 66.42167)
			(xy 159.30233 66.42167) (xy 159.30233 66.4354) (xy 159.30233 66.44914) (xy 159.2886 66.44914) (xy 159.2886 66.46287)
			(xy 159.27487 66.46287) (xy 159.27487 66.4766) (xy 159.27487 66.49033) (xy 159.26113 66.49033) (xy 159.26113 66.50406)
			(xy 159.2474 66.50406) (xy 159.2474 66.51779) (xy 159.23367 66.51779) (xy 159.23367 66.53153) (xy 159.23367 66.54526)
			(xy 159.21994 66.54526) (xy 159.21994 66.55899) (xy 159.20621 66.55899) (xy 159.20621 66.57272) (xy 159.19248 66.57272)
			(xy 159.19248 66.58645) (xy 159.19248 66.60019) (xy 159.17874 66.60019) (xy 159.17874 66.61392) (xy 159.16501 66.61392)
			(xy 159.16501 66.62765) (xy 159.15128 66.62765) (xy 159.15128 66.64138) (xy 159.15128 66.65511) (xy 159.13755 66.65511)
			(xy 159.13755 66.66885) (xy 159.12382 66.66885) (xy 159.12382 66.68258) (xy 159.11009 66.68258) (xy 159.11009 66.69631)
			(xy 159.11009 66.71004) (xy 159.09635 66.71004) (xy 159.09635 66.72377) (xy 159.08262 66.72377) (xy 159.08262 66.7375)
			(xy 159.06889 66.7375) (xy 159.06889 66.75124) (xy 159.05516 66.75124) (xy 159.05516 66.76497) (xy 159.05516 66.7787)
			(xy 159.04143 66.7787) (xy 159.04143 66.79243) (xy 159.0277 66.79243) (xy 159.0277 66.80616) (xy 159.01396 66.80616)
			(xy 159.01396 66.81989) (xy 159.00023 66.81989) (xy 159.00023 66.83363) (xy 158.9865 66.83363) (xy 158.9865 66.84736)
			(xy 158.9865 66.86109) (xy 158.97277 66.86109) (xy 158.97277 66.87482) (xy 158.95904 66.87482) (xy 158.95904 66.88855)
			(xy 158.94531 66.88855) (xy 158.94531 66.90228) (xy 158.93157 66.90228) (xy 158.93157 66.91602) (xy 158.91784 66.91602)
			(xy 158.91784 66.92975) (xy 158.90411 66.92975) (xy 158.90411 66.94348) (xy 158.89038 66.94348) (xy 158.89038 66.95721)
			(xy 158.89038 66.97094) (xy 158.87665 66.97094) (xy 158.87665 66.98467) (xy 158.86292 66.98467) (xy 158.86292 66.99841)
			(xy 158.84918 66.99841) (xy 158.84918 67.01214) (xy 158.83545 67.01214) (xy 158.83545 67.02587) (xy 158.82172 67.02587)
			(xy 158.82172 67.0396) (xy 158.80799 67.0396) (xy 158.80799 67.05333) (xy 158.79426 67.05333) (xy 158.79426 67.06707)
			(xy 158.78052 67.06707) (xy 158.78052 67.0808) (xy 158.76679 67.0808) (xy 158.76679 67.09453) (xy 158.75306 67.09453)
			(xy 158.75306 67.10826) (xy 158.73933 67.10826) (xy 158.73933 67.12199) (xy 158.7256 67.12199) (xy 158.7256 67.13573)
			(xy 158.71186 67.13573) (xy 158.71186 67.14946) (xy 158.69813 67.14946) (xy 158.69813 67.16319) (xy 158.6844 67.16319)
			(xy 158.6844 67.17692) (xy 158.67067 67.17692) (xy 158.67067 67.19065) (xy 158.65694 67.19065) (xy 158.65694 67.20438)
			(xy 158.64321 67.20438) (xy 158.64321 67.21812) (xy 158.62947 67.21812) (xy 158.62947 67.23185) (xy 158.61574 67.23185)
			(xy 158.61574 67.24558) (xy 158.60201 67.24558) (xy 158.60201 67.25931) (xy 158.58828 67.25931) (xy 158.58828 67.27304)
			(xy 158.57455 67.27304) (xy 158.57455 67.28677) (xy 158.56082 67.28677) (xy 158.56082 67.30051) (xy 158.54708 67.30051)
			(xy 158.54708 67.31424) (xy 158.53335 67.31424) (xy 158.53335 67.32797) (xy 158.51962 67.32797) (xy 158.51962 67.3417)
			(xy 158.49216 67.3417) (xy 158.49216 67.35543) (xy 158.47843 67.35543) (xy 158.47843 67.36916) (xy 158.46469 67.36916)
			(xy 158.46469 67.3829) (xy 158.45096 67.3829) (xy 158.45096 67.39663) (xy 158.43723 67.39663) (xy 158.43723 67.41036)
			(xy 158.4235 67.41036) (xy 158.4235 67.42409) (xy 158.40977 67.42409) (xy 158.40977 67.43782) (xy 158.3823 67.43782)
			(xy 158.3823 67.45155) (xy 158.36857 67.45155) (xy 158.36857 67.46529) (xy 158.35484 67.46529) (xy 158.35484 67.47902)
			(xy 158.34111 67.47902) (xy 158.34111 67.49275) (xy 158.32738 67.49275) (xy 158.32738 67.50648) (xy 158.29991 67.50648)
			(xy 158.29991 67.52021) (xy 158.28618 67.52021) (xy 158.28618 67.53394) (xy 158.27245 67.53394) (xy 158.27245 67.54768)
			(xy 158.25872 67.54768) (xy 158.25872 67.56141) (xy 158.23125 67.56141) (xy 158.23125 67.57514) (xy 158.21752 67.57514)
			(xy 158.21752 67.58887) (xy 158.20379 67.58887) (xy 158.20379 67.6026) (xy 158.17633 67.6026) (xy 158.17633 67.61634)
			(xy 158.16259 67.61634) (xy 158.16259 67.63007) (xy 158.14886 67.63007) (xy 158.14886 67.6438) (xy 158.1214 67.6438)
			(xy 158.1214 67.65753) (xy 158.10767 67.65753) (xy 158.10767 67.67126) (xy 158.09394 67.67126) (xy 158.09394 67.685)
			(xy 158.06647 67.685) (xy 158.06647 67.69873) (xy 158.05274 67.69873) (xy 158.05274 67.71246) (xy 158.03901 67.71246)
			(xy 158.03901 67.72619) (xy 158.01155 67.72619) (xy 158.01155 67.73992) (xy 157.99781 67.73992) (xy 157.99781 67.75365)
			(xy 157.97035 67.75365) (xy 157.97035 67.76739) (xy 157.95662 67.76739) (xy 157.95662 67.78112) (xy 157.92916 67.78112)
			(xy 157.92916 67.79485) (xy 157.91542 67.79485) (xy 157.91542 67.80858) (xy 157.88796 67.80858) (xy 157.88796 67.82231)
			(xy 157.87423 67.82231) (xy 157.87423 67.83604) (xy 157.84677 67.83604) (xy 157.84677 67.84978) (xy 157.83303 67.84978)
			(xy 157.83303 67.86351) (xy 157.80557 67.86351) (xy 157.80557 67.87724) (xy 157.77811 67.87724) (xy 157.77811 67.89097)
			(xy 157.76437 67.89097) (xy 157.76437 67.9047) (xy 157.73691 67.9047) (xy 157.73691 67.91843) (xy 157.72318 67.91843)
			(xy 157.72318 67.93217) (xy 157.69571 67.93217) (xy 157.69571 67.9459) (xy 157.66825 67.9459) (xy 157.66825 67.95963)
			(xy 157.65452 67.95963) (xy 157.65452 67.97336) (xy 157.62706 67.97336) (xy 157.62706 67.98709) (xy 157.59959 67.98709)
			(xy 157.59959 68.00082) (xy 157.57213 68.00082) (xy 157.57213 68.01456) (xy 157.54467 68.01456) (xy 157.54467 68.02829)
			(xy 157.53093 68.02829) (xy 157.53093 68.04202) (xy 157.50347 68.04202) (xy 157.50347 68.05575) (xy 157.47601 68.05575)
			(xy 157.47601 68.06948) (xy 157.44854 68.06948) (xy 157.44854 68.08321) (xy 157.42108 68.08321) (xy 157.42108 68.09695)
			(xy 157.39362 68.09695) (xy 157.39362 68.11068) (xy 157.36615 68.11068) (xy 157.36615 68.12441) (xy 157.33869 68.12441)
			(xy 157.33869 68.13814) (xy 157.31123 68.13814) (xy 157.31123 68.15187) (xy 157.28376 68.15187) (xy 157.28376 68.16561)
			(xy 157.2563 68.16561) (xy 157.2563 68.17934) (xy 157.22884 68.17934) (xy 157.22884 68.19307) (xy 157.20137 68.19307)
			(xy 157.20137 68.2068) (xy 157.16018 68.2068) (xy 157.16018 68.22053) (xy 157.13271 68.22053) (xy 157.13271 68.23427)
			(xy 157.10525 68.23427) (xy 157.10525 68.248) (xy 157.07779 68.248) (xy 157.07779 68.26173) (xy 157.03659 68.26173)
			(xy 157.03659 68.27546) (xy 157.00913 68.27546) (xy 157.00913 68.28919) (xy 156.96793 68.28919) (xy 156.96793 68.30292)
			(xy 156.94047 68.30292) (xy 156.94047 68.31666) (xy 156.89927 68.31666) (xy 156.89927 68.33039) (xy 156.87181 68.33039)
			(xy 156.87181 68.34412) (xy 156.83062 68.34412) (xy 156.83062 68.35785) (xy 156.78942 68.35785) (xy 156.78942 68.37158)
			(xy 156.74823 68.37158) (xy 156.74823 68.38531) (xy 156.70703 68.38531) (xy 156.70703 68.39905) (xy 156.66583 68.39905)
			(xy 156.66583 68.41278) (xy 156.62464 68.41278) (xy 156.62464 68.42651) (xy 156.58344 68.42651) (xy 156.58344 68.44024)
			(xy 156.54225 68.44024) (xy 156.54225 68.45397) (xy 156.48732 68.45397) (xy 156.48732 68.4677) (xy 156.44613 68.4677)
			(xy 156.44613 68.48144) (xy 156.3912 68.48144) (xy 156.3912 68.49517) (xy 156.33627 68.49517) (xy 156.33627 68.5089)
			(xy 156.28135 68.5089) (xy 156.28135 68.52263) (xy 156.22642 68.52263) (xy 156.22642 68.53636) (xy 156.17149 68.53636)
			(xy 156.17149 68.55009) (xy 156.10283 68.55009) (xy 156.10283 68.56383) (xy 156.03417 68.56383) (xy 156.03417 68.57756)
			(xy 155.95178 68.57756) (xy 155.95178 68.59129) (xy 155.86939 68.59129) (xy 155.86939 68.60502) (xy 155.77327 68.60502)
			(xy 155.77327 68.61875) (xy 155.66342 68.61875) (xy 155.66342 68.63248) (xy 155.53983 68.63248) (xy 155.53983 68.64622)
			(xy 155.33385 68.64622) (xy 155.33385 68.65995) (xy 154.79832 68.65995) (xy 154.79832 68.64622) (xy 154.77085 68.64622)
			(xy 154.77085 68.65995) (xy 154.75712 68.65995) (xy 154.75712 68.64622) (xy 154.60607 68.64622) (xy 154.60607 68.63248)
			(xy 154.44129 68.63248) (xy 154.44129 68.61875) (xy 154.3589 68.61875) (xy 154.3589 68.60502) (xy 154.26278 68.60502)
			(xy 154.26278 68.59129) (xy 154.18039 68.59129) (xy 154.18039 68.57756) (xy 154.098 68.57756) (xy 154.098 68.56383)
			(xy 154.02934 68.56383) (xy 154.02934 68.55009) (xy 153.97441 68.55009) (xy 153.97441 68.53636) (xy 153.90575 68.53636)
			(xy 153.90575 68.52263) (xy 153.85083 68.52263) (xy 153.85083 68.5089) (xy 153.7959 68.5089) (xy 153.7959 68.49517)
			(xy 153.74097 68.49517) (xy 153.74097 68.48144) (xy 153.68605 68.48144) (xy 153.68605 68.4677) (xy 153.64485 68.4677)
			(xy 153.64485 68.45397) (xy 153.58992 68.45397) (xy 153.58992 68.44024) (xy 153.54873 68.44024) (xy 153.54873 68.42651)
			(xy 153.50753 68.42651) (xy 153.50753 68.41278) (xy 153.46634 68.41278) (xy 153.46634 68.39905) (xy 153.42514 68.39905)
			(xy 153.42514 68.38531) (xy 153.38395 68.38531) (xy 153.38395 68.37158) (xy 153.34275 68.37158) (xy 153.34275 68.35785)
			(xy 153.30156 68.35785) (xy 153.30156 68.34412) (xy 153.27409 68.34412) (xy 153.27409 68.33039) (xy 153.2329 68.33039)
			(xy 153.2329 68.31666) (xy 153.1917 68.31666) (xy 153.1917 68.30292) (xy 153.16424 68.30292) (xy 153.16424 68.28919)
			(xy 153.12304 68.28919) (xy 153.12304 68.27546) (xy 153.09558 68.27546) (xy 153.09558 68.26173) (xy 153.06812 68.26173)
			(xy 153.06812 68.248) (xy 153.02692 68.248) (xy 153.02692 68.23427) (xy 152.99946 68.23427) (xy 152.99946 68.22053)
			(xy 152.95826 68.22053) (xy 152.95826 68.2068) (xy 152.9308 68.2068) (xy 152.9308 68.19307) (xy 152.90333 68.19307)
			(xy 152.90333 68.17934) (xy 152.87587 68.17934) (xy 152.87587 68.16561) (xy 152.84841 68.16561) (xy 152.84841 68.15187)
			(xy 152.82094 68.15187) (xy 152.82094 68.13814) (xy 152.79348 68.13814) (xy 152.79348 68.12441) (xy 152.76602 68.12441)
			(xy 152.76602 68.11068) (xy 152.73855 68.11068) (xy 152.73855 68.09695) (xy 152.71109 68.09695) (xy 152.71109 68.08321)
			(xy 152.68363 68.08321) (xy 152.68363 68.06948) (xy 152.65616 68.06948) (xy 152.65616 68.05575) (xy 152.6287 68.05575)
			(xy 152.6287 68.04202) (xy 152.60124 68.04202) (xy 152.60124 68.02829) (xy 152.58751 68.02829) (xy 152.58751 68.01456)
			(xy 152.56004 68.01456) (xy 152.56004 68.00082) (xy 152.53258 68.00082) (xy 152.53258 67.98709) (xy 152.50511 67.98709)
			(xy 152.50511 67.97336) (xy 152.49138 67.97336) (xy 152.49138 67.95963) (xy 152.46392 67.95963) (xy 152.46392 67.9459)
			(xy 152.43645 67.9459) (xy 152.43645 67.93217) (xy 152.42272 67.93217) (xy 152.42272 67.91843) (xy 152.39526 67.91843)
			(xy 152.39526 67.9047) (xy 152.3678 67.9047) (xy 152.3678 67.89097) (xy 152.35406 67.89097) (xy 152.35406 67.87724)
			(xy 152.3266 67.87724) (xy 152.3266 67.86351) (xy 152.29914 67.86351) (xy 152.29914 67.84978) (xy 152.28541 67.84978)
			(xy 152.28541 67.83604) (xy 152.25794 67.83604) (xy 152.25794 67.82231) (xy 152.24421 67.82231) (xy 152.24421 67.80858)
			(xy 152.21675 67.80858) (xy 152.21675 67.79485) (xy 152.20302 67.79485) (xy 152.20302 67.78112) (xy 152.17555 67.78112)
			(xy 152.17555 67.76739) (xy 152.16182 67.76739) (xy 152.16182 67.75365) (xy 152.13436 67.75365) (xy 152.13436 67.73992)
			(xy 152.12063 67.73992) (xy 152.12063 67.72619) (xy 152.10689 67.72619) (xy 152.10689 67.71246) (xy 152.07943 67.71246)
			(xy 152.07943 67.69873) (xy 152.0657 67.69873) (xy 152.0657 67.685) (xy 152.03824 67.685) (xy 152.03824 67.67126)
			(xy 152.0245 67.67126) (xy 152.0245 67.65753) (xy 152.01077 67.65753) (xy 152.01077 67.6438) (xy 151.98331 67.6438)
			(xy 151.98331 67.63007) (xy 151.96958 67.63007) (xy 151.96958 67.61634) (xy 151.95584 67.61634) (xy 151.95584 67.6026)
			(xy 151.92838 67.6026) (xy 151.92838 67.58887) (xy 151.91465 67.58887) (xy 151.91465 67.57514) (xy 151.90092 67.57514)
			(xy 151.90092 67.56141) (xy 151.88718 67.56141) (xy 151.88718 67.54768) (xy 151.85972 67.54768) (xy 151.85972 67.53394)
			(xy 151.84599 67.53394) (xy 151.84599 67.52021) (xy 151.83226 67.52021) (xy 151.83226 67.50648) (xy 151.81853 67.50648)
			(xy 151.81853 67.49275) (xy 151.79106 67.49275) (xy 151.79106 67.47902) (xy 151.77733 67.47902) (xy 151.77733 67.46529)
			(xy 151.7636 67.46529) (xy 151.7636 67.45155) (xy 151.74987 67.45155) (xy 151.74987 67.43782) (xy 151.73614 67.43782)
			(xy 151.73614 67.42409) (xy 151.70867 67.42409) (xy 151.70867 67.41036) (xy 151.69494 67.41036) (xy 151.69494 67.39663)
			(xy 151.68121 67.39663) (xy 151.68121 67.3829) (xy 151.66748 67.3829) (xy 151.66748 67.36916) (xy 151.65375 67.36916)
			(xy 151.65375 67.35543) (xy 151.64001 67.35543) (xy 151.64001 67.3417) (xy 151.62628 67.3417) (xy 151.62628 67.32797)
			(xy 151.59882 67.32797) (xy 151.59882 67.31424) (xy 151.58509 67.31424) (xy 151.58509 67.30051) (xy 151.57136 67.30051)
			(xy 151.57136 67.28677) (xy 151.55762 67.28677) (xy 151.55762 67.27304) (xy 151.54389 67.27304) (xy 151.54389 67.25931)
			(xy 151.53016 67.25931) (xy 151.53016 67.24558) (xy 151.51643 67.24558) (xy 151.51643 67.23185) (xy 151.5027 67.23185)
			(xy 151.5027 67.21812) (xy 151.48896 67.21812) (xy 151.48896 67.20438) (xy 151.47523 67.20438) (xy 151.47523 67.19065)
			(xy 151.4615 67.19065) (xy 151.4615 67.17692) (xy 151.44777 67.17692) (xy 151.44777 67.16319) (xy 151.43404 67.16319)
			(xy 151.43404 67.14946) (xy 151.4203 67.14946) (xy 151.4203 67.13573) (xy 151.40657 67.13573) (xy 151.40657 67.12199)
			(xy 151.39284 67.12199) (xy 151.39284 67.10826) (xy 151.37911 67.10826) (xy 151.37911 67.09453) (xy 151.36538 67.09453)
			(xy 151.36538 67.0808) (xy 151.35165 67.0808) (xy 151.35165 67.06707) (xy 151.33791 67.06707) (xy 151.33791 67.05333)
			(xy 151.32418 67.05333) (xy 151.32418 67.0396) (xy 151.31045 67.0396) (xy 151.31045 67.02587) (xy 151.29672 67.02587)
			(xy 151.29672 67.01214) (xy 151.28299 67.01214) (xy 151.28299 66.99841) (xy 151.26926 66.99841) (xy 151.26926 66.98467)
			(xy 151.25552 66.98467) (xy 151.25552 66.97094) (xy 151.25552 66.95721) (xy 151.24179 66.95721) (xy 151.24179 66.94348)
			(xy 151.22806 66.94348) (xy 151.22806 66.92975) (xy 151.00835 66.92975) (xy 146.90256 66.92975) (xy 146.90256 66.91602)
			(xy 146.90256 66.90228) (xy 146.90256 66.88855) (xy 146.90256 66.87482) (xy 146.90256 66.86109) (xy 146.90256 66.84736)
			(xy 146.90256 66.83363) (xy 146.90256 66.81989) (xy 146.90256 66.80616) (xy 146.90256 66.79243) (xy 146.90256 66.7787)
			(xy 146.88883 66.7787) (xy 146.88883 66.76497) (xy 146.88883 66.75124) (xy 146.88883 66.7375) (xy 146.88883 66.72377)
			(xy 146.88883 66.71004) (xy 146.8751 66.71004) (xy 146.8751 66.69631) (xy 146.8751 66.68258) (xy 146.8751 66.66885)
			(xy 146.86136 66.66885) (xy 146.86136 66.65511) (xy 146.86136 66.64138) (xy 146.86136 66.62765) (xy 146.84763 66.62765)
			(xy 146.84763 66.61392) (xy 146.84763 66.60019) (xy 146.84763 66.58645) (xy 146.8339 66.58645) (xy 146.8339 66.57272)
			(xy 146.8339 66.55899) (xy 146.82017 66.55899) (xy 146.82017 66.54526) (xy 146.82017 66.53153) (xy 146.80644 66.53153)
			(xy 146.80644 66.51779) (xy 146.80644 66.50406) (xy 146.79271 66.50406) (xy 146.79271 66.49033) (xy 146.79271 66.4766)
			(xy 146.77897 66.4766) (xy 146.77897 66.46287) (xy 146.76524 66.46287) (xy 146.76524 66.44914) (xy 146.76524 66.4354)
			(xy 146.75151 66.4354) (xy 146.75151 66.42167) (xy 146.73778 66.42167) (xy 146.73778 66.40794) (xy 146.73778 66.39421)
			(xy 146.72405 66.39421) (xy 146.72405 66.38048) (xy 146.71031 66.38048) (xy 146.71031 66.36675) (xy 146.69658 66.36675)
			(xy 146.69658 66.35301) (xy 146.68285 66.35301) (xy 146.68285 66.33928) (xy 146.68285 66.32555) (xy 146.66912 66.32555)
			(xy 146.66912 66.31182) (xy 146.65539 66.31182) (xy 146.65539 66.29809) (xy 146.64165 66.29809) (xy 146.64165 66.28436)
			(xy 146.62792 66.28436) (xy 146.62792 66.27062) (xy 146.61419 66.27062) (xy 146.61419 66.25689) (xy 146.58673 66.25689)
			(xy 146.58673 66.24316) (xy 146.573 66.24316) (xy 146.573 66.22943) (xy 146.55926 66.22943) (xy 146.55926 66.2157)
			(xy 146.54553 66.2157) (xy 146.54553 66.20197) (xy 146.51807 66.20197) (xy 146.51807 66.18823) (xy 146.50434 66.18823)
			(xy 146.50434 66.1745) (xy 146.47687 66.1745) (xy 146.47687 66.16077) (xy 146.44941 66.16077) (xy 146.44941 66.14704)
			(xy 146.43568 66.14704) (xy 146.43568 66.13331) (xy 146.40822 66.13331) (xy 146.40822 66.11958) (xy 146.38075 66.11958)
			(xy 146.38075 66.10584) (xy 146.33956 66.10584) (xy 146.33956 66.09211) (xy 146.31209 66.09211) (xy 146.31209 66.07838)
			(xy 146.2709 66.07838) (xy 146.2709 66.06465) (xy 146.21597 66.06465) (xy 146.21597 66.05092) (xy 146.14731 66.05092)
			(xy 146.14731 66.03718) (xy 146.00999 66.03718) (xy 146.00999 66.02345) (xy 145.99626 66.02345) (xy 145.99626 66.03718)
			(xy 141.87674 66.03718) (xy 141.87674 66.02345) (xy 141.86301 66.02345) (xy 141.86301 66.03718) (xy 141.83554 66.03718)
			(xy 141.83554 66.02345) (xy 141.73942 66.02345) (xy 141.73942 66.00972) (xy 141.67076 66.00972) (xy 141.67076 65.99599)
			(xy 141.62957 65.99599) (xy 141.62957 65.98226) (xy 141.58837 65.98226) (xy 141.58837 65.96852) (xy 141.54718 65.96852)
			(xy 141.54718 65.95479) (xy 141.51971 65.95479) (xy 141.51971 65.94106) (xy 141.49225 65.94106) (xy 141.49225 65.92733)
			(xy 141.46479 65.92733) (xy 141.46479 65.9136) (xy 141.43732 65.9136) (xy 141.43732 65.89987) (xy 141.42359 65.89987)
			(xy 141.42359 65.88613) (xy 141.39613 65.88613) (xy 141.39613 65.8724) (xy 141.38239 65.8724) (xy 141.38239 65.85867)
			(xy 141.35493 65.85867) (xy 141.35493 65.84494) (xy 141.3412 65.84494) (xy 141.3412 65.83121) (xy 141.32747 65.83121)
			(xy 141.32747 65.81748) (xy 141.3 65.81748) (xy 141.3 65.80374) (xy 141.28627 65.80374) (xy 141.28627 65.79001)
			(xy 141.27254 65.79001) (xy 141.27254 65.77628) (xy 141.25881 65.77628) (xy 141.25881 65.76255) (xy 141.24508 65.76255)
			(xy 141.24508 65.74882) (xy 141.23135 65.74882) (xy 141.23135 65.73509) (xy 141.21761 65.73509) (xy 141.21761 65.72135)
			(xy 141.20388 65.72135) (xy 141.20388 65.70762) (xy 141.20388 65.69389) (xy 141.19015 65.69389) (xy 141.19015 65.68016)
			(xy 141.17642 65.68016) (xy 141.17642 65.66643) (xy 141.16269 65.66643) (xy 141.16269 65.6527) (xy 141.14896 65.6527)
			(xy 141.14896 65.63896) (xy 141.14896 65.62523) (xy 141.13522 65.62523) (xy 141.13522 65.6115) (xy 141.12149 65.6115)
			(xy 141.12149 65.59777) (xy 141.12149 65.58404) (xy 141.10776 65.58404) (xy 141.10776 65.57031) (xy 141.10776 65.55657)
			(xy 141.09403 65.55657) (xy 141.09403 65.54284) (xy 141.09403 65.52911) (xy 141.0803 65.52911) (xy 141.0803 65.51538)
			(xy 141.0803 65.50165) (xy 141.06657 65.50165) (xy 141.06657 65.48791) (xy 141.06657 65.47418) (xy 141.05283 65.47418)
			(xy 141.05283 65.46045) (xy 141.05283 65.44672) (xy 141.05283 65.43299) (xy 141.0391 65.43299) (xy 141.0391 65.41925)
			(xy 141.0391 65.40552) (xy 141.0391 65.39179) (xy 141.02537 65.39179) (xy 141.02537 65.37806) (xy 141.02537 65.36433)
			(xy 141.02537 65.3506) (xy 141.01164 65.3506) (xy 141.01164 65.33686) (xy 141.01164 65.32313) (xy 141.01164 65.3094)
			(xy 141.01164 65.29567) (xy 141.01164 65.28194) (xy 140.99791 65.28194) (xy 140.99791 65.26821) (xy 140.99791 65.25447)
			(xy 140.99791 65.24074) (xy 140.99791 65.22701) (xy 140.99791 65.21328) (xy 140.99791 65.19955) (xy 140.99791 65.18582)
			(xy 140.99791 65.17208) (xy 140.99791 65.15835) (xy 140.99791 65.14462) (xy 140.99791 65.13089) (xy 140.99791 65.11716)
			(xy 140.99791 65.10343) (xy 140.99791 65.08969) (xy 140.99791 65.07596) (xy 140.99791 65.06223) (xy 140.99791 65.0485)
			(xy 140.99791 65.03477) (xy 140.99791 65.02104) (xy 140.99791 65.0073) (xy 140.99791 64.99357) (xy 141.01164 64.99357)
			(xy 141.01164 64.97984) (xy 141.01164 64.96611) (xy 141.01164 64.95238) (xy 141.01164 64.93864) (xy 141.01164 64.92491)
			(xy 141.02537 64.92491) (xy 141.02537 64.91118) (xy 141.02537 64.89745) (xy 141.02537 64.88372) (xy 141.02537 64.86998)
			(xy 141.0391 64.86998) (xy 141.0391 64.85625) (xy 141.0391 64.84252) (xy 141.0391 64.82879) (xy 141.05283 64.82879)
			(xy 141.05283 64.81506) (xy 141.05283 64.80133) (xy 141.06657 64.80133) (xy 141.06657 64.78759) (xy 141.06657 64.77386)
			(xy 141.06657 64.76013) (xy 141.0803 64.76013) (xy 141.0803 64.7464) (xy 141.0803 64.73267) (xy 141.09403 64.73267)
			(xy 141.09403 64.71894) (xy 141.09403 64.7052) (xy 141.10776 64.7052) (xy 141.10776 64.69147) (xy 141.12149 64.69147)
			(xy 141.12149 64.67774) (xy 141.12149 64.66401) (xy 141.13522 64.66401) (xy 141.13522 64.65028) (xy 141.13522 64.63655)
			(xy 141.14896 64.63655) (xy 141.14896 64.62281) (xy 141.16269 64.62281) (xy 141.16269 64.60908) (xy 141.17642 64.60908)
			(xy 141.17642 64.59535) (xy 141.17642 64.58162) (xy 141.19015 64.58162) (xy 141.19015 64.56789) (xy 141.20388 64.56789)
			(xy 141.20388 64.55416) (xy 141.21761 64.55416) (xy 141.21761 64.54042) (xy 141.23135 64.54042) (xy 141.23135 64.52669)
			(xy 141.24508 64.52669) (xy 141.24508 64.51296) (xy 141.25881 64.51296) (xy 141.25881 64.49923) (xy 141.27254 64.49923)
			(xy 141.27254 64.4855) (xy 141.28627 64.4855) (xy 141.28627 64.47176) (xy 141.3 64.47176) (xy 141.3 64.45803)
			(xy 141.31374 64.45803) (xy 141.31374 64.4443) (xy 141.32747 64.4443) (xy 141.32747 64.43057) (xy 141.35493 64.43057)
			(xy 141.35493 64.41684) (xy 141.36866 64.41684) (xy 141.36866 64.4031) (xy 141.38239 64.4031) (xy 141.38239 64.38937)
			(xy 141.40986 64.38937) (xy 141.40986 64.37564) (xy 141.42359 64.37564) (xy 141.42359 64.36191) (xy 141.45105 64.36191)
			(xy 141.45105 64.34818) (xy 141.47852 64.34818) (xy 141.47852 64.33445) (xy 141.50598 64.33445) (xy 141.50598 64.32071)
			(xy 141.53345 64.32071) (xy 141.53345 64.30698) (xy 141.57464 64.30698) (xy 141.57464 64.29325) (xy 141.61584 64.29325)
			(xy 141.61584 64.27952) (xy 141.65703 64.27952) (xy 141.65703 64.26579) (xy 141.71196 64.26579) (xy 141.71196 64.25206)
			(xy 141.78062 64.25206) (xy 141.78062 64.23833) (xy 144.41711 64.23833) (xy 144.41711 64.22459) (xy 144.51323 64.22459)
			(xy 144.51323 64.21086) (xy 144.56816 64.21086) (xy 144.56816 64.19713) (xy 144.60936 64.19713) (xy 144.60936 64.1834)
			(xy 144.65055 64.1834) (xy 148.08349 64.1834) (xy 148.08349 64.19713) (xy 148.08349 64.21086) (xy 148.08349 64.22459)
			(xy 148.08349 64.23833) (xy 148.08349 64.25206) (xy 148.08349 64.26579) (xy 148.08349 64.27952) (xy 148.08349 64.29325)
			(xy 148.08349 64.30698) (xy 148.08349 64.32071) (xy 148.08349 64.33445) (xy 148.08349 64.34818) (xy 148.08349 64.36191)
			(xy 148.08349 64.37564) (xy 148.08349 64.38937) (xy 148.08349 64.4031) (xy 148.08349 64.41684) (xy 148.08349 64.43057)
			(xy 148.08349 64.4443) (xy 148.08349 64.45803) (xy 148.08349 64.47176) (xy 148.08349 64.4855) (xy 148.08349 64.49923)
			(xy 148.08349 64.51296) (xy 148.08349 64.52669) (xy 148.08349 64.54042) (xy 148.08349 64.55416) (xy 148.08349 64.56789)
			(xy 148.08349 64.58162) (xy 148.08349 64.59535) (xy 148.08349 64.60908) (xy 148.08349 64.62281) (xy 148.08349 64.63655)
			(xy 148.08349 64.65028) (xy 148.08349 64.66401) (xy 148.08349 64.67774) (xy 148.08349 64.69147) (xy 148.08349 64.7052)
			(xy 148.08349 64.71894) (xy 148.08349 64.73267) (xy 148.08349 64.7464) (xy 148.08349 64.76013) (xy 148.08349 64.77386)
			(xy 148.08349 64.78759) (xy 148.08349 64.80133) (xy 148.08349 64.81506) (xy 148.08349 64.82879) (xy 148.08349 64.84252)
			(xy 148.08349 64.85625) (xy 148.08349 64.86998) (xy 148.08349 64.88372) (xy 148.08349 64.89745) (xy 148.08349 64.91118)
			(xy 148.08349 64.92491) (xy 148.08349 64.93864) (xy 148.08349 64.95238) (xy 148.08349 64.96611) (xy 148.08349 64.97984)
			(xy 148.08349 64.99357) (xy 148.08349 65.0073) (xy 148.08349 65.02104) (xy 148.08349 65.03477) (xy 148.08349 65.0485)
			(xy 148.08349 65.06223) (xy 148.08349 65.07596) (xy 148.08349 65.08969) (xy 148.08349 65.10343) (xy 148.08349 65.11716)
			(xy 148.08349 65.13089) (xy 148.08349 65.14462) (xy 148.08349 65.15835) (xy 148.08349 65.17208) (xy 148.08349 65.18582)
			(xy 148.08349 65.19955) (xy 148.08349 65.21328) (xy 148.08349 65.22701) (xy 148.08349 65.24074) (xy 148.08349 65.25447)
			(xy 148.08349 65.26821) (xy 148.08349 65.28194) (xy 148.08349 65.29567) (xy 148.08349 65.3094) (xy 148.08349 65.32313)
			(xy 148.08349 65.33686) (xy 148.08349 65.3506) (xy 148.08349 65.36433) (xy 148.08349 65.37806) (xy 148.08349 65.39179)
			(xy 148.08349 65.40552) (xy 148.08349 65.41925) (xy 148.08349 65.43299) (xy 148.08349 65.44672) (xy 148.08349 65.46045)
			(xy 148.08349 65.47418) (xy 148.08349 65.48791) (xy 148.08349 65.50165) (xy 148.08349 65.51538) (xy 148.08349 65.52911)
			(xy 148.08349 65.54284) (xy 148.08349 65.55657) (xy 148.08349 65.57031) (xy 148.08349 65.58404) (xy 148.08349 65.59777)
			(xy 148.08349 65.6115) (xy 148.08349 65.62523) (xy 148.08349 65.63896) (xy 148.08349 65.6527) (xy 148.08349 65.66643)
			(xy 148.08349 65.68016) (xy 148.08349 65.69389) (xy 148.08349 65.70762) (xy 148.08349 65.72135) (xy 148.08349 65.73509)
			(xy 148.08349 65.74882) (xy 148.08349 65.76255) (xy 148.08349 65.77628) (xy 148.08349 65.79001) (xy 148.08349 65.80374)
			(xy 148.08349 65.81748) (xy 148.08349 65.83121) (xy 148.08349 65.84494) (xy 148.08349 65.85867) (xy 148.08349 65.8724)
			(xy 148.08349 65.88613) (xy 148.08349 65.89987) (xy 148.08349 65.9136) (xy 148.08349 65.92733) (xy 148.08349 65.94106)
			(xy 148.08349 65.95479) (xy 148.08349 65.96852) (xy 148.08349 65.98226) (xy 148.08349 65.99599) (xy 148.08349 66.00972)
			(xy 148.08349 66.02345) (xy 148.08349 66.03718) (xy 148.08349 66.05092) (xy 148.08349 66.06465) (xy 148.08349 66.07838)
			(xy 148.08349 66.09211) (xy 148.08349 66.10584) (xy 148.08349 66.11958) (xy 148.08349 66.13331) (xy 148.09722 66.13331)
			(xy 148.09722 66.14704) (xy 148.09722 66.16077) (xy 148.09722 66.1745) (xy 148.09722 66.18823) (xy 148.11095 66.18823)
			(xy 148.11095 66.20197) (xy 148.11095 66.2157) (xy 148.11095 66.22943) (xy 148.12468 66.22943) (xy 148.12468 66.24316)
			(xy 148.13842 66.24316) (xy 148.13842 66.25689) (xy 148.15215 66.25689) (xy 148.15215 66.27062) (xy 148.16588 66.27062)
			(xy 148.16588 66.28436) (xy 148.17961 66.28436) (xy 148.17961 66.29809) (xy 148.19334 66.29809) (xy 148.19334 66.31182)
			(xy 148.20707 66.31182) (xy 148.20707 66.32555) (xy 148.22081 66.32555) (xy 148.22081 66.33928) (xy 148.23454 66.33928)
			(xy 148.23454 66.35301) (xy 148.24827 66.35301) (xy 148.24827 66.36675) (xy 148.262 66.36675) (xy 148.262 66.38048)
			(xy 148.27573 66.38048) (xy 148.27573 66.39421) (xy 148.28947 66.39421) (xy 148.28947 66.40794) (xy 148.3032 66.40794)
			(xy 148.3032 66.42167) (xy 148.31693 66.42167) (xy 148.31693 66.4354) (xy 148.33066 66.4354) (xy 148.33066 66.44914)
			(xy 148.34439 66.44914) (xy 148.34439 66.46287) (xy 148.35813 66.46287) (xy 148.35813 66.4766) (xy 148.37186 66.4766)
			(xy 148.37186 66.49033) (xy 148.38559 66.49033) (xy 148.38559 66.50406) (xy 148.39932 66.50406) (xy 148.39932 66.51779)
			(xy 148.41305 66.51779) (xy 148.41305 66.53153) (xy 148.42678 66.53153) (xy 148.42678 66.54526) (xy 148.44052 66.54526)
			(xy 148.44052 66.55899) (xy 148.45425 66.55899) (xy 148.45425 66.57272) (xy 148.46798 66.57272) (xy 148.46798 66.58645)
			(xy 148.48171 66.58645) (xy 148.48171 66.60019) (xy 148.49544 66.60019) (xy 148.49544 66.61392) (xy 148.50917 66.61392)
			(xy 148.50917 66.62765) (xy 148.53664 66.62765) (xy 148.53664 66.64138) (xy 148.59156 66.64138) (xy 148.59156 66.65511)
			(xy 150.55521 66.65511) (xy 150.55521 66.64138) (xy 150.56894 66.64138) (xy 150.56894 66.62765) (xy 150.58267 66.62765)
			(xy 150.58267 66.61392) (xy 150.5964 66.61392) (xy 150.5964 66.60019) (xy 150.5964 66.58645) (xy 150.8985 66.58645)
			(xy 150.8985 66.60019) (xy 150.8985 66.61392) (xy 150.8985 66.62765) (xy 150.8985 66.64138) (xy 150.91223 66.64138)
			(xy 150.91223 66.65511) (xy 151.68121 66.65511) (xy 151.68121 66.64138) (xy 151.70867 66.64138) (xy 151.70867 66.62765)
			(xy 151.7224 66.62765) (xy 151.7224 66.61392) (xy 151.73614 66.61392) (xy 151.73614 66.60019) (xy 151.74987 66.60019)
			(xy 151.74987 66.58645) (xy 151.7636 66.58645) (xy 151.7636 66.57272) (xy 151.7636 66.55899) (xy 151.77733 66.55899)
			(xy 151.77733 66.54526) (xy 151.77733 66.53153) (xy 151.79106 66.53153) (xy 151.79106 66.51779) (xy 151.80479 66.51779)
			(xy 151.80479 66.50406) (xy 151.80479 66.49033) (xy 151.81853 66.49033) (xy 151.81853 66.4766) (xy 151.81853 66.46287)
			(xy 151.83226 66.46287) (xy 151.83226 66.44914) (xy 151.83226 66.4354) (xy 151.84599 66.4354) (xy 151.84599 66.42167)
			(xy 151.85972 66.42167) (xy 151.85972 66.40794) (xy 151.85972 66.39421) (xy 151.87345 66.39421) (xy 151.87345 66.38048)
			(xy 151.87345 66.36675) (xy 151.88718 66.36675) (xy 151.88718 66.35301) (xy 151.90092 66.35301) (xy 151.90092 66.33928)
			(xy 151.90092 66.32555) (xy 151.91465 66.32555) (xy 151.91465 66.31182) (xy 151.91465 66.29809) (xy 151.92838 66.29809)
			(xy 151.92838 66.28436) (xy 151.94211 66.28436) (xy 151.94211 66.27062) (xy 151.94211 66.25689) (xy 151.95584 66.25689)
			(xy 151.95584 66.24316) (xy 151.95584 66.22943) (xy 151.96958 66.22943) (xy 151.96958 66.2157) (xy 151.98331 66.2157)
			(xy 151.98331 66.20197) (xy 151.98331 66.18823) (xy 151.99704 66.18823) (xy 151.99704 66.1745) (xy 151.99704 66.16077)
			(xy 152.01077 66.16077) (xy 152.01077 66.14704) (xy 152.01077 66.13331) (xy 152.0245 66.13331) (xy 152.0245 66.11958)
			(xy 152.03824 66.11958) (xy 152.03824 66.10584) (xy 152.03824 66.09211) (xy 152.05197 66.09211) (xy 152.05197 66.07838)
			(xy 152.05197 66.06465) (xy 152.0657 66.06465) (xy 152.0657 66.05092) (xy 152.07943 66.05092) (xy 152.07943 66.03718)
			(xy 152.07943 66.02345) (xy 152.09316 66.02345) (xy 152.09316 66.00972) (xy 152.09316 65.99599) (xy 152.10689 65.99599)
			(xy 152.10689 65.98226) (xy 152.12063 65.98226) (xy 152.12063 65.96852) (xy 152.12063 65.95479) (xy 152.13436 65.95479)
			(xy 152.13436 65.94106) (xy 152.13436 65.92733) (xy 152.14809 65.92733) (xy 152.14809 65.9136) (xy 152.14809 65.89987)
			(xy 152.16182 65.89987) (xy 152.16182 65.88613) (xy 152.17555 65.88613) (xy 152.17555 65.8724) (xy 152.17555 65.85867)
			(xy 152.18928 65.85867) (xy 152.18928 65.84494) (xy 152.18928 65.83121) (xy 152.20302 65.83121) (xy 152.20302 65.81748)
			(xy 152.21675 65.81748) (xy 152.21675 65.80374) (xy 152.21675 65.79001) (xy 152.23048 65.79001) (xy 152.23048 65.77628)
			(xy 152.23048 65.76255) (xy 152.75229 65.76255) (xy 152.75229 65.77628) (xy 152.75229 65.79001) (xy 152.75229 65.80374)
			(xy 152.75229 65.81748) (xy 152.75229 65.83121) (xy 152.76602 65.83121) (xy 152.76602 65.84494) (xy 152.75229 65.84494)
			(xy 152.75229 65.85867) (xy 152.75229 65.8724) (xy 152.75229 65.88613) (xy 152.75229 65.89987) (xy 152.75229 65.9136)
			(xy 152.75229 65.92733) (xy 152.75229 65.94106) (xy 152.75229 65.95479) (xy 152.75229 65.96852) (xy 152.75229 65.98226)
			(xy 152.75229 65.99599) (xy 152.75229 66.00972) (xy 152.75229 66.02345) (xy 152.75229 66.03718) (xy 152.75229 66.05092)
			(xy 152.75229 66.06465) (xy 152.75229 66.07838) (xy 152.75229 66.09211) (xy 152.75229 66.10584) (xy 152.75229 66.11958)
			(xy 152.75229 66.13331) (xy 152.75229 66.14704) (xy 152.75229 66.16077) (xy 152.75229 66.1745) (xy 152.75229 66.18823)
			(xy 152.75229 66.20197) (xy 152.75229 66.2157) (xy 152.75229 66.22943) (xy 152.75229 66.24316) (xy 152.75229 66.25689)
			(xy 152.75229 66.27062) (xy 152.75229 66.28436) (xy 152.75229 66.29809) (xy 152.75229 66.31182) (xy 152.75229 66.32555)
			(xy 152.75229 66.33928) (xy 152.75229 66.35301) (xy 152.75229 66.36675) (xy 152.75229 66.38048) (xy 152.75229 66.39421)
			(xy 152.75229 66.40794) (xy 152.75229 66.42167) (xy 152.75229 66.4354) (xy 152.75229 66.44914) (xy 152.75229 66.46287)
			(xy 152.75229 66.4766) (xy 152.75229 66.49033) (xy 152.75229 66.50406) (xy 152.75229 66.51779) (xy 152.75229 66.53153)
			(xy 152.75229 66.54526) (xy 152.75229 66.55899) (xy 152.75229 66.57272) (xy 152.75229 66.58645) (xy 152.76602 66.58645)
			(xy 152.76602 66.60019) (xy 152.76602 66.61392) (xy 152.76602 66.62765) (xy 152.77975 66.62765) (xy 152.77975 66.64138)
			(xy 152.79348 66.64138) (xy 152.79348 66.65511) (xy 153.46634 66.65511) (xy 153.46634 66.64138) (xy 153.4938 66.64138)
			(xy 153.4938 66.62765) (xy 153.50753 66.62765) (xy 153.50753 66.61392) (xy 153.50753 66.60019) (xy 153.50753 66.58645)
			(xy 153.52126 66.58645) (xy 153.52126 66.57272) (xy 153.50753 66.57272) (xy 153.50753 66.55899) (xy 153.52126 66.55899)
			(xy 153.52126 66.54526) (xy 153.52126 66.53153) (xy 153.52126 66.51779) (xy 153.52126 66.50406) (xy 153.52126 66.49033)
			(xy 153.52126 66.4766) (xy 153.52126 66.46287) (xy 153.52126 66.44914) (xy 153.52126 66.4354) (xy 153.52126 66.42167)
			(xy 153.52126 66.40794) (xy 153.52126 66.39421) (xy 153.52126 66.38048) (xy 153.52126 66.36675) (xy 153.52126 66.35301)
			(xy 153.52126 66.33928) (xy 153.52126 66.32555) (xy 153.52126 66.31182) (xy 153.52126 66.29809) (xy 153.52126 66.28436)
			(xy 153.52126 66.27062) (xy 153.52126 66.25689) (xy 153.52126 66.24316) (xy 153.52126 66.22943) (xy 153.52126 66.2157)
			(xy 153.52126 66.20197) (xy 153.52126 66.18823) (xy 153.52126 66.1745) (xy 153.52126 66.16077) (xy 153.52126 66.14704)
			(xy 153.52126 66.13331) (xy 153.52126 66.11958) (xy 153.52126 66.10584) (xy 153.52126 66.09211) (xy 153.52126 66.07838)
			(xy 153.52126 66.06465) (xy 153.52126 66.05092) (xy 153.52126 66.03718) (xy 153.52126 66.02345) (xy 153.52126 66.00972)
			(xy 153.52126 65.99599) (xy 153.52126 65.98226) (xy 153.52126 65.96852) (xy 153.52126 65.95479) (xy 153.52126 65.94106)
			(xy 153.52126 65.92733) (xy 153.52126 65.9136) (xy 153.52126 65.89987) (xy 153.52126 65.88613) (xy 153.52126 65.8724)
			(xy 153.52126 65.85867) (xy 153.52126 65.84494) (xy 153.52126 65.83121) (xy 153.52126 65.81748) (xy 153.52126 65.80374)
			(xy 153.52126 65.79001) (xy 153.52126 65.77628) (xy 153.52126 65.76255) (xy 153.52126 65.74882) (xy 153.52126 65.73509)
			(xy 153.52126 65.72135) (xy 153.52126 65.70762) (xy 153.52126 65.69389) (xy 153.52126 65.68016) (xy 153.52126 65.66643)
			(xy 153.52126 65.6527) (xy 153.52126 65.63896) (xy 153.52126 65.62523) (xy 153.52126 65.6115) (xy 153.52126 65.59777)
			(xy 153.52126 65.58404) (xy 153.52126 65.57031) (xy 153.52126 65.55657) (xy 153.52126 65.54284) (xy 153.52126 65.52911)
			(xy 153.52126 65.51538) (xy 153.52126 65.50165) (xy 153.52126 65.48791) (xy 153.52126 65.47418) (xy 153.52126 65.46045)
			(xy 153.52126 65.44672) (xy 153.52126 65.43299) (xy 153.52126 65.41925) (xy 153.52126 65.40552) (xy 153.52126 65.39179)
			(xy 153.52126 65.37806) (xy 153.52126 65.36433) (xy 153.52126 65.3506) (xy 153.52126 65.33686) (xy 153.52126 65.32313)
			(xy 153.52126 65.3094) (xy 153.52126 65.29567) (xy 153.52126 65.28194) (xy 153.52126 65.26821) (xy 153.52126 65.25447)
			(xy 153.52126 65.24074) (xy 153.52126 65.22701) (xy 153.52126 65.21328) (xy 153.52126 65.19955) (xy 153.52126 65.18582)
			(xy 153.52126 65.17208) (xy 153.52126 65.15835) (xy 153.52126 65.14462) (xy 153.52126 65.13089) (xy 153.52126 65.11716)
			(xy 153.52126 65.10343) (xy 153.52126 65.08969) (xy 153.52126 65.07596) (xy 153.52126 65.06223) (xy 153.52126 65.0485)
			(xy 153.52126 65.03477) (xy 153.52126 65.02104) (xy 153.52126 65.0073) (xy 153.52126 64.99357) (xy 153.52126 64.97984)
			(xy 153.52126 64.96611) (xy 153.52126 64.95238) (xy 153.52126 64.93864) (xy 153.52126 64.92491) (xy 153.52126 64.91118)
			(xy 153.52126 64.89745) (xy 153.52126 64.88372) (xy 153.52126 64.86998) (xy 153.52126 64.85625) (xy 153.52126 64.84252)
			(xy 153.52126 64.82879) (xy 153.52126 64.81506) (xy 153.52126 64.80133) (xy 153.52126 64.78759) (xy 153.52126 64.77386)
			(xy 153.52126 64.76013) (xy 153.52126 64.7464) (xy 153.52126 64.73267) (xy 153.52126 64.71894) (xy 153.52126 64.7052)
			(xy 153.52126 64.69147) (xy 153.52126 64.67774) (xy 153.52126 64.66401) (xy 153.52126 64.65028) (xy 153.52126 64.63655)
			(xy 153.52126 64.62281) (xy 153.52126 64.60908) (xy 153.52126 64.59535) (xy 153.52126 64.58162) (xy 153.52126 64.56789)
			(xy 153.52126 64.55416) (xy 153.52126 64.54042) (xy 153.52126 64.52669) (xy 153.52126 64.51296) (xy 153.52126 64.49923)
			(xy 153.52126 64.4855) (xy 153.52126 64.47176) (xy 153.52126 64.45803) (xy 153.52126 64.4443) (xy 153.52126 64.43057)
			(xy 153.52126 64.41684) (xy 153.52126 64.4031) (xy 153.52126 64.38937) (xy 153.52126 64.37564) (xy 153.52126 64.36191)
			(xy 153.52126 64.34818) (xy 153.52126 64.33445) (xy 153.52126 64.32071) (xy 153.52126 64.30698) (xy 153.52126 64.29325)
			(xy 153.52126 64.27952) (xy 153.52126 64.26579) (xy 153.52126 64.25206) (xy 153.52126 64.23833) (xy 153.52126 64.22459)
			(xy 153.52126 64.21086) (xy 153.52126 64.19713) (xy 153.52126 64.1834) (xy 153.80963 64.1834) (xy 153.80963 64.19713)
			(xy 153.80963 64.21086) (xy 153.80963 64.22459) (xy 153.80963 64.23833) (xy 153.80963 64.25206) (xy 153.80963 64.26579)
			(xy 153.80963 64.27952) (xy 153.80963 64.29325) (xy 153.80963 64.30698) (xy 153.80963 64.32071) (xy 153.80963 64.33445)
			(xy 153.80963 64.34818) (xy 153.80963 64.36191) (xy 153.80963 64.37564) (xy 153.80963 64.38937) (xy 153.80963 64.4031)
			(xy 153.80963 64.41684) (xy 153.80963 64.43057) (xy 153.80963 64.4443) (xy 153.80963 64.45803) (xy 153.80963 64.47176)
			(xy 153.80963 64.4855) (xy 153.80963 64.49923) (xy 153.80963 64.51296) (xy 153.80963 64.52669) (xy 153.80963 64.54042)
			(xy 153.80963 64.55416) (xy 153.80963 64.56789) (xy 153.80963 64.58162) (xy 153.80963 64.59535) (xy 153.80963 64.60908)
			(xy 153.80963 64.62281) (xy 153.80963 64.63655) (xy 153.80963 64.65028) (xy 153.80963 64.66401) (xy 153.80963 64.67774)
			(xy 153.80963 64.69147) (xy 153.80963 64.7052) (xy 153.80963 64.71894) (xy 153.80963 64.73267) (xy 153.80963 64.7464)
			(xy 153.80963 64.76013) (xy 153.80963 64.77386) (xy 153.80963 64.78759) (xy 153.80963 64.80133) (xy 153.80963 64.81506)
			(xy 153.80963 64.82879) (xy 153.80963 64.84252) (xy 153.80963 64.85625) (xy 153.80963 64.86998) (xy 153.80963 64.88372)
			(xy 153.80963 64.89745) (xy 153.80963 64.91118) (xy 153.80963 64.92491) (xy 153.80963 64.93864) (xy 153.80963 64.95238)
			(xy 153.80963 64.96611) (xy 153.80963 64.97984) (xy 153.80963 64.99357) (xy 153.80963 65.0073) (xy 153.80963 65.02104)
			(xy 153.80963 65.03477) (xy 153.80963 65.0485) (xy 153.80963 65.06223) (xy 153.80963 65.07596) (xy 153.80963 65.08969)
			(xy 153.80963 65.10343) (xy 153.80963 65.11716) (xy 153.80963 65.13089) (xy 153.80963 65.14462) (xy 153.80963 65.15835)
			(xy 153.80963 65.17208) (xy 153.80963 65.18582) (xy 153.80963 65.19955) (xy 153.80963 65.21328) (xy 153.80963 65.22701)
			(xy 153.80963 65.24074) (xy 153.80963 65.25447) (xy 153.80963 65.26821) (xy 153.80963 65.28194) (xy 153.80963 65.29567)
			(xy 153.80963 65.3094) (xy 153.80963 65.32313) (xy 153.80963 65.33686) (xy 153.80963 65.3506) (xy 153.80963 65.36433)
			(xy 153.80963 65.37806) (xy 153.80963 65.39179) (xy 153.80963 65.40552) (xy 153.80963 65.41925) (xy 153.80963 65.43299)
			(xy 153.80963 65.44672) (xy 153.80963 65.46045) (xy 153.80963 65.47418) (xy 153.80963 65.48791) (xy 153.80963 65.50165)
			(xy 153.80963 65.51538) (xy 153.80963 65.52911) (xy 153.80963 65.54284) (xy 153.80963 65.55657) (xy 153.80963 65.57031)
			(xy 153.80963 65.58404) (xy 153.80963 65.59777) (xy 153.80963 65.6115) (xy 153.80963 65.62523) (xy 153.80963 65.63896)
			(xy 153.80963 65.6527) (xy 153.80963 65.66643) (xy 153.80963 65.68016) (xy 153.80963 65.69389) (xy 153.80963 65.70762)
			(xy 153.80963 65.72135) (xy 153.80963 65.73509) (xy 153.80963 65.74882) (xy 153.80963 65.76255) (xy 153.80963 65.77628)
			(xy 153.80963 65.79001) (xy 153.80963 65.80374) (xy 153.80963 65.81748) (xy 153.80963 65.83121) (xy 153.80963 65.84494)
			(xy 153.80963 65.85867) (xy 153.80963 65.8724) (xy 153.80963 65.88613) (xy 153.80963 65.89987) (xy 153.80963 65.9136)
			(xy 153.80963 65.92733) (xy 153.80963 65.94106) (xy 153.80963 65.95479) (xy 153.80963 65.96852) (xy 153.80963 65.98226)
			(xy 153.80963 65.99599) (xy 153.80963 66.00972) (xy 153.80963 66.02345) (xy 153.80963 66.03718) (xy 153.80963 66.05092)
			(xy 153.80963 66.06465) (xy 153.80963 66.07838) (xy 153.80963 66.09211) (xy 153.80963 66.10584) (xy 153.80963 66.11958)
			(xy 153.80963 66.13331) (xy 153.80963 66.14704) (xy 153.80963 66.16077) (xy 153.80963 66.1745) (xy 153.80963 66.18823)
			(xy 153.80963 66.20197) (xy 153.80963 66.2157) (xy 153.80963 66.22943) (xy 153.80963 66.24316) (xy 153.80963 66.25689)
			(xy 153.80963 66.27062) (xy 153.80963 66.28436) (xy 153.80963 66.29809) (xy 153.80963 66.31182) (xy 153.80963 66.32555)
			(xy 153.80963 66.33928) (xy 153.80963 66.35301) (xy 153.80963 66.36675) (xy 153.80963 66.38048) (xy 153.80963 66.39421)
			(xy 153.80963 66.40794) (xy 153.80963 66.42167) (xy 153.80963 66.4354) (xy 153.80963 66.44914) (xy 153.80963 66.46287)
			(xy 153.80963 66.4766) (xy 153.80963 66.49033) (xy 153.80963 66.50406) (xy 153.80963 66.51779) (xy 153.80963 66.53153)
			(xy 153.80963 66.54526) (xy 153.80963 66.55899) (xy 153.80963 66.57272) (xy 153.80963 66.58645) (xy 153.80963 66.60019)
			(xy 153.82336 66.60019) (xy 153.82336 66.61392) (xy 153.82336 66.62765) (xy 153.83709 66.62765) (xy 153.83709 66.64138)
			(xy 153.86456 66.64138) (xy 153.86456 66.65511) (xy 154.50995 66.65511) (xy 154.50995 66.64138) (xy 154.53741 66.64138)
			(xy 154.53741 66.62765) (xy 154.55114 66.62765) (xy 154.55114 66.61392) (xy 154.56488 66.61392) (xy 154.56488 66.60019)
			(xy 154.56488 66.58645) (xy 154.56488 66.57272) (xy 154.56488 66.55899) (xy 154.56488 66.54526) (xy 154.56488 66.53153)
			(xy 154.56488 66.51779) (xy 154.56488 66.50406) (xy 154.56488 66.49033) (xy 154.56488 66.4766) (xy 154.56488 66.46287)
			(xy 154.56488 66.44914) (xy 154.56488 66.4354) (xy 154.56488 66.42167) (xy 154.56488 66.40794) (xy 154.56488 66.39421)
			(xy 154.56488 66.38048) (xy 154.56488 66.36675) (xy 154.56488 66.35301) (xy 154.56488 66.33928) (xy 154.56488 66.32555)
			(xy 154.56488 66.31182) (xy 154.56488 66.29809) (xy 154.56488 66.28436) (xy 154.56488 66.27062) (xy 154.56488 66.25689)
			(xy 154.56488 66.24316) (xy 154.56488 66.22943) (xy 154.56488 66.2157) (xy 154.56488 66.20197) (xy 154.56488 66.18823)
			(xy 154.56488 66.1745) (xy 154.56488 66.16077) (xy 154.56488 66.14704) (xy 154.56488 66.13331) (xy 154.56488 66.11958)
			(xy 154.56488 66.10584) (xy 154.56488 66.09211) (xy 154.56488 66.07838) (xy 154.56488 66.06465) (xy 154.56488 66.05092)
			(xy 154.56488 66.03718) (xy 154.56488 66.02345) (xy 154.56488 66.00972) (xy 154.56488 65.99599) (xy 154.56488 65.98226)
			(xy 154.56488 65.96852) (xy 154.56488 65.95479) (xy 154.56488 65.94106) (xy 154.56488 65.92733) (xy 154.56488 65.9136)
			(xy 154.56488 65.89987) (xy 154.56488 65.88613) (xy 154.56488 65.8724) (xy 154.56488 65.85867) (xy 154.56488 65.84494)
			(xy 154.56488 65.83121) (xy 154.56488 65.81748) (xy 154.56488 65.80374) (xy 154.56488 65.79001) (xy 154.56488 65.77628)
			(xy 154.57861 65.77628) (xy 154.57861 65.76255) (xy 154.57861 65.74882) (xy 154.60607 65.74882) (xy 154.60607 65.73509)
			(xy 155.5261 65.73509) (xy 155.5261 65.74882) (xy 155.55356 65.74882) (xy 155.55356 65.76255) (xy 155.55356 65.77628)
			(xy 155.56729 65.77628) (xy 155.56729 65.79001) (xy 155.56729 65.80374) (xy 155.56729 65.81748) (xy 155.56729 65.83121)
			(xy 155.56729 65.84494) (xy 155.56729 65.85867) (xy 155.56729 65.8724) (xy 155.56729 65.88613) (xy 155.56729 65.89987)
			(xy 155.56729 65.9136) (xy 155.56729 65.92733) (xy 155.56729 65.94106) (xy 155.56729 65.95479) (xy 155.56729 65.96852)
			(xy 155.56729 65.98226) (xy 155.56729 65.99599) (xy 155.56729 66.00972) (xy 155.56729 66.02345) (xy 155.56729 66.03718)
			(xy 155.56729 66.05092) (xy 155.56729 66.06465) (xy 155.56729 66.07838) (xy 155.56729 66.09211) (xy 155.56729 66.10584)
			(xy 155.56729 66.11958) (xy 155.56729 66.13331) (xy 155.56729 66.14704) (xy 155.56729 66.16077) (xy 155.56729 66.1745)
			(xy 155.56729 66.18823) (xy 155.56729 66.20197) (xy 155.56729 66.2157) (xy 155.56729 66.22943) (xy 155.56729 66.24316)
			(xy 155.56729 66.25689) (xy 155.56729 66.27062) (xy 155.56729 66.28436) (xy 155.56729 66.29809) (xy 155.56729 66.31182)
			(xy 155.56729 66.32555) (xy 155.56729 66.33928) (xy 155.56729 66.35301) (xy 155.56729 66.36675) (xy 155.56729 66.38048)
			(xy 155.56729 66.39421) (xy 155.56729 66.40794) (xy 155.56729 66.42167) (xy 155.56729 66.4354) (xy 155.56729 66.44914)
			(xy 155.56729 66.46287) (xy 155.56729 66.4766) (xy 155.56729 66.49033) (xy 155.56729 66.50406) (xy 155.56729 66.51779)
			(xy 155.56729 66.53153) (xy 155.56729 66.54526) (xy 155.56729 66.55899) (xy 155.56729 66.57272) (xy 155.56729 66.58645)
			(xy 155.56729 66.60019) (xy 155.58102 66.60019) (xy 155.58102 66.61392) (xy 155.58102 66.62765) (xy 155.59476 66.62765)
			(xy 155.59476 66.64138) (xy 155.62222 66.64138) (xy 155.62222 66.65511) (xy 156.26761 66.65511) (xy 156.26761 66.64138)
			(xy 156.29508 66.64138) (xy 156.29508 66.62765) (xy 156.30881 66.62765) (xy 156.30881 66.61392) (xy 156.32254 66.61392)
			(xy 156.32254 66.60019) (xy 156.32254 66.58645) (xy 156.32254 66.57272) (xy 156.32254 66.55899) (xy 156.32254 66.54526)
			(xy 156.32254 66.53153) (xy 156.32254 66.51779) (xy 156.32254 66.50406) (xy 156.32254 66.49033) (xy 156.32254 66.4766)
			(xy 156.32254 66.46287) (xy 156.32254 66.44914) (xy 156.32254 66.4354) (xy 156.32254 66.42167) (xy 156.32254 66.40794)
			(xy 156.32254 66.39421) (xy 156.32254 66.38048) (xy 156.32254 66.36675) (xy 156.32254 66.35301) (xy 156.32254 66.33928)
			(xy 156.32254 66.32555) (xy 156.32254 66.31182) (xy 156.32254 66.29809) (xy 156.32254 66.28436) (xy 156.32254 66.27062)
			(xy 156.32254 66.25689) (xy 156.32254 66.24316) (xy 156.32254 66.22943) (xy 156.32254 66.2157) (xy 156.32254 66.20197)
			(xy 156.32254 66.18823) (xy 156.32254 66.1745) (xy 156.32254 66.16077) (xy 156.32254 66.14704) (xy 156.32254 66.13331)
			(xy 156.32254 66.11958) (xy 156.32254 66.10584) (xy 156.32254 66.09211) (xy 156.32254 66.07838) (xy 156.32254 66.06465)
			(xy 156.32254 66.05092) (xy 156.32254 66.03718) (xy 156.32254 66.02345) (xy 156.32254 66.00972) (xy 156.32254 65.99599)
			(xy 156.32254 65.98226) (xy 156.32254 65.96852) (xy 156.32254 65.95479) (xy 156.32254 65.94106) (xy 156.32254 65.92733)
			(xy 156.32254 65.9136) (xy 156.32254 65.89987) (xy 156.32254 65.88613) (xy 156.32254 65.8724) (xy 156.32254 65.85867)
			(xy 156.32254 65.84494) (xy 156.32254 65.83121) (xy 156.32254 65.81748) (xy 156.32254 65.80374) (xy 156.32254 65.79001)
			(xy 156.32254 65.77628) (xy 156.32254 65.76255) (xy 156.32254 65.74882) (xy 156.32254 65.73509) (xy 156.32254 65.72135)
			(xy 156.32254 65.70762) (xy 156.32254 65.69389) (xy 156.32254 65.68016) (xy 156.32254 65.66643) (xy 156.32254 65.6527)
			(xy 156.32254 65.63896) (xy 156.32254 65.62523) (xy 156.32254 65.6115) (xy 156.32254 65.59777) (xy 156.32254 65.58404)
			(xy 156.32254 65.57031) (xy 156.32254 65.55657) (xy 156.32254 65.54284) (xy 156.32254 65.52911) (xy 156.32254 65.51538)
			(xy 156.30881 65.51538) (xy 156.30881 65.50165) (xy 156.29508 65.50165) (xy 156.29508 65.48791) (xy 156.28135 65.48791)
			(xy 156.28135 65.47418) (xy 156.26761 65.47418) (xy 156.26761 65.46045) (xy 156.25388 65.46045) (xy 156.25388 65.44672)
			(xy 156.24015 65.44672) (xy 156.24015 65.43299) (xy 156.21269 65.43299) (xy 156.21269 65.41925) (xy 156.19896 65.41925)
			(xy 156.19896 65.40552) (xy 156.18522 65.40552) (xy 156.18522 65.39179) (xy 156.17149 65.39179) (xy 156.17149 65.37806)
			(xy 156.15776 65.37806) (xy 156.15776 65.36433) (xy 156.14403 65.36433) (xy 156.14403 65.3506) (xy 156.13029 65.3506)
			(xy 156.13029 65.33686) (xy 156.11656 65.33686) (xy 156.11656 65.32313) (xy 156.10283 65.32313) (xy 156.10283 65.3094)
			(xy 156.0891 65.3094) (xy 156.0891 65.29567) (xy 156.07537 65.29567) (xy 156.07537 65.28194) (xy 156.06164 65.28194)
			(xy 156.06164 65.26821) (xy 156.0479 65.26821) (xy 156.0479 65.25447) (xy 156.03417 65.25447) (xy 156.03417 65.24074)
			(xy 156.02044 65.24074) (xy 156.02044 65.22701) (xy 156.00671 65.22701) (xy 156.00671 65.21328) (xy 155.99298 65.21328)
			(xy 155.99298 65.19955) (xy 155.97925 65.19955) (xy 155.97925 65.18582) (xy 155.96551 65.18582) (xy 155.96551 65.17208)
			(xy 155.95178 65.17208) (xy 155.95178 65.15835) (xy 155.93805 65.15835) (xy 155.93805 65.14462) (xy 155.92432 65.14462)
			(xy 155.92432 65.13089) (xy 155.91059 65.13089) (xy 155.91059 65.11716) (xy 155.89686 65.11716) (xy 155.89686 65.10343)
			(xy 155.88312 65.10343) (xy 155.88312 65.08969) (xy 155.86939 65.08969) (xy 155.86939 65.07596) (xy 155.85566 65.07596)
			(xy 155.85566 65.06223) (xy 155.84193 65.06223) (xy 155.84193 65.0485) (xy 155.8282 65.0485) (xy 155.8282 65.03477)
			(xy 155.81447 65.03477) (xy 155.81447 65.02104) (xy 155.80073 65.02104) (xy 155.80073 65.0073) (xy 155.787 65.0073)
			(xy 155.787 64.99357) (xy 155.77327 64.99357) (xy 155.77327 64.97984) (xy 155.75954 64.97984) (xy 155.75954 64.96611)
			(xy 155.74581 64.96611) (xy 155.74581 64.95238) (xy 155.73208 64.95238) (xy 155.73208 64.93864) (xy 155.71834 64.93864)
			(xy 155.71834 64.92491) (xy 155.70461 64.92491) (xy 155.70461 64.91118) (xy 155.69088 64.91118) (xy 155.69088 64.89745)
			(xy 155.67715 64.89745) (xy 155.67715 64.88372) (xy 155.66342 64.88372) (xy 155.66342 64.86998) (xy 155.64968 64.86998)
			(xy 155.64968 64.85625) (xy 155.63595 64.85625) (xy 155.63595 64.84252) (xy 155.62222 64.84252) (xy 155.62222 64.82879)
			(xy 155.60849 64.82879) (xy 155.60849 64.81506) (xy 155.59476 64.81506) (xy 155.59476 64.80133) (xy 155.58102 64.80133)
			(xy 155.58102 64.78759) (xy 155.56729 64.78759) (xy 155.56729 64.80133) (xy 155.56729 64.81506) (xy 155.56729 64.82879)
			(xy 155.56729 64.84252) (xy 155.56729 64.85625) (xy 155.56729 64.86998) (xy 155.56729 64.88372) (xy 155.56729 64.89745)
			(xy 155.56729 64.91118) (xy 155.56729 64.92491) (xy 155.56729 64.93864) (xy 155.56729 64.95238) (xy 155.56729 64.96611)
			(xy 155.56729 64.97984) (xy 155.56729 64.99357) (xy 155.56729 65.0073) (xy 155.56729 65.02104) (xy 155.56729 65.03477)
			(xy 155.56729 65.0485) (xy 155.56729 65.06223) (xy 155.56729 65.07596) (xy 155.56729 65.08969) (xy 154.56488 65.08969)
			(xy 154.56488 65.07596) (xy 154.56488 65.06223) (xy 154.56488 65.0485) (xy 154.56488 65.03477) (xy 154.56488 65.02104)
			(xy 154.56488 65.0073) (xy 154.56488 64.99357) (xy 154.56488 64.97984) (xy 154.56488 64.96611) (xy 154.56488 64.95238)
			(xy 154.56488 64.93864) (xy 154.56488 64.92491) (xy 154.56488 64.91118) (xy 154.56488 64.89745) (xy 154.56488 64.88372)
			(xy 154.56488 64.86998) (xy 154.56488 64.85625) (xy 154.56488 64.84252) (xy 154.56488 64.82879) (xy 154.56488 64.81506)
			(xy 154.56488 64.80133) (xy 154.56488 64.78759) (xy 154.56488 64.77386) (xy 154.56488 64.76013) (xy 154.56488 64.7464)
			(xy 154.56488 64.73267) (xy 154.56488 64.71894) (xy 154.56488 64.7052) (xy 154.56488 64.69147) (xy 154.56488 64.67774)
			(xy 154.56488 64.66401) (xy 154.56488 64.65028) (xy 154.56488 64.63655) (xy 154.56488 64.62281) (xy 154.56488 64.60908)
			(xy 154.56488 64.59535) (xy 154.56488 64.58162) (xy 154.56488 64.56789) (xy 154.56488 64.55416) (xy 154.56488 64.54042)
			(xy 154.56488 64.52669) (xy 154.56488 64.51296) (xy 154.56488 64.49923) (xy 154.56488 64.4855) (xy 154.56488 64.47176)
			(xy 154.56488 64.45803) (xy 154.56488 64.4443) (xy 154.56488 64.43057) (xy 154.56488 64.41684) (xy 154.56488 64.4031)
			(xy 154.56488 64.38937) (xy 154.56488 64.37564) (xy 154.56488 64.36191) (xy 154.56488 64.34818) (xy 154.56488 64.33445)
			(xy 155.18281 64.33445) (xy 155.18281 64.32071) (xy 155.16907 64.32071) (xy 155.16907 64.30698) (xy 155.15534 64.30698)
			(xy 155.15534 64.29325) (xy 155.14161 64.29325) (xy 155.14161 64.27952) (xy 155.12788 64.27952) (xy 155.12788 64.26579)
			(xy 155.11415 64.26579) (xy 155.11415 64.25206) (xy 155.10041 64.25206) (xy 155.10041 64.23833) (xy 155.08668 64.23833)
			(xy 155.08668 64.22459) (xy 155.07295 64.22459) (xy 155.07295 64.21086) (xy 155.05922 64.21086) (xy 155.05922 64.19713)
			(xy 155.04549 64.19713) (xy 155.04549 64.1834) (xy 155.03175 64.1834) (xy 155.03175 64.16967) (xy 155.01802 64.16967)
			(xy 155.01802 64.15594) (xy 155.00429 64.15594) (xy 155.00429 64.1422) (xy 154.99056 64.1422) (xy 154.99056 64.12847)
			(xy 154.97683 64.12847) (xy 154.97683 64.11474) (xy 154.9631 64.11474) (xy 154.9631 64.10101) (xy 154.94936 64.10101)
			(xy 154.94936 64.08728) (xy 154.93563 64.08728) (xy 154.93563 64.07355) (xy 154.9219 64.07355) (xy 154.9219 64.05981)
			(xy 154.90817 64.05981) (xy 154.90817 64.04608) (xy 154.89444 64.04608) (xy 154.89444 64.03235) (xy 154.88071 64.03235)
			(xy 154.88071 64.01862) (xy 154.86697 64.01862) (xy 154.86697 64.00489) (xy 154.85324 64.00489) (xy 154.85324 63.99115)
			(xy 154.83951 63.99115) (xy 154.83951 63.97742) (xy 154.82578 63.97742) (xy 154.82578 63.96369) (xy 154.81205 63.96369)
			(xy 154.81205 63.94996) (xy 154.79832 63.94996) (xy 154.79832 63.93623) (xy 154.78458 63.93623) (xy 154.78458 63.92249)
			(xy 154.77085 63.92249) (xy 154.77085 63.90876) (xy 154.75712 63.90876) (xy 154.75712 63.89503) (xy 154.74339 63.89503)
			(xy 154.74339 63.8813) (xy 154.72966 63.8813) (xy 154.72966 63.86757) (xy 154.71593 63.86757) (xy 154.71593 63.85384)
			(xy 154.70219 63.85384) (xy 154.70219 63.8401) (xy 154.68846 63.8401) (xy 154.68846 63.82637) (xy 154.67473 63.82637)
			(xy 154.67473 63.81264) (xy 154.661 63.81264) (xy 154.661 63.79891) (xy 154.64727 63.79891) (xy 154.64727 63.78518)
			(xy 154.63354 63.78518) (xy 154.63354 63.77145) (xy 154.6198 63.77145) (xy 154.6198 63.75771) (xy 154.60607 63.75771)
			(xy 154.60607 63.74398) (xy 154.59234 63.74398) (xy 154.59234 63.73025) (xy 154.57861 63.73025) (xy 154.57861 63.71652)
			(xy 154.56488 63.71652) (xy 154.56488 63.70279) (xy 154.55114 63.70279) (xy 154.55114 63.68906) (xy 154.53741 63.68906)
			(xy 154.53741 63.67532) (xy 154.52368 63.67532) (xy 154.52368 63.66159) (xy 154.33144 63.66159) (xy 154.33144 63.67532)
			(xy 154.27651 63.67532) (xy 154.27651 63.68906) (xy 154.24905 63.68906) (xy 154.24905 63.70279) (xy 154.22158 63.70279)
			(xy 154.22158 63.71652) (xy 154.20785 63.71652) (xy 154.20785 63.73025) (xy 154.19412 63.73025) (xy 154.19412 63.74398)
			(xy 154.18039 63.74398) (xy 154.18039 63.75771) (xy 154.16666 63.75771) (xy 154.16666 63.77145) (xy 154.15293 63.77145)
			(xy 154.15293 63.78518) (xy 154.13919 63.78518) (xy 154.13919 63.79891) (xy 154.12546 63.79891) (xy 154.12546 63.81264)
			(xy 154.11173 63.81264) (xy 154.11173 63.82637) (xy 154.098 63.82637) (xy 154.098 63.8401) (xy 154.08427 63.8401)
			(xy 154.08427 63.85384) (xy 154.07053 63.85384) (xy 154.07053 63.86757) (xy 154.0568 63.86757) (xy 154.0568 63.8813)
			(xy 154.04307 63.8813) (xy 154.04307 63.89503) (xy 154.02934 63.89503) (xy 154.02934 63.90876) (xy 154.01561 63.90876)
			(xy 154.01561 63.92249) (xy 154.00187 63.92249) (xy 154.00187 63.93623) (xy 153.98814 63.93623) (xy 153.98814 63.94996)
			(xy 153.97441 63.94996) (xy 153.97441 63.96369) (xy 153.96068 63.96369) (xy 153.96068 63.97742) (xy 153.94695 63.97742)
			(xy 153.94695 63.99115) (xy 153.93322 63.99115) (xy 153.93322 64.00489) (xy 153.91948 64.00489) (xy 153.91948 64.01862)
			(xy 153.90575 64.01862) (xy 153.90575 64.03235) (xy 153.89202 64.03235) (xy 153.89202 64.04608) (xy 153.87829 64.04608)
			(xy 153.87829 64.05981) (xy 153.86456 64.05981) (xy 153.86456 64.07355) (xy 153.85083 64.07355) (xy 153.85083 64.08728)
			(xy 153.83709 64.08728) (xy 153.83709 64.10101) (xy 153.83709 64.11474) (xy 153.83709 64.12847) (xy 153.82336 64.12847)
			(xy 153.82336 64.1422) (xy 153.82336 64.15594) (xy 153.82336 64.16967) (xy 153.82336 64.1834) (xy 153.80963 64.1834)
			(xy 153.52126 64.1834) (xy 153.52126 64.16967) (xy 153.52126 64.15594) (xy 153.52126 64.1422) (xy 153.52126 64.12847)
			(xy 153.52126 64.11474) (xy 153.52126 64.10101) (xy 153.52126 64.08728) (xy 153.52126 64.07355) (xy 153.52126 64.05981)
			(xy 153.52126 64.04608) (xy 153.52126 64.03235) (xy 153.52126 64.01862) (xy 153.52126 64.00489) (xy 153.52126 63.99115)
			(xy 153.52126 63.97742) (xy 153.52126 63.96369) (xy 153.52126 63.94996) (xy 153.52126 63.93623) (xy 153.52126 63.92249)
			(xy 153.52126 63.90876) (xy 153.52126 63.89503) (xy 153.52126 63.8813) (xy 153.52126 63.86757) (xy 153.52126 63.85384)
			(xy 153.52126 63.8401) (xy 153.52126 63.82637) (xy 153.52126 63.81264) (xy 153.52126 63.79891) (xy 153.52126 63.78518)
			(xy 153.52126 63.77145) (xy 153.52126 63.75771) (xy 153.52126 63.74398) (xy 153.50753 63.74398) (xy 153.50753 63.73025)
			(xy 153.50753 63.71652) (xy 153.50753 63.70279) (xy 153.4938 63.70279) (xy 153.4938 63.68906) (xy 153.48007 63.68906)
			(xy 153.48007 63.67532) (xy 153.4526 63.67532) (xy 153.4526 63.66159) (xy 151.55762 63.66159) (xy 151.55762 63.67532)
			(xy 151.48896 63.67532) (xy 151.48896 63.68906) (xy 151.44777 63.68906) (xy 151.44777 63.70279) (xy 151.4203 63.70279)
			(xy 151.4203 63.71652) (xy 151.40657 63.71652) (xy 151.40657 63.73025) (xy 151.39284 63.73025) (xy 151.39284 63.74398)
			(xy 151.37911 63.74398) (xy 151.37911 63.75771) (xy 151.36538 63.75771) (xy 151.36538 63.77145) (xy 151.35165 63.77145)
			(xy 151.35165 63.78518) (xy 151.33791 63.78518) (xy 151.33791 63.79891) (xy 151.32418 63.79891) (xy 151.32418 63.81264)
			(xy 151.31045 63.81264) (xy 151.31045 63.82637) (xy 151.29672 63.82637) (xy 151.29672 63.8401) (xy 151.28299 63.8401)
			(xy 151.28299 63.85384) (xy 151.26926 63.85384) (xy 151.26926 63.86757) (xy 151.25552 63.86757) (xy 151.25552 63.8813)
			(xy 151.24179 63.8813) (xy 151.24179 63.89503) (xy 151.22806 63.89503) (xy 151.22806 63.90876) (xy 151.21433 63.90876)
			(xy 151.21433 63.92249) (xy 151.2006 63.92249) (xy 151.2006 63.93623) (xy 151.18687 63.93623) (xy 151.18687 63.94996)
			(xy 151.17313 63.94996) (xy 151.17313 63.96369) (xy 151.1594 63.96369) (xy 151.1594 63.97742) (xy 151.14567 63.97742)
			(xy 151.14567 63.99115) (xy 151.13194 63.99115) (xy 151.13194 64.00489) (xy 151.11821 64.00489) (xy 151.11821 64.01862)
			(xy 151.10448 64.01862) (xy 151.10448 64.03235) (xy 151.09074 64.03235) (xy 151.09074 64.04608) (xy 151.07701 64.04608)
			(xy 151.07701 64.05981) (xy 151.06328 64.05981) (xy 151.06328 64.07355) (xy 151.04955 64.07355) (xy 151.04955 64.08728)
			(xy 151.03582 64.08728) (xy 151.03582 64.10101) (xy 151.03582 64.11474) (xy 151.02209 64.11474) (xy 151.02209 64.12847)
			(xy 151.02209 64.1422) (xy 151.02209 64.15594) (xy 151.00835 64.15594) (xy 151.00835 64.16967) (xy 151.00835 64.1834)
			(xy 151.00835 64.19713) (xy 151.00835 64.21086) (xy 151.00835 64.22459) (xy 151.00835 64.23833) (xy 151.00835 64.25206)
			(xy 151.00835 64.26579) (xy 151.00835 64.27952) (xy 151.00835 64.29325) (xy 151.00835 64.30698) (xy 151.00835 64.32071)
			(xy 151.00835 64.33445) (xy 151.00835 64.34818) (xy 151.00835 64.36191) (xy 151.00835 64.37564) (xy 151.00835 64.38937)
			(xy 151.00835 64.4031) (xy 151.00835 64.41684) (xy 151.00835 64.43057) (xy 151.00835 64.4443) (xy 151.00835 64.45803)
			(xy 151.00835 64.47176) (xy 151.00835 64.4855) (xy 151.00835 64.49923) (xy 151.00835 64.51296) (xy 151.00835 64.52669)
			(xy 151.00835 64.54042) (xy 151.00835 64.55416) (xy 151.00835 64.56789) (xy 151.00835 64.58162) (xy 151.00835 64.59535)
			(xy 151.00835 64.60908) (xy 151.00835 64.62281) (xy 151.00835 64.63655) (xy 151.00835 64.65028) (xy 151.00835 64.66401)
			(xy 151.00835 64.67774) (xy 151.00835 64.69147) (xy 151.00835 64.7052) (xy 151.00835 64.71894) (xy 151.00835 64.73267)
			(xy 151.00835 64.7464) (xy 151.00835 64.76013) (xy 151.00835 64.77386) (xy 151.00835 64.78759) (xy 151.00835 64.80133)
			(xy 151.00835 64.81506) (xy 151.00835 64.82879) (xy 151.00835 64.84252) (xy 151.00835 64.85625) (xy 151.00835 64.86998)
			(xy 151.00835 64.88372) (xy 151.00835 64.89745) (xy 151.00835 64.91118) (xy 151.00835 64.92491) (xy 151.00835 64.93864)
			(xy 151.00835 64.95238) (xy 151.00835 64.96611) (xy 151.00835 64.97984) (xy 151.00835 64.99357) (xy 151.00835 65.0073)
			(xy 151.00835 65.02104) (xy 151.00835 65.03477) (xy 151.00835 65.0485) (xy 151.00835 65.06223) (xy 151.00835 65.07596)
			(xy 151.00835 65.08969) (xy 151.00835 65.10343) (xy 151.00835 65.11716) (xy 151.00835 65.13089) (xy 151.00835 65.14462)
			(xy 151.00835 65.15835) (xy 151.00835 65.17208) (xy 151.00835 65.18582) (xy 151.00835 65.19955) (xy 151.00835 65.21328)
			(xy 151.00835 65.22701) (xy 151.00835 65.24074) (xy 151.02209 65.24074) (xy 151.02209 65.25447) (xy 151.02209 65.26821)
			(xy 151.03582 65.26821) (xy 151.03582 65.28194) (xy 151.03582 65.29567) (xy 151.04955 65.29567) (xy 151.04955 65.3094)
			(xy 151.06328 65.3094) (xy 151.06328 65.32313) (xy 151.07701 65.32313) (xy 151.07701 65.33686) (xy 151.09074 65.33686)
			(xy 151.09074 65.3506) (xy 151.10448 65.3506) (xy 151.10448 65.36433) (xy 151.11821 65.36433) (xy 151.11821 65.37806)
			(xy 151.11821 65.39179) (xy 151.13194 65.39179) (xy 151.13194 65.40552) (xy 151.14567 65.40552) (xy 151.14567 65.41925)
			(xy 151.1594 65.41925) (xy 151.1594 65.43299) (xy 151.17313 65.43299) (xy 151.17313 65.44672) (xy 151.18687 65.44672)
			(xy 151.18687 65.46045) (xy 151.2006 65.46045) (xy 151.2006 65.47418) (xy 151.21433 65.47418) (xy 151.21433 65.48791)
			(xy 151.22806 65.48791) (xy 151.22806 65.50165) (xy 151.24179 65.50165) (xy 151.24179 65.51538) (xy 151.25552 65.51538)
			(xy 151.25552 65.52911) (xy 151.26926 65.52911) (xy 151.26926 65.54284) (xy 151.28299 65.54284) (xy 151.28299 65.55657)
			(xy 151.29672 65.55657) (xy 151.29672 65.57031) (xy 151.31045 65.57031) (xy 151.31045 65.58404) (xy 151.32418 65.58404)
			(xy 151.32418 65.59777) (xy 151.33791 65.59777) (xy 151.33791 65.6115) (xy 151.35165 65.6115) (xy 151.35165 65.62523)
			(xy 151.36538 65.62523) (xy 151.36538 65.63896) (xy 151.37911 65.63896) (xy 151.37911 65.6527) (xy 151.39284 65.6527)
			(xy 151.39284 65.66643) (xy 151.40657 65.66643) (xy 151.40657 65.68016) (xy 151.4203 65.68016) (xy 151.4203 65.69389)
			(xy 151.43404 65.69389) (xy 151.43404 65.70762) (xy 151.43404 65.72135) (xy 151.4203 65.72135) (xy 151.4203 65.73509)
			(xy 151.40657 65.73509) (xy 151.40657 65.74882) (xy 151.40657 65.76255) (xy 151.39284 65.76255) (xy 151.39284 65.77628)
			(xy 151.39284 65.79001) (xy 151.37911 65.79001) (xy 151.37911 65.80374) (xy 151.36538 65.80374) (xy 151.36538 65.81748)
			(xy 151.36538 65.83121) (xy 151.35165 65.83121) (xy 151.35165 65.84494) (xy 151.35165 65.85867) (xy 151.33791 65.85867)
			(xy 151.33791 65.8724) (xy 151.33791 65.88613) (xy 151.32418 65.88613) (xy 151.32418 65.89987) (xy 151.31045 65.89987)
			(xy 151.31045 65.9136) (xy 151.31045 65.92733) (xy 151.29672 65.92733) (xy 151.29672 65.94106) (xy 151.29672 65.95479)
			(xy 151.28299 65.95479) (xy 151.28299 65.96852) (xy 151.26926 65.96852) (xy 151.26926 65.98226) (xy 151.26926 65.99599)
			(xy 151.25552 65.99599) (xy 151.25552 66.00972) (xy 151.25552 66.02345) (xy 151.24179 66.02345) (xy 151.24179 66.03718)
			(xy 151.22806 66.03718) (xy 151.22806 66.05092) (xy 151.22806 66.06465) (xy 151.21433 66.06465) (xy 151.21433 66.07838)
			(xy 151.21433 66.09211) (xy 151.2006 66.09211) (xy 151.2006 66.10584) (xy 151.18687 66.10584) (xy 151.18687 66.11958)
			(xy 151.18687 66.13331) (xy 151.17313 66.13331) (xy 151.17313 66.14704) (xy 151.17313 66.16077) (xy 151.1594 66.16077)
			(xy 151.1594 66.1745) (xy 151.14567 66.1745) (xy 151.14567 66.18823) (xy 151.14567 66.20197) (xy 151.13194 66.20197)
			(xy 151.13194 66.2157) (xy 151.13194 66.22943) (xy 151.11821 66.22943) (xy 151.11821 66.24316) (xy 151.10448 66.24316)
			(xy 151.10448 66.25689) (xy 151.10448 66.27062) (xy 151.09074 66.27062) (xy 151.09074 66.28436) (xy 151.09074 66.29809)
			(xy 151.07701 66.29809) (xy 151.07701 66.31182) (xy 151.06328 66.31182) (xy 151.06328 66.32555) (xy 151.06328 66.33928)
			(xy 151.04955 66.33928) (xy 151.04955 66.35301) (xy 151.04955 66.36675) (xy 151.03582 66.36675) (xy 151.03582 66.38048)
			(xy 151.02209 66.38048) (xy 151.02209 66.39421) (xy 151.02209 66.40794) (xy 151.00835 66.40794) (xy 151.00835 66.42167)
			(xy 151.00835 66.4354) (xy 150.99462 66.4354) (xy 150.99462 66.44914) (xy 150.98089 66.44914) (xy 150.98089 66.46287)
			(xy 150.98089 66.4766) (xy 150.96716 66.4766) (xy 150.96716 66.49033) (xy 150.96716 66.50406) (xy 150.95343 66.50406)
			(xy 150.95343 66.51779) (xy 150.93969 66.51779) (xy 150.93969 66.53153) (xy 150.93969 66.54526) (xy 150.92596 66.54526)
			(xy 150.92596 66.55899) (xy 150.92596 66.57272) (xy 150.91223 66.57272) (xy 150.91223 66.58645) (xy 150.8985 66.58645)
			(xy 150.5964 66.58645) (xy 150.5964 66.57272) (xy 150.5964 66.55899) (xy 150.5964 66.54526) (xy 150.5964 66.53153)
			(xy 150.5964 66.51779) (xy 150.5964 66.50406) (xy 150.5964 66.49033) (xy 150.5964 66.4766) (xy 150.5964 66.46287)
			(xy 150.5964 66.44914) (xy 150.5964 66.4354) (xy 150.5964 66.42167) (xy 150.5964 66.40794) (xy 150.5964 66.39421)
			(xy 150.5964 66.38048) (xy 150.5964 66.36675) (xy 150.5964 66.35301) (xy 150.5964 66.33928) (xy 150.5964 66.32555)
			(xy 150.5964 66.31182) (xy 150.5964 66.29809) (xy 150.5964 66.28436) (xy 150.5964 66.27062) (xy 150.5964 66.25689)
			(xy 150.5964 66.24316) (xy 150.5964 66.22943) (xy 150.5964 66.2157) (xy 150.5964 66.20197) (xy 150.5964 66.18823)
			(xy 150.5964 66.1745) (xy 150.5964 66.16077) (xy 150.5964 66.14704) (xy 150.5964 66.13331) (xy 150.5964 66.11958)
			(xy 150.5964 66.10584) (xy 150.5964 66.09211) (xy 150.5964 66.07838) (xy 150.5964 66.06465) (xy 150.5964 66.05092)
			(xy 150.5964 66.03718) (xy 150.5964 66.02345) (xy 150.5964 66.00972) (xy 150.5964 65.99599) (xy 150.5964 65.98226)
			(xy 150.5964 65.96852) (xy 150.5964 65.95479) (xy 150.5964 65.94106) (xy 150.5964 65.92733) (xy 150.5964 65.9136)
			(xy 150.5964 65.89987) (xy 150.5964 65.88613) (xy 150.5964 65.8724) (xy 150.5964 65.85867) (xy 150.5964 65.84494)
			(xy 150.5964 65.83121) (xy 150.5964 65.81748) (xy 150.5964 65.80374) (xy 150.5964 65.79001) (xy 150.5964 65.77628)
			(xy 150.5964 65.76255) (xy 150.5964 65.74882) (xy 150.5964 65.73509) (xy 150.5964 65.72135) (xy 150.5964 65.70762)
			(xy 150.5964 65.69389) (xy 150.5964 65.68016) (xy 150.5964 65.66643) (xy 150.5964 65.6527) (xy 150.5964 65.63896)
			(xy 150.5964 65.62523) (xy 150.5964 65.6115) (xy 150.5964 65.59777) (xy 150.5964 65.58404) (xy 150.5964 65.57031)
			(xy 150.5964 65.55657) (xy 150.5964 65.54284) (xy 150.5964 65.52911) (xy 150.5964 65.51538) (xy 150.5964 65.50165)
			(xy 150.5964 65.48791) (xy 150.5964 65.47418) (xy 150.5964 65.46045) (xy 150.5964 65.44672) (xy 150.5964 65.43299)
			(xy 150.5964 65.41925) (xy 150.5964 65.40552) (xy 150.5964 65.39179) (xy 150.5964 65.37806) (xy 150.5964 65.36433)
			(xy 150.5964 65.3506) (xy 150.5964 65.33686) (xy 150.5964 65.32313) (xy 150.5964 65.3094) (xy 150.5964 65.29567)
			(xy 150.5964 65.28194) (xy 150.5964 65.26821) (xy 150.5964 65.25447) (xy 150.5964 65.24074) (xy 150.5964 65.22701)
			(xy 150.5964 65.21328) (xy 150.5964 65.19955) (xy 150.5964 65.18582) (xy 150.5964 65.17208) (xy 150.5964 65.15835)
			(xy 150.5964 65.14462) (xy 150.5964 65.13089) (xy 150.5964 65.11716) (xy 150.5964 65.10343) (xy 150.5964 65.08969)
			(xy 150.5964 65.07596) (xy 150.5964 65.06223) (xy 150.5964 65.0485) (xy 150.5964 65.03477) (xy 150.5964 65.02104)
			(xy 150.5964 65.0073) (xy 150.5964 64.99357) (xy 150.5964 64.97984) (xy 150.5964 64.96611) (xy 150.5964 64.95238)
			(xy 150.5964 64.93864) (xy 150.5964 64.92491) (xy 150.5964 64.91118) (xy 150.5964 64.89745) (xy 150.5964 64.88372)
			(xy 150.5964 64.86998) (xy 150.5964 64.85625) (xy 150.5964 64.84252) (xy 150.5964 64.82879) (xy 150.5964 64.81506)
			(xy 150.5964 64.80133) (xy 150.5964 64.78759) (xy 150.5964 64.77386) (xy 150.5964 64.76013) (xy 150.5964 64.7464)
			(xy 150.5964 64.73267) (xy 150.5964 64.71894) (xy 150.5964 64.7052) (xy 150.5964 64.69147) (xy 150.5964 64.67774)
			(xy 150.5964 64.66401) (xy 150.5964 64.65028) (xy 150.5964 64.63655) (xy 150.5964 64.62281) (xy 150.5964 64.60908)
			(xy 150.5964 64.59535) (xy 150.5964 64.58162) (xy 150.5964 64.56789) (xy 150.5964 64.55416) (xy 150.5964 64.54042)
			(xy 150.5964 64.52669) (xy 150.5964 64.51296) (xy 150.5964 64.49923) (xy 150.5964 64.4855) (xy 150.5964 64.47176)
			(xy 150.5964 64.45803) (xy 150.5964 64.4443) (xy 150.5964 64.43057) (xy 150.5964 64.41684) (xy 150.5964 64.4031)
			(xy 150.5964 64.38937) (xy 150.5964 64.37564) (xy 150.5964 64.36191) (xy 150.5964 64.34818) (xy 150.5964 64.33445)
			(xy 150.5964 64.32071) (xy 150.5964 64.30698) (xy 150.5964 64.29325) (xy 150.5964 64.27952) (xy 150.5964 64.26579)
			(xy 150.5964 64.25206) (xy 150.5964 64.23833) (xy 150.5964 64.22459) (xy 150.5964 64.21086) (xy 150.5964 64.19713)
			(xy 150.5964 64.1834) (xy 150.5964 64.16967) (xy 150.5964 64.15594) (xy 150.5964 64.1422) (xy 150.5964 64.12847)
			(xy 150.5964 64.11474) (xy 150.5964 64.10101) (xy 150.5964 64.08728) (xy 150.5964 64.07355) (xy 150.5964 64.05981)
			(xy 150.5964 64.04608) (xy 150.5964 64.03235) (xy 150.5964 64.01862) (xy 150.5964 64.00489) (xy 150.5964 63.99115)
			(xy 150.5964 63.97742) (xy 150.5964 63.96369) (xy 150.5964 63.94996) (xy 150.5964 63.93623) (xy 150.5964 63.92249)
			(xy 150.5964 63.90876) (xy 150.5964 63.89503) (xy 150.5964 63.8813) (xy 150.5964 63.86757) (xy 150.5964 63.85384)
			(xy 150.5964 63.8401) (xy 150.5964 63.82637) (xy 150.5964 63.81264) (xy 150.5964 63.79891) (xy 150.5964 63.78518)
			(xy 150.5964 63.77145) (xy 150.5964 63.75771) (xy 150.5964 63.74398) (xy 150.5964 63.73025) (xy 150.5964 63.71652)
			(xy 150.58267 63.71652) (xy 150.58267 63.70279) (xy 150.56894 63.70279) (xy 150.56894 63.68906) (xy 150.55521 63.68906)
			(xy 150.55521 63.67532) (xy 150.52774 63.67532) (xy 150.52774 63.66159) (xy 148.63276 63.66159) (xy 148.63276 63.67532)
			(xy 148.5641 63.67532) (xy 148.5641 63.68906) (xy 148.52291 63.68906) (xy 148.52291 63.70279) (xy 148.50917 63.70279)
			(xy 148.50917 63.71652) (xy 148.49544 63.71652) (xy 148.49544 63.73025) (xy 148.48171 63.73025) (xy 148.48171 63.74398)
			(xy 148.46798 63.74398) (xy 148.46798 63.75771) (xy 148.45425 63.75771) (xy 148.45425 63.77145) (xy 148.44052 63.77145)
			(xy 148.44052 63.78518) (xy 148.42678 63.78518) (xy 148.42678 63.79891) (xy 148.41305 63.79891) (xy 148.41305 63.81264)
			(xy 148.39932 63.81264) (xy 148.39932 63.82637) (xy 148.38559 63.82637) (xy 148.38559 63.8401) (xy 148.37186 63.8401)
			(xy 148.37186 63.85384) (xy 148.35813 63.85384) (xy 148.35813 63.86757) (xy 148.34439 63.86757) (xy 148.34439 63.8813)
			(xy 148.33066 63.8813) (xy 148.33066 63.89503) (xy 148.31693 63.89503) (xy 148.31693 63.90876) (xy 148.3032 63.90876)
			(xy 148.3032 63.92249) (xy 148.28947 63.92249) (xy 148.28947 63.93623) (xy 148.27573 63.93623) (xy 148.27573 63.94996)
			(xy 148.262 63.94996) (xy 148.262 63.96369) (xy 148.24827 63.96369) (xy 148.24827 63.97742) (xy 148.23454 63.97742)
			(xy 148.23454 63.99115) (xy 148.22081 63.99115) (xy 148.22081 64.00489) (xy 148.20707 64.00489) (xy 148.20707 64.01862)
			(xy 148.19334 64.01862) (xy 148.19334 64.03235) (xy 148.17961 64.03235) (xy 148.17961 64.04608) (xy 148.16588 64.04608)
			(xy 148.16588 64.05981) (xy 148.15215 64.05981) (xy 148.15215 64.07355) (xy 148.13842 64.07355) (xy 148.13842 64.08728)
			(xy 148.12468 64.08728) (xy 148.12468 64.10101) (xy 148.11095 64.10101) (xy 148.11095 64.11474) (xy 148.11095 64.12847)
			(xy 148.09722 64.12847) (xy 148.09722 64.1422) (xy 148.09722 64.15594) (xy 148.09722 64.16967) (xy 148.09722 64.1834)
			(xy 148.08349 64.1834) (xy 144.65055 64.1834) (xy 144.65055 64.16967) (xy 144.67802 64.16967) (xy 144.67802 64.15594)
			(xy 144.71921 64.15594) (xy 144.71921 64.1422) (xy 144.74668 64.1422) (xy 144.74668 64.12847) (xy 144.76041 64.12847)
			(xy 144.76041 64.11474) (xy 144.78787 64.11474) (xy 144.78787 64.10101) (xy 144.81533 64.10101) (xy 144.81533 64.08728)
			(xy 144.82907 64.08728) (xy 144.82907 64.07355) (xy 144.85653 64.07355) (xy 144.85653 64.05981) (xy 144.87026 64.05981)
			(xy 144.87026 64.04608) (xy 144.88399 64.04608) (xy 144.88399 64.03235) (xy 144.91146 64.03235) (xy 144.91146 64.01862)
			(xy 144.92519 64.01862) (xy 144.92519 64.00489) (xy 144.93892 64.00489) (xy 144.93892 63.99115) (xy 144.95265 63.99115)
			(xy 144.95265 63.97742) (xy 144.96638 63.97742) (xy 144.96638 63.96369) (xy 144.98011 63.96369) (xy 144.98011 63.94996)
			(xy 144.99385 63.94996) (xy 144.99385 63.93623) (xy 145.00758 63.93623) (xy 145.00758 63.92249) (xy 145.02131 63.92249)
			(xy 145.02131 63.90876) (xy 145.03504 63.90876) (xy 145.03504 63.89503) (xy 145.03504 63.8813) (xy 145.04877 63.8813)
			(xy 145.04877 63.86757) (xy 145.0625 63.86757) (xy 145.0625 63.85384) (xy 145.07624 63.85384) (xy 145.07624 63.8401)
			(xy 145.07624 63.82637) (xy 145.08997 63.82637) (xy 145.08997 63.81264) (xy 145.1037 63.81264) (xy 145.1037 63.79891)
			(xy 145.1037 63.78518) (xy 145.11743 63.78518) (xy 145.11743 63.77145) (xy 145.11743 63.75771) (xy 145.13116 63.75771)
			(xy 145.13116 63.74398) (xy 145.13116 63.73025) (xy 145.1449 63.73025) (xy 145.1449 63.71652) (xy 145.1449 63.70279)
			(xy 145.15863 63.70279) (xy 145.15863 63.68906) (xy 145.15863 63.67532) (xy 145.17236 63.67532) (xy 145.17236 63.66159)
			(xy 145.17236 63.64786) (xy 145.17236 63.63413) (xy 145.18609 63.63413) (xy 145.18609 63.6204) (xy 145.18609 63.60667)
			(xy 145.18609 63.59293) (xy 145.19982 63.59293) (xy 145.19982 63.5792) (xy 145.19982 63.56547) (xy 145.19982 63.55174)
			(xy 145.19982 63.53801) (xy 145.21356 63.53801) (xy 145.21356 63.52428) (xy 145.21356 63.51054) (xy 145.21356 63.49681)
			(xy 145.21356 63.48308) (xy 145.21356 63.46935) (xy 145.21356 63.45562) (xy 145.22729 63.45562) (xy 145.22729 63.44188)
			(xy 145.22729 63.42815) (xy 145.22729 63.41442) (xy 145.22729 63.40069) (xy 145.22729 63.38696) (xy 145.22729 63.37322)
			(xy 145.22729 63.35949) (xy 145.22729 63.34576) (xy 145.22729 63.33203) (xy 145.22729 63.3183) (xy 145.22729 63.30457)
			(xy 145.22729 63.29083) (xy 145.22729 63.2771) (xy 145.22729 63.26337) (xy 145.22729 63.24964) (xy 145.22729 63.23591)
			(xy 149.75876 63.23591) (xy 149.75876 63.24964) (xy 149.75876 63.26337) (xy 149.75876 63.2771) (xy 149.77249 63.2771)
			(xy 149.77249 63.29083) (xy 149.75876 63.29083) (xy 149.75876 63.30457) (xy 149.75876 63.3183) (xy 149.75876 63.33203)
			(xy 149.75876 63.34576) (xy 149.75876 63.35949) (xy 149.75876 63.37322) (xy 149.75876 63.38696) (xy 149.75876 63.40069)
			(xy 149.75876 63.41442) (xy 149.75876 63.42815) (xy 149.75876 63.44188) (xy 149.75876 63.45562) (xy 149.92355 63.45562)
			(xy 149.92355 63.44188) (xy 149.92355 63.42815) (xy 149.92355 63.41442) (xy 149.92355 63.40069) (xy 149.92355 63.38696)
			(xy 149.92355 63.37322) (xy 149.92355 63.35949) (xy 149.92355 63.34576) (xy 149.92355 63.33203) (xy 149.92355 63.3183)
			(xy 149.92355 63.30457) (xy 149.93728 63.30457) (xy 149.93728 63.29083) (xy 149.93728 63.2771) (xy 149.93728 63.26337)
			(xy 149.93728 63.24964) (xy 149.93728 63.23591) (xy 149.93728 63.22218) (xy 149.93728 63.20844) (xy 149.93728 63.19471)
			(xy 149.93728 63.18098) (xy 149.93728 63.16725) (xy 149.93728 63.15352) (xy 149.93728 63.13979) (xy 149.93728 63.12605)
			(xy 149.93728 63.11232) (xy 149.93728 63.09859) (xy 149.93728 63.08486) (xy 149.93728 63.07113) (xy 149.95101 63.07113)
			(xy 149.95101 63.0574) (xy 149.95101 63.04366) (xy 149.95101 63.02993) (xy 149.95101 63.0162) (xy 149.95101 63.00247)
			(xy 149.95101 62.98874) (xy 149.95101 62.97501) (xy 149.95101 62.96127) (xy 149.95101 62.94754) (xy 149.96474 62.94754)
			(xy 149.96474 62.93381) (xy 149.96474 62.92008) (xy 149.96474 62.90635) (xy 149.96474 62.89261) (xy 149.96474 62.87888)
			(xy 149.96474 62.86515) (xy 149.96474 62.85142) (xy 149.96474 62.83769) (xy 149.96474 62.82395) (xy 149.97847 62.82395)
			(xy 149.97847 62.81022) (xy 149.97847 62.79649) (xy 149.97847 62.78276) (xy 149.97847 62.76903) (xy 149.97847 62.7553)
			(xy 149.97847 62.74156) (xy 149.97847 62.72783) (xy 149.9922 62.72783) (xy 149.9922 62.7141) (xy 149.9922 62.70037)
			(xy 149.9922 62.68664) (xy 149.9922 62.67291) (xy 149.9922 62.65917) (xy 149.9922 62.64544) (xy 150.00594 62.64544)
			(xy 150.00594 62.63171) (xy 150.00594 62.61798) (xy 150.00594 62.60425) (xy 150.00594 62.59052) (xy 150.00594 62.57678)
			(xy 150.01967 62.57678) (xy 150.01967 62.56305) (xy 150.01967 62.54932) (xy 150.01967 62.53559) (xy 150.01967 62.52186)
			(xy 150.01967 62.50813) (xy 150.01967 62.49439) (xy 150.0334 62.49439) (xy 150.0334 62.48066) (xy 150.0334 62.46693)
			(xy 150.0334 62.4532) (xy 150.0334 62.43947) (xy 150.04713 62.43947) (xy 150.04713 62.42574) (xy 150.04713 62.412)
			(xy 150.04713 62.39827) (xy 150.04713 62.38454) (xy 150.04713 62.37081) (xy 150.06086 62.37081) (xy 150.06086 62.35708)
			(xy 150.06086 62.34334) (xy 150.06086 62.32961) (xy 150.06086 62.31588) (xy 150.07459 62.31588) (xy 150.07459 62.30215)
			(xy 150.07459 62.28842) (xy 150.07459 62.27468) (xy 150.07459 62.26095) (xy 150.08833 62.26095) (xy 150.08833 62.24722)
			(xy 150.08833 62.23349) (xy 150.08833 62.21976) (xy 150.08833 62.20603) (xy 150.10206 62.20603) (xy 150.10206 62.19229)
			(xy 150.10206 62.17856) (xy 150.10206 62.16483) (xy 150.10206 62.1511) (xy 150.11579 62.1511) (xy 150.11579 62.13737)
			(xy 150.11579 62.12364) (xy 150.11579 62.1099) (xy 150.12952 62.1099) (xy 150.12952 62.09617) (xy 150.12952 62.08244)
			(xy 150.12952 62.06871) (xy 150.12952 62.05498) (xy 150.14325 62.05498) (xy 150.14325 62.04125) (xy 150.14325 62.02751)
			(xy 150.14325 62.01378) (xy 150.15698 62.01378) (xy 150.15698 62.00005) (xy 150.15698 61.98632) (xy 150.15698 61.97259)
			(xy 150.17072 61.97259) (xy 150.17072 61.95886) (xy 150.17072 61.94512) (xy 150.17072 61.93139) (xy 150.17072 61.91766)
			(xy 150.18445 61.91766) (xy 150.18445 61.90393) (xy 150.18445 61.8902) (xy 150.18445 61.87646) (xy 150.19818 61.87646)
			(xy 150.19818 61.86273) (xy 150.19818 61.849) (xy 150.19818 61.83527) (xy 150.21191 61.83527) (xy 150.21191 61.82154)
			(xy 150.21191 61.8078) (xy 150.22564 61.8078) (xy 150.22564 61.79407) (xy 150.22564 61.78034) (xy 150.22564 61.76661)
			(xy 150.23937 61.76661) (xy 150.23937 61.75288) (xy 150.23937 61.73915) (xy 150.23937 61.72541) (xy 150.25311 61.72541)
			(xy 150.25311 61.71168) (xy 150.25311 61.69795) (xy 150.25311 61.68422) (xy 150.26684 61.68422) (xy 150.26684 61.67049)
			(xy 150.26684 61.65676) (xy 150.28057 61.65676) (xy 150.28057 61.64302) (xy 150.28057 61.62929) (xy 150.28057 61.61556)
			(xy 150.2943 61.61556) (xy 150.2943 61.60183) (xy 150.2943 61.5881) (xy 150.30803 61.5881) (xy 150.30803 61.57437)
			(xy 150.30803 61.56063) (xy 150.30803 61.5469) (xy 150.32176 61.5469) (xy 150.32176 61.53317) (xy 150.32176 61.51944)
			(xy 150.3355 61.51944) (xy 150.3355 61.50571) (xy 150.3355 61.49198) (xy 150.34923 61.49198) (xy 150.34923 61.47824)
			(xy 150.34923 61.46451) (xy 150.34923 61.45078) (xy 150.36296 61.45078) (xy 150.36296 61.43705) (xy 150.36296 61.42332)
			(xy 150.37669 61.42332) (xy 150.37669 61.40959) (xy 150.37669 61.39585) (xy 150.39042 61.39585) (xy 150.39042 61.38212)
			(xy 150.39042 61.36839) (xy 150.40416 61.36839) (xy 150.40416 61.35466) (xy 150.40416 61.34093) (xy 150.41789 61.34093)
			(xy 150.41789 61.32719) (xy 150.41789 61.31346) (xy 150.43162 61.31346) (xy 150.43162 61.29973) (xy 150.43162 61.286)
			(xy 150.43162 61.27227) (xy 150.44535 61.27227) (xy 150.44535 61.25853) (xy 150.44535 61.2448) (xy 150.45908 61.2448)
			(xy 150.45908 61.23107) (xy 150.45908 61.21734) (xy 150.47282 61.21734) (xy 150.47282 61.20361) (xy 150.47282 61.18988)
			(xy 150.48655 61.18988) (xy 150.48655 61.17614) (xy 150.48655 61.16241) (xy 150.50028 61.16241) (xy 150.50028 61.14868)
			(xy 150.51401 61.14868) (xy 150.51401 61.13495) (xy 150.51401 61.12122) (xy 150.52774 61.12122) (xy 150.52774 61.10749)
			(xy 150.52774 61.09375) (xy 150.54147 61.09375) (xy 150.54147 61.08002) (xy 150.54147 61.06629) (xy 150.55521 61.06629)
			(xy 150.55521 61.05256) (xy 150.55521 61.03883) (xy 150.56894 61.03883) (xy 150.56894 61.0251) (xy 150.56894 61.01136)
			(xy 150.58267 61.01136) (xy 150.58267 60.99763) (xy 150.5964 60.99763) (xy 150.5964 60.9839) (xy 150.5964 60.97017)
			(xy 150.61013 60.97017) (xy 150.61013 60.95644) (xy 150.61013 60.94271) (xy 150.62386 60.94271) (xy 150.62386 60.92897)
			(xy 150.62386 60.91524) (xy 150.6376 60.91524) (xy 150.6376 60.90151) (xy 150.65133 60.90151) (xy 150.65133 60.88778)
			(xy 150.65133 60.87405) (xy 150.66506 60.87405) (xy 150.66506 60.86032) (xy 150.66506 60.84658) (xy 150.67879 60.84658)
			(xy 150.67879 60.83285) (xy 150.69252 60.83285) (xy 150.69252 60.81912) (xy 150.69252 60.80539) (xy 150.70625 60.80539)
			(xy 150.70625 60.79166) (xy 150.70625 60.77792) (xy 150.71999 60.77792) (xy 150.71999 60.76419) (xy 150.73372 60.76419)
			(xy 150.73372 60.75046) (xy 150.73372 60.73673) (xy 150.74745 60.73673) (xy 150.74745 60.723) (xy 150.76118 60.723)
			(xy 150.76118 60.70926) (xy 150.76118 60.69553) (xy 150.77491 60.69553) (xy 150.77491 60.6818) (xy 150.78864 60.6818)
			(xy 150.78864 60.66807) (xy 150.78864 60.65434) (xy 150.80238 60.65434) (xy 150.80238 60.64061) (xy 150.81611 60.64061)
			(xy 150.81611 60.62687) (xy 150.81611 60.61314) (xy 150.82984 60.61314) (xy 150.82984 60.59941) (xy 150.84357 60.59941)
			(xy 150.84357 60.58568) (xy 150.84357 60.57195) (xy 150.8573 60.57195) (xy 150.8573 60.55822) (xy 150.87103 60.55822)
			(xy 150.87103 60.54448) (xy 150.88477 60.54448) (xy 150.88477 60.53075) (xy 150.88477 60.51702) (xy 150.8985 60.51702)
			(xy 150.8985 60.50329) (xy 150.91223 60.50329) (xy 150.91223 60.48956) (xy 152.16182 60.48956) (xy 152.16182 60.50329)
			(xy 152.16182 60.51702) (xy 152.16182 60.53075) (xy 152.16182 60.54448) (xy 152.16182 60.55822) (xy 152.16182 60.57195)
			(xy 152.16182 60.58568) (xy 152.16182 60.59941) (xy 152.16182 60.61314) (xy 152.16182 60.62687) (xy 152.16182 60.64061)
			(xy 152.16182 60.65434) (xy 152.16182 60.66807) (xy 152.16182 60.6818) (xy 152.16182 60.69553) (xy 152.16182 60.70926)
			(xy 152.16182 60.723) (xy 152.16182 60.73673) (xy 152.16182 60.75046) (xy 152.16182 60.76419) (xy 152.16182 60.77792)
			(xy 152.16182 60.79166) (xy 152.16182 60.80539) (xy 152.16182 60.81912) (xy 152.16182 60.83285) (xy 152.16182 60.84658)
			(xy 152.16182 60.86032) (xy 152.16182 60.87405) (xy 152.16182 60.88778) (xy 152.16182 60.90151) (xy 152.16182 60.91524)
			(xy 152.16182 60.92897) (xy 152.16182 60.94271) (xy 152.16182 60.95644) (xy 152.16182 60.97017) (xy 152.16182 60.9839)
			(xy 152.16182 60.99763) (xy 152.16182 61.01136) (xy 152.16182 61.0251) (xy 152.16182 61.03883) (xy 152.16182 61.05256)
			(xy 152.16182 61.06629) (xy 152.16182 61.08002) (xy 152.17555 61.08002) (xy 152.17555 61.09375) (xy 152.18928 61.09375)
			(xy 152.18928 61.10749) (xy 152.20302 61.10749) (xy 152.20302 61.12122) (xy 153.68605 61.12122) (xy 153.68605 61.13495)
			(xy 153.69978 61.13495) (xy 153.69978 61.14868) (xy 153.69978 61.16241) (xy 153.69978 61.17614) (xy 153.69978 61.18988)
			(xy 153.69978 61.20361) (xy 153.69978 61.21734) (xy 153.69978 61.23107) (xy 153.69978 61.2448) (xy 153.69978 61.25853)
			(xy 153.69978 61.27227) (xy 153.69978 61.286) (xy 153.69978 61.29973) (xy 153.69978 61.31346) (xy 153.69978 61.32719)
			(xy 153.69978 61.34093) (xy 153.69978 61.35466) (xy 153.69978 61.36839) (xy 153.69978 61.38212) (xy 153.69978 61.39585)
			(xy 153.69978 61.40959) (xy 153.69978 61.42332) (xy 153.69978 61.43705) (xy 153.69978 61.45078) (xy 153.69978 61.46451)
			(xy 153.69978 61.47824) (xy 153.69978 61.49198) (xy 153.69978 61.50571) (xy 153.69978 61.51944) (xy 153.69978 61.53317)
			(xy 153.69978 61.5469) (xy 153.69978 61.56063) (xy 153.69978 61.57437) (xy 153.69978 61.5881) (xy 153.69978 61.60183)
			(xy 153.69978 61.61556) (xy 153.68605 61.61556) (xy 153.68605 61.62929) (xy 152.42272 61.62929) (xy 152.42272 61.64302)
			(xy 152.39526 61.64302) (xy 152.39526 61.65676) (xy 152.39526 61.67049) (xy 152.38153 61.67049) (xy 152.38153 61.68422)
			(xy 152.38153 61.69795) (xy 152.38153 61.71168) (xy 152.38153 61.72541) (xy 152.38153 61.73915) (xy 152.38153 61.75288)
			(xy 152.38153 61.76661) (xy 152.38153 61.78034) (xy 152.38153 61.79407) (xy 152.38153 61.8078) (xy 152.38153 61.82154)
			(xy 152.38153 61.83527) (xy 152.38153 61.849) (xy 152.38153 61.86273) (xy 152.38153 61.87646) (xy 152.38153 61.8902)
			(xy 152.38153 61.90393) (xy 152.38153 61.91766) (xy 152.38153 61.93139) (xy 152.38153 61.94512) (xy 152.38153 61.95886)
			(xy 152.38153 61.97259) (xy 152.38153 61.98632) (xy 152.38153 62.00005) (xy 152.38153 62.01378) (xy 152.38153 62.02751)
			(xy 152.38153 62.04125) (xy 152.38153 62.05498) (xy 152.38153 62.06871) (xy 152.38153 62.08244) (xy 152.38153 62.09617)
			(xy 152.38153 62.1099) (xy 152.38153 62.12364) (xy 152.38153 62.13737) (xy 152.38153 62.1511) (xy 152.38153 62.16483)
			(xy 152.38153 62.17856) (xy 152.39526 62.17856) (xy 152.39526 62.19229) (xy 152.39526 62.20603) (xy 152.42272 62.20603)
			(xy 152.42272 62.21976) (xy 153.68605 62.21976) (xy 153.68605 62.23349) (xy 153.69978 62.23349) (xy 153.69978 62.24722)
			(xy 153.69978 62.26095) (xy 153.69978 62.27468) (xy 153.69978 62.28842) (xy 153.69978 62.30215) (xy 153.69978 62.31588)
			(xy 153.69978 62.32961) (xy 153.69978 62.34334) (xy 153.69978 62.35708) (xy 153.69978 62.37081) (xy 153.69978 62.38454)
			(xy 153.69978 62.39827) (xy 153.69978 62.412) (xy 153.69978 62.42574) (xy 153.69978 62.43947) (xy 153.69978 62.4532)
			(xy 153.69978 62.46693) (xy 153.69978 62.48066) (xy 153.69978 62.49439) (xy 153.69978 62.50813) (xy 153.69978 62.52186)
			(xy 153.69978 62.53559) (xy 153.69978 62.54932) (xy 153.69978 62.56305) (xy 153.69978 62.57678) (xy 153.69978 62.59052)
			(xy 153.69978 62.60425) (xy 153.69978 62.61798) (xy 153.69978 62.63171) (xy 153.69978 62.64544) (xy 153.69978 62.65917)
			(xy 153.69978 62.67291) (xy 153.69978 62.68664) (xy 153.69978 62.70037) (xy 153.68605 62.70037) (xy 153.68605 62.7141)
			(xy 152.21675 62.7141) (xy 152.21675 62.72783) (xy 152.18928 62.72783) (xy 152.18928 62.74156) (xy 152.17555 62.74156)
			(xy 152.17555 62.7553) (xy 152.17555 62.76903) (xy 152.16182 62.76903) (xy 152.16182 62.78276) (xy 152.16182 62.79649)
			(xy 152.16182 62.81022) (xy 152.16182 62.82395) (xy 152.16182 62.83769) (xy 152.16182 62.85142) (xy 152.16182 62.86515)
			(xy 152.16182 62.87888) (xy 152.16182 62.89261) (xy 152.16182 62.90635) (xy 152.16182 62.92008) (xy 152.16182 62.93381)
			(xy 152.16182 62.94754) (xy 152.16182 62.96127) (xy 152.16182 62.97501) (xy 152.16182 62.98874) (xy 152.16182 63.00247)
			(xy 152.16182 63.0162) (xy 152.16182 63.02993) (xy 152.16182 63.04366) (xy 152.16182 63.0574) (xy 152.16182 63.07113)
			(xy 152.16182 63.08486) (xy 152.16182 63.09859) (xy 152.16182 63.11232) (xy 152.16182 63.12605) (xy 152.16182 63.13979)
			(xy 152.16182 63.15352) (xy 152.16182 63.16725) (xy 152.16182 63.18098) (xy 152.16182 63.19471) (xy 152.16182 63.20844)
			(xy 152.16182 63.22218) (xy 152.16182 63.23591) (xy 152.16182 63.24964) (xy 152.16182 63.26337) (xy 152.16182 63.2771)
			(xy 152.16182 63.29083) (xy 152.16182 63.30457) (xy 152.16182 63.3183) (xy 152.16182 63.33203) (xy 152.16182 63.34576)
			(xy 152.16182 63.35949) (xy 152.17555 63.35949) (xy 152.17555 63.37322) (xy 152.17555 63.38696) (xy 152.18928 63.38696)
			(xy 152.18928 63.40069) (xy 152.20302 63.40069) (xy 152.20302 63.41442) (xy 153.94695 63.41442) (xy 153.94695 63.40069)
			(xy 154.00187 63.40069) (xy 154.00187 63.38696) (xy 154.02934 63.38696) (xy 154.02934 63.37322) (xy 154.04307 63.37322)
			(xy 154.04307 63.35949) (xy 154.0568 63.35949) (xy 154.0568 63.34576) (xy 154.07053 63.34576) (xy 154.07053 63.33203)
			(xy 154.08427 63.33203) (xy 154.08427 63.3183) (xy 154.098 63.3183) (xy 154.098 63.30457) (xy 154.11173 63.30457)
			(xy 154.11173 63.29083) (xy 154.12546 63.29083) (xy 154.12546 63.2771) (xy 154.13919 63.2771) (xy 154.13919 63.26337)
			(xy 154.15293 63.26337) (xy 154.15293 63.24964) (xy 154.16666 63.24964) (xy 154.16666 63.23591) (xy 154.18039 63.23591)
			(xy 154.18039 63.22218) (xy 154.19412 63.22218) (xy 154.19412 63.20844) (xy 154.20785 63.20844) (xy 154.20785 63.19471)
			(xy 154.22158 63.19471) (xy 154.22158 63.18098) (xy 154.23532 63.18098) (xy 154.23532 63.16725) (xy 154.24905 63.16725)
			(xy 154.24905 63.15352) (xy 154.26278 63.15352) (xy 154.26278 63.13979) (xy 154.27651 63.13979) (xy 154.27651 63.12605)
			(xy 154.29024 63.12605) (xy 154.29024 63.11232) (xy 154.30397 63.11232) (xy 154.30397 63.09859) (xy 154.3177 63.09859)
			(xy 154.3177 63.08486) (xy 154.33144 63.08486) (xy 154.33144 63.07113) (xy 154.34517 63.07113) (xy 154.34517 63.0574)
			(xy 154.3589 63.0574) (xy 154.3589 63.04366) (xy 154.37263 63.04366) (xy 154.37263 63.02993) (xy 154.38636 63.02993)
			(xy 154.38636 63.0162) (xy 154.40009 63.0162) (xy 154.40009 63.00247) (xy 154.41383 63.00247) (xy 154.41383 62.98874)
			(xy 154.41383 62.97501) (xy 154.42756 62.97501) (xy 154.42756 62.96127) (xy 154.42756 62.94754) (xy 154.44129 62.94754)
			(xy 154.44129 62.93381) (xy 154.44129 62.92008) (xy 154.44129 62.90635) (xy 154.44129 62.89261) (xy 154.44129 62.87888)
			(xy 154.45502 62.87888) (xy 154.45502 62.86515) (xy 154.45502 62.85142) (xy 154.45502 62.83769) (xy 154.45502 62.82395)
			(xy 154.45502 62.81022) (xy 154.45502 62.79649) (xy 154.45502 62.78276) (xy 154.45502 62.76903) (xy 154.45502 62.7553)
			(xy 154.45502 62.74156) (xy 154.45502 62.72783) (xy 154.45502 62.7141) (xy 154.45502 62.70037) (xy 154.45502 62.68664)
			(xy 154.45502 62.67291) (xy 154.45502 62.65917) (xy 154.45502 62.64544) (xy 154.45502 62.63171) (xy 154.45502 62.61798)
			(xy 154.45502 62.60425) (xy 154.45502 62.59052) (xy 154.45502 62.57678) (xy 154.45502 62.56305) (xy 154.45502 62.54932)
			(xy 154.45502 62.53559) (xy 154.45502 62.52186) (xy 154.45502 62.50813) (xy 154.45502 62.49439) (xy 154.45502 62.48066)
			(xy 154.45502 62.46693) (xy 154.45502 62.4532) (xy 154.45502 62.43947) (xy 154.45502 62.42574) (xy 154.45502 62.412)
			(xy 154.45502 62.39827) (xy 154.45502 62.38454) (xy 154.45502 62.37081) (xy 154.45502 62.35708) (xy 154.45502 62.34334)
			(xy 154.45502 62.32961) (xy 154.45502 62.31588) (xy 154.45502 62.30215) (xy 154.45502 62.28842) (xy 154.45502 62.27468)
			(xy 154.45502 62.26095) (xy 154.45502 62.24722) (xy 154.45502 62.23349) (xy 154.45502 62.21976) (xy 154.45502 62.20603)
			(xy 154.45502 62.19229) (xy 154.45502 62.17856) (xy 154.45502 62.16483) (xy 154.45502 62.1511) (xy 154.45502 62.13737)
			(xy 154.45502 62.12364) (xy 154.45502 62.1099) (xy 154.45502 62.09617) (xy 154.45502 62.08244) (xy 154.45502 62.06871)
			(xy 154.45502 62.05498) (xy 154.45502 62.04125) (xy 154.45502 62.02751) (xy 154.45502 62.01378) (xy 154.45502 62.00005)
			(xy 154.45502 61.98632) (xy 154.45502 61.97259) (xy 154.45502 61.95886) (xy 154.45502 61.94512) (xy 154.45502 61.93139)
			(xy 154.45502 61.91766) (xy 154.45502 61.90393) (xy 154.45502 61.8902) (xy 154.45502 61.87646) (xy 154.45502 61.86273)
			(xy 154.45502 61.849) (xy 154.45502 61.83527) (xy 154.45502 61.82154) (xy 154.45502 61.8078) (xy 154.45502 61.79407)
			(xy 154.45502 61.78034) (xy 154.45502 61.76661) (xy 154.45502 61.75288) (xy 154.45502 61.73915) (xy 154.45502 61.72541)
			(xy 154.45502 61.71168) (xy 154.45502 61.69795) (xy 154.45502 61.68422) (xy 154.45502 61.67049) (xy 154.45502 61.65676)
			(xy 154.45502 61.64302) (xy 154.45502 61.62929) (xy 154.45502 61.61556) (xy 154.45502 61.60183) (xy 154.45502 61.5881)
			(xy 154.45502 61.57437) (xy 154.45502 61.56063) (xy 154.45502 61.5469) (xy 154.45502 61.53317) (xy 154.45502 61.51944)
			(xy 154.45502 61.50571) (xy 154.45502 61.49198) (xy 154.45502 61.47824) (xy 154.45502 61.46451) (xy 154.45502 61.45078)
			(xy 154.45502 61.43705) (xy 154.45502 61.42332) (xy 154.45502 61.40959) (xy 154.45502 61.39585) (xy 154.45502 61.38212)
			(xy 154.45502 61.36839) (xy 154.45502 61.35466) (xy 154.45502 61.34093) (xy 154.45502 61.32719) (xy 154.45502 61.31346)
			(xy 154.45502 61.29973) (xy 154.45502 61.286) (xy 154.45502 61.27227) (xy 154.45502 61.25853) (xy 154.45502 61.2448)
			(xy 154.45502 61.23107) (xy 154.45502 61.21734) (xy 154.45502 61.20361) (xy 154.45502 61.18988) (xy 154.45502 61.17614)
			(xy 154.45502 61.16241) (xy 154.45502 61.14868) (xy 154.45502 61.13495) (xy 154.45502 61.12122) (xy 154.45502 61.10749)
			(xy 154.45502 61.09375) (xy 154.45502 61.08002) (xy 154.45502 61.06629) (xy 154.45502 61.05256) (xy 154.45502 61.03883)
			(xy 154.45502 61.0251) (xy 154.45502 61.01136) (xy 154.45502 60.99763) (xy 154.45502 60.9839) (xy 154.45502 60.97017)
			(xy 154.44129 60.97017) (xy 154.44129 60.95644) (xy 154.44129 60.94271) (xy 154.44129 60.92897) (xy 154.44129 60.91524)
			(xy 154.44129 60.90151) (xy 154.42756 60.90151) (xy 154.42756 60.88778) (xy 154.42756 60.87405) (xy 154.42756 60.86032)
			(xy 154.41383 60.86032) (xy 154.41383 60.84658) (xy 154.40009 60.84658) (xy 154.40009 60.83285) (xy 154.38636 60.83285)
			(xy 154.38636 60.81912) (xy 154.37263 60.81912) (xy 154.37263 60.80539) (xy 154.3589 60.80539) (xy 154.3589 60.79166)
			(xy 154.34517 60.79166) (xy 154.34517 60.77792) (xy 154.33144 60.77792) (xy 154.33144 60.76419) (xy 154.3177 60.76419)
			(xy 154.3177 60.75046) (xy 154.30397 60.75046) (xy 154.30397 60.73673) (xy 154.29024 60.73673) (xy 154.29024 60.723)
			(xy 154.27651 60.723) (xy 154.27651 60.70926) (xy 154.26278 60.70926) (xy 154.26278 60.69553) (xy 154.24905 60.69553)
			(xy 154.24905 60.6818) (xy 154.23532 60.6818) (xy 154.23532 60.66807) (xy 154.22158 60.66807) (xy 154.22158 60.65434)
			(xy 154.20785 60.65434) (xy 154.20785 60.64061) (xy 154.19412 60.64061) (xy 154.19412 60.62687) (xy 154.18039 60.62687)
			(xy 154.18039 60.61314) (xy 154.16666 60.61314) (xy 154.16666 60.59941) (xy 154.15293 60.59941) (xy 154.15293 60.58568)
			(xy 154.13919 60.58568) (xy 154.13919 60.57195) (xy 154.12546 60.57195) (xy 154.12546 60.55822) (xy 154.11173 60.55822)
			(xy 154.11173 60.54448) (xy 154.098 60.54448) (xy 154.098 60.53075) (xy 154.08427 60.53075) (xy 154.08427 60.51702)
			(xy 154.07053 60.51702) (xy 154.07053 60.50329) (xy 154.0568 60.50329) (xy 154.0568 60.48956) (xy 154.04307 60.48956)
			(xy 154.04307 60.47583) (xy 154.02934 60.47583) (xy 154.02934 60.46209) (xy 154.00187 60.46209) (xy 154.00187 60.44836)
			(xy 153.96068 60.44836) (xy 153.96068 60.43463) (xy 153.89202 60.43463) (xy 153.89202 60.4209) (xy 152.28541 60.4209)
			(xy 152.28541 60.43463) (xy 152.27167 60.43463) (xy 152.27167 60.4209) (xy 152.23048 60.4209) (xy 152.23048 60.43463)
			(xy 152.20302 60.43463) (xy 152.20302 60.44836) (xy 152.18928 60.44836) (xy 152.18928 60.46209) (xy 152.17555 60.46209)
			(xy 152.17555 60.47583) (xy 152.17555 60.48956) (xy 152.16182 60.48956) (xy 150.91223 60.48956) (xy 150.91223 60.47583)
			(xy 150.92596 60.47583) (xy 150.92596 60.46209) (xy 150.93969 60.46209) (xy 150.93969 60.44836) (xy 150.95343 60.44836)
			(xy 150.95343 60.43463) (xy 150.95343 60.4209) (xy 150.96716 60.4209) (xy 150.96716 60.40717) (xy 150.98089 60.40717)
			(xy 150.98089 60.39344) (xy 150.99462 60.39344) (xy 150.99462 60.3797) (xy 150.99462 60.36597) (xy 151.00835 60.36597)
			(xy 151.00835 60.35224) (xy 151.02209 60.35224) (xy 151.02209 60.33851) (xy 151.03582 60.33851) (xy 151.03582 60.32478)
			(xy 151.04955 60.32478) (xy 151.04955 60.31105) (xy 151.04955 60.29731) (xy 151.06328 60.29731) (xy 151.06328 60.28358)
			(xy 151.07701 60.28358) (xy 151.07701 60.26985) (xy 151.09074 60.26985) (xy 151.09074 60.25612) (xy 151.10448 60.25612)
			(xy 151.10448 60.24239) (xy 151.10448 60.22865) (xy 151.11821 60.22865) (xy 151.11821 60.21492) (xy 151.13194 60.21492)
			(xy 151.13194 60.20119) (xy 151.14567 60.20119) (xy 151.14567 60.18746) (xy 151.1594 60.18746) (xy 151.1594 60.17373)
			(xy 151.17313 60.17373) (xy 151.17313 60.15999) (xy 151.18687 60.15999) (xy 151.18687 60.14626) (xy 151.18687 60.13253)
			(xy 151.2006 60.13253) (xy 151.2006 60.1188) (xy 151.21433 60.1188) (xy 151.21433 60.10507) (xy 151.22806 60.10507)
			(xy 151.22806 60.09134) (xy 151.24179 60.09134) (xy 151.24179 60.0776) (xy 151.25552 60.0776) (xy 151.25552 60.06387)
			(xy 151.26926 60.06387) (xy 151.26926 60.05014) (xy 151.28299 60.05014) (xy 151.28299 60.03641) (xy 151.29672 60.03641)
			(xy 151.29672 60.02268) (xy 151.31045 60.02268) (xy 151.31045 60.00895) (xy 151.31045 59.99521) (xy 151.32418 59.99521)
			(xy 151.32418 59.98148) (xy 151.33791 59.98148) (xy 151.33791 59.96775) (xy 151.35165 59.96775) (xy 151.35165 59.95402)
			(xy 151.36538 59.95402) (xy 151.36538 59.94029) (xy 151.37911 59.94029) (xy 151.37911 59.92656) (xy 151.39284 59.92656)
			(xy 151.39284 59.91282) (xy 151.40657 59.91282) (xy 151.40657 59.89909) (xy 151.4203 59.89909) (xy 151.4203 59.88536)
			(xy 151.43404 59.88536) (xy 151.43404 59.87163) (xy 151.44777 59.87163) (xy 151.44777 59.8579) (xy 151.4615 59.8579)
			(xy 151.4615 59.84417) (xy 151.47523 59.84417) (xy 151.47523 59.83043) (xy 151.48896 59.83043) (xy 151.48896 59.8167)
			(xy 151.5027 59.8167) (xy 151.5027 59.80297) (xy 151.51643 59.80297) (xy 151.51643 59.78924) (xy 151.53016 59.78924)
			(xy 151.53016 59.77551) (xy 151.54389 59.77551) (xy 151.54389 59.76177) (xy 151.57136 59.76177) (xy 151.57136 59.74804)
			(xy 151.58509 59.74804) (xy 151.58509 59.73431) (xy 151.59882 59.73431) (xy 151.59882 59.72058) (xy 151.61255 59.72058)
			(xy 151.61255 59.70685) (xy 151.62628 59.70685) (xy 151.62628 59.69311) (xy 151.64001 59.69311) (xy 151.64001 59.67938)
			(xy 151.65375 59.67938) (xy 151.65375 59.66565) (xy 151.66748 59.66565) (xy 151.66748 59.65192) (xy 151.68121 59.65192)
			(xy 151.68121 59.63819) (xy 151.70867 59.63819) (xy 151.70867 59.62446) (xy 151.7224 59.62446) (xy 151.7224 59.61072)
			(xy 151.73614 59.61072) (xy 151.73614 59.59699) (xy 151.74987 59.59699) (xy 151.74987 59.58326) (xy 151.7636 59.58326)
			(xy 151.7636 59.56953) (xy 151.77733 59.56953) (xy 151.77733 59.5558) (xy 151.80479 59.5558) (xy 151.80479 59.54207)
			(xy 151.81853 59.54207) (xy 151.81853 59.52833) (xy 151.83226 59.52833) (xy 151.83226 59.5146) (xy 151.84599 59.5146)
			(xy 151.84599 59.50087) (xy 151.87345 59.50087) (xy 151.87345 59.48714) (xy 151.88718 59.48714) (xy 151.88718 59.47341)
			(xy 151.90092 59.47341) (xy 151.90092 59.45968) (xy 151.91465 59.45968) (xy 151.91465 59.44594) (xy 151.94211 59.44594)
			(xy 151.94211 59.43221) (xy 151.95584 59.43221) (xy 151.95584 59.41848) (xy 151.96958 59.41848) (xy 151.96958 59.40475)
			(xy 151.99704 59.40475) (xy 151.99704 59.39102) (xy 152.01077 59.39102) (xy 152.01077 59.37729) (xy 152.0245 59.37729)
			(xy 152.0245 59.36355) (xy 152.05197 59.36355) (xy 152.05197 59.34982) (xy 152.0657 59.34982) (xy 152.0657 59.33609)
			(xy 152.09316 59.33609) (xy 152.09316 59.32236) (xy 152.10689 59.32236) (xy 152.10689 59.30863) (xy 152.12063 59.30863)
			(xy 152.12063 59.2949) (xy 152.14809 59.2949) (xy 152.14809 59.28116) (xy 152.16182 59.28116) (xy 154.78458 59.28116)
			(xy 154.78458 59.2949) (xy 154.78458 59.30863) (xy 154.78458 59.32236) (xy 154.78458 59.33609) (xy 154.78458 59.34982)
			(xy 154.78458 59.36355) (xy 154.78458 59.37729) (xy 154.78458 59.39102) (xy 154.78458 59.40475) (xy 154.78458 59.41848)
			(xy 154.78458 59.43221) (xy 154.78458 59.44594) (xy 154.78458 59.45968) (xy 154.78458 59.47341) (xy 154.78458 59.48714)
			(xy 154.78458 59.50087) (xy 154.78458 59.5146) (xy 154.78458 59.52833) (xy 154.78458 59.54207) (xy 154.78458 59.5558)
			(xy 154.78458 59.56953) (xy 154.78458 59.58326) (xy 154.78458 59.59699) (xy 154.78458 59.61072) (xy 154.78458 59.62446)
			(xy 154.78458 59.63819) (xy 154.78458 59.65192) (xy 154.78458 59.66565) (xy 154.78458 59.67938) (xy 154.78458 59.69311)
			(xy 154.78458 59.70685) (xy 154.78458 59.72058) (xy 154.78458 59.73431) (xy 154.78458 59.74804) (xy 154.78458 59.76177)
			(xy 154.78458 59.77551) (xy 154.78458 59.78924) (xy 154.78458 59.80297) (xy 154.78458 59.8167) (xy 154.78458 59.83043)
			(xy 154.78458 59.84417) (xy 154.78458 59.8579) (xy 154.78458 59.87163) (xy 154.78458 59.88536) (xy 154.78458 59.89909)
			(xy 154.78458 59.91282) (xy 154.78458 59.92656) (xy 154.78458 59.94029) (xy 154.78458 59.95402) (xy 154.78458 59.96775)
			(xy 154.78458 59.98148) (xy 154.78458 59.99521) (xy 154.78458 60.00895) (xy 154.78458 60.02268) (xy 154.78458 60.03641)
			(xy 154.78458 60.05014) (xy 154.78458 60.06387) (xy 154.78458 60.0776) (xy 154.78458 60.09134) (xy 154.78458 60.10507)
			(xy 154.78458 60.1188) (xy 154.78458 60.13253) (xy 154.78458 60.14626) (xy 154.78458 60.15999) (xy 154.78458 60.17373)
			(xy 154.78458 60.18746) (xy 154.78458 60.20119) (xy 154.78458 60.21492) (xy 154.78458 60.22865) (xy 154.78458 60.24239)
			(xy 154.78458 60.25612) (xy 154.78458 60.26985) (xy 154.78458 60.28358) (xy 154.78458 60.29731) (xy 154.78458 60.31105)
			(xy 154.78458 60.32478) (xy 154.78458 60.33851) (xy 154.78458 60.35224) (xy 154.78458 60.36597) (xy 154.78458 60.3797)
			(xy 154.78458 60.39344) (xy 154.78458 60.40717) (xy 154.78458 60.4209) (xy 154.78458 60.43463) (xy 154.78458 60.44836)
			(xy 154.78458 60.46209) (xy 154.78458 60.47583) (xy 154.78458 60.48956) (xy 154.78458 60.50329) (xy 154.78458 60.51702)
			(xy 154.78458 60.53075) (xy 154.78458 60.54448) (xy 154.78458 60.55822) (xy 154.78458 60.57195) (xy 154.78458 60.58568)
			(xy 154.78458 60.59941) (xy 154.78458 60.61314) (xy 154.78458 60.62687) (xy 154.78458 60.64061) (xy 154.78458 60.65434)
			(xy 154.78458 60.66807) (xy 154.78458 60.6818) (xy 154.78458 60.69553) (xy 154.78458 60.70926) (xy 154.78458 60.723)
			(xy 154.78458 60.73673) (xy 154.78458 60.75046) (xy 154.78458 60.76419) (xy 154.78458 60.77792) (xy 154.78458 60.79166)
			(xy 154.78458 60.80539) (xy 154.78458 60.81912) (xy 154.78458 60.83285) (xy 154.78458 60.84658) (xy 154.78458 60.86032)
			(xy 154.78458 60.87405) (xy 154.78458 60.88778) (xy 154.78458 60.90151) (xy 154.78458 60.91524) (xy 154.78458 60.92897)
			(xy 154.78458 60.94271) (xy 154.78458 60.95644) (xy 154.78458 60.97017) (xy 154.78458 60.9839) (xy 154.78458 60.99763)
			(xy 154.78458 61.01136) (xy 154.78458 61.0251) (xy 154.78458 61.03883) (xy 154.78458 61.05256) (xy 154.78458 61.06629)
			(xy 154.78458 61.08002) (xy 154.78458 61.09375) (xy 154.78458 61.10749) (xy 154.78458 61.12122) (xy 154.78458 61.13495)
			(xy 154.78458 61.14868) (xy 154.78458 61.16241) (xy 154.78458 61.17614) (xy 154.78458 61.18988) (xy 154.78458 61.20361)
			(xy 154.78458 61.21734) (xy 154.78458 61.23107) (xy 154.78458 61.2448) (xy 154.78458 61.25853) (xy 154.78458 61.27227)
			(xy 154.78458 61.286) (xy 154.78458 61.29973) (xy 154.78458 61.31346) (xy 154.78458 61.32719) (xy 154.78458 61.34093)
			(xy 154.78458 61.35466) (xy 154.78458 61.36839) (xy 154.78458 61.38212) (xy 154.78458 61.39585) (xy 154.78458 61.40959)
			(xy 154.78458 61.42332) (xy 154.78458 61.43705) (xy 154.78458 61.45078) (xy 154.78458 61.46451) (xy 154.78458 61.47824)
			(xy 154.78458 61.49198) (xy 154.78458 61.50571) (xy 154.78458 61.51944) (xy 154.78458 61.53317) (xy 154.78458 61.5469)
			(xy 154.78458 61.56063) (xy 154.78458 61.57437) (xy 154.78458 61.5881) (xy 154.78458 61.60183) (xy 154.78458 61.61556)
			(xy 154.78458 61.62929) (xy 154.78458 61.64302) (xy 154.78458 61.65676) (xy 154.78458 61.67049) (xy 154.78458 61.68422)
			(xy 154.78458 61.69795) (xy 154.78458 61.71168) (xy 154.78458 61.72541) (xy 154.78458 61.73915) (xy 154.78458 61.75288)
			(xy 154.78458 61.76661) (xy 154.78458 61.78034) (xy 154.78458 61.79407) (xy 154.78458 61.8078) (xy 154.78458 61.82154)
			(xy 154.78458 61.83527) (xy 154.78458 61.849) (xy 154.78458 61.86273) (xy 154.78458 61.87646) (xy 154.78458 61.8902)
			(xy 154.78458 61.90393) (xy 154.78458 61.91766) (xy 154.78458 61.93139) (xy 154.78458 61.94512) (xy 154.78458 61.95886)
			(xy 154.78458 61.97259) (xy 154.78458 61.98632) (xy 154.78458 62.00005) (xy 154.78458 62.01378) (xy 154.78458 62.02751)
			(xy 154.78458 62.04125) (xy 154.78458 62.05498) (xy 154.78458 62.06871) (xy 154.78458 62.08244) (xy 154.78458 62.09617)
			(xy 154.78458 62.1099) (xy 154.78458 62.12364) (xy 154.78458 62.13737) (xy 154.78458 62.1511) (xy 154.78458 62.16483)
			(xy 154.78458 62.17856) (xy 154.78458 62.19229) (xy 154.78458 62.20603) (xy 154.78458 62.21976) (xy 154.78458 62.23349)
			(xy 154.78458 62.24722) (xy 154.78458 62.26095) (xy 154.78458 62.27468) (xy 154.78458 62.28842) (xy 154.78458 62.30215)
			(xy 154.78458 62.31588) (xy 154.78458 62.32961) (xy 154.78458 62.34334) (xy 154.78458 62.35708) (xy 154.78458 62.37081)
			(xy 154.78458 62.38454) (xy 154.78458 62.39827) (xy 154.78458 62.412) (xy 154.78458 62.42574) (xy 154.78458 62.43947)
			(xy 154.78458 62.4532) (xy 154.78458 62.46693) (xy 154.78458 62.48066) (xy 154.78458 62.49439) (xy 154.78458 62.50813)
			(xy 154.78458 62.52186) (xy 154.78458 62.53559) (xy 154.78458 62.54932) (xy 154.78458 62.56305) (xy 154.78458 62.57678)
			(xy 154.78458 62.59052) (xy 154.78458 62.60425) (xy 154.78458 62.61798) (xy 154.78458 62.63171) (xy 154.78458 62.64544)
			(xy 154.78458 62.65917) (xy 154.78458 62.67291) (xy 154.78458 62.68664) (xy 154.78458 62.70037) (xy 154.78458 62.7141)
			(xy 154.78458 62.72783) (xy 154.78458 62.74156) (xy 154.78458 62.7553) (xy 154.78458 62.76903) (xy 154.78458 62.78276)
			(xy 154.78458 62.79649) (xy 154.78458 62.81022) (xy 154.78458 62.82395) (xy 154.78458 62.83769) (xy 154.78458 62.85142)
			(xy 154.78458 62.86515) (xy 154.78458 62.87888) (xy 154.78458 62.89261) (xy 154.78458 62.90635) (xy 154.78458 62.92008)
			(xy 154.78458 62.93381) (xy 154.78458 62.94754) (xy 154.78458 62.96127) (xy 154.78458 62.97501) (xy 154.78458 62.98874)
			(xy 154.78458 63.00247) (xy 154.78458 63.0162) (xy 154.78458 63.02993) (xy 154.78458 63.04366) (xy 154.78458 63.0574)
			(xy 154.78458 63.07113) (xy 154.78458 63.08486) (xy 154.78458 63.09859) (xy 154.78458 63.11232) (xy 154.78458 63.12605)
			(xy 154.78458 63.13979) (xy 154.78458 63.15352) (xy 154.78458 63.16725) (xy 154.78458 63.18098) (xy 154.78458 63.19471)
			(xy 154.78458 63.20844) (xy 154.78458 63.22218) (xy 154.78458 63.23591) (xy 154.78458 63.24964) (xy 154.78458 63.26337)
			(xy 154.78458 63.2771) (xy 154.78458 63.29083) (xy 154.78458 63.30457) (xy 154.78458 63.3183) (xy 154.78458 63.33203)
			(xy 154.78458 63.34576) (xy 154.78458 63.35949) (xy 154.78458 63.37322) (xy 154.78458 63.38696) (xy 154.78458 63.40069)
			(xy 154.78458 63.41442) (xy 154.78458 63.42815) (xy 154.78458 63.44188) (xy 154.78458 63.45562) (xy 154.78458 63.46935)
			(xy 154.78458 63.48308) (xy 154.78458 63.49681) (xy 154.78458 63.51054) (xy 154.78458 63.52428) (xy 154.78458 63.53801)
			(xy 154.78458 63.55174) (xy 154.79832 63.55174) (xy 154.79832 63.56547) (xy 154.79832 63.5792) (xy 154.79832 63.59293)
			(xy 154.79832 63.60667) (xy 154.81205 63.60667) (xy 154.81205 63.6204) (xy 154.81205 63.63413) (xy 154.82578 63.63413)
			(xy 154.82578 63.64786) (xy 154.82578 63.66159) (xy 154.83951 63.66159) (xy 154.83951 63.67532) (xy 154.83951 63.68906)
			(xy 154.85324 63.68906) (xy 154.85324 63.70279) (xy 154.86697 63.70279) (xy 154.86697 63.71652) (xy 154.86697 63.73025)
			(xy 154.88071 63.73025) (xy 154.88071 63.74398) (xy 154.89444 63.74398) (xy 154.89444 63.75771) (xy 154.90817 63.75771)
			(xy 154.90817 63.77145) (xy 154.9219 63.77145) (xy 154.9219 63.78518) (xy 154.93563 63.78518) (xy 154.93563 63.79891)
			(xy 154.94936 63.79891) (xy 154.94936 63.81264) (xy 154.9631 63.81264) (xy 154.9631 63.82637) (xy 154.97683 63.82637)
			(xy 154.97683 63.8401) (xy 154.99056 63.8401) (xy 154.99056 63.85384) (xy 155.00429 63.85384) (xy 155.00429 63.86757)
			(xy 155.01802 63.86757) (xy 155.01802 63.8813) (xy 155.03175 63.8813) (xy 155.03175 63.89503) (xy 155.04549 63.89503)
			(xy 155.04549 63.90876) (xy 155.05922 63.90876) (xy 155.05922 63.92249) (xy 155.07295 63.92249) (xy 155.07295 63.93623)
			(xy 155.08668 63.93623) (xy 155.08668 63.94996) (xy 155.10041 63.94996) (xy 155.10041 63.96369) (xy 155.11415 63.96369)
			(xy 155.11415 63.97742) (xy 155.12788 63.97742) (xy 155.12788 63.99115) (xy 155.14161 63.99115) (xy 155.14161 64.00489)
			(xy 155.15534 64.00489) (xy 155.15534 64.01862) (xy 155.16907 64.01862) (xy 155.16907 64.03235) (xy 155.18281 64.03235)
			(xy 155.18281 64.04608) (xy 155.19654 64.04608) (xy 155.19654 64.05981) (xy 155.21027 64.05981) (xy 155.21027 64.07355)
			(xy 155.224 64.07355) (xy 155.224 64.08728) (xy 155.23773 64.08728) (xy 155.23773 64.10101) (xy 155.25146 64.10101)
			(xy 155.25146 64.11474) (xy 155.2652 64.11474) (xy 155.2652 64.12847) (xy 155.27893 64.12847) (xy 155.27893 64.1422)
			(xy 155.30639 64.1422) (xy 155.30639 64.15594) (xy 155.32012 64.15594) (xy 155.32012 64.16967) (xy 155.33385 64.16967)
			(xy 155.33385 64.1834) (xy 155.34759 64.1834) (xy 155.34759 64.19713) (xy 155.36132 64.19713) (xy 155.36132 64.21086)
			(xy 155.37505 64.21086) (xy 155.37505 64.22459) (xy 155.38878 64.22459) (xy 155.38878 64.23833) (xy 155.40251 64.23833)
			(xy 155.40251 64.25206) (xy 155.41624 64.25206) (xy 155.41624 64.26579) (xy 155.42998 64.26579) (xy 155.42998 64.27952)
			(xy 155.44371 64.27952) (xy 155.44371 64.29325) (xy 155.45744 64.29325) (xy 155.45744 64.30698) (xy 155.47117 64.30698)
			(xy 155.47117 64.32071) (xy 155.4849 64.32071) (xy 155.4849 64.33445) (xy 155.49863 64.33445) (xy 155.49863 64.34818)
			(xy 155.51237 64.34818) (xy 155.51237 64.36191) (xy 155.5261 64.36191) (xy 155.5261 64.37564) (xy 155.53983 64.37564)
			(xy 155.53983 64.38937) (xy 155.55356 64.38937) (xy 155.55356 64.4031) (xy 155.56729 64.4031) (xy 155.56729 64.41684)
			(xy 155.58102 64.41684) (xy 155.58102 64.43057) (xy 155.59476 64.43057) (xy 155.59476 64.4443) (xy 155.60849 64.4443)
			(xy 155.60849 64.45803) (xy 155.62222 64.45803) (xy 155.62222 64.47176) (xy 155.63595 64.47176) (xy 155.63595 64.4855)
			(xy 155.64968 64.4855) (xy 155.64968 64.49923) (xy 155.66342 64.49923) (xy 155.66342 64.51296) (xy 155.67715 64.51296)
			(xy 155.67715 64.52669) (xy 155.69088 64.52669) (xy 155.69088 64.54042) (xy 155.70461 64.54042) (xy 155.70461 64.55416)
			(xy 155.71834 64.55416) (xy 155.71834 64.56789) (xy 155.73208 64.56789) (xy 155.73208 64.58162) (xy 155.74581 64.58162)
			(xy 155.74581 64.59535) (xy 155.75954 64.59535) (xy 155.75954 64.60908) (xy 155.77327 64.60908) (xy 155.77327 64.62281)
			(xy 155.787 64.62281) (xy 155.787 64.63655) (xy 155.80073 64.63655) (xy 155.80073 64.65028) (xy 155.81447 64.65028)
			(xy 155.81447 64.66401) (xy 155.8282 64.66401) (xy 155.8282 64.67774) (xy 155.84193 64.67774) (xy 155.84193 64.69147)
			(xy 155.85566 64.69147) (xy 155.85566 64.7052) (xy 155.86939 64.7052) (xy 155.86939 64.71894) (xy 155.88312 64.71894)
			(xy 155.88312 64.73267) (xy 155.89686 64.73267) (xy 155.89686 64.7464) (xy 155.91059 64.7464) (xy 155.91059 64.76013)
			(xy 155.92432 64.76013) (xy 155.92432 64.77386) (xy 155.93805 64.77386) (xy 155.93805 64.78759) (xy 155.95178 64.78759)
			(xy 155.95178 64.80133) (xy 155.96551 64.80133) (xy 155.96551 64.81506) (xy 155.97925 64.81506) (xy 155.97925 64.82879)
			(xy 155.99298 64.82879) (xy 155.99298 64.84252) (xy 156.00671 64.84252) (xy 156.00671 64.85625) (xy 156.02044 64.85625)
			(xy 156.02044 64.86998) (xy 156.03417 64.86998) (xy 156.03417 64.88372) (xy 156.0479 64.88372) (xy 156.0479 64.89745)
			(xy 156.06164 64.89745) (xy 156.06164 64.91118) (xy 156.07537 64.91118) (xy 156.07537 64.92491) (xy 156.0891 64.92491)
			(xy 156.0891 64.93864) (xy 156.10283 64.93864) (xy 156.10283 64.95238) (xy 156.11656 64.95238) (xy 156.11656 64.96611)
			(xy 156.13029 64.96611) (xy 156.13029 64.97984) (xy 156.14403 64.97984) (xy 156.14403 64.99357) (xy 156.15776 64.99357)
			(xy 156.15776 65.0073) (xy 156.17149 65.0073) (xy 156.17149 65.02104) (xy 156.18522 65.02104) (xy 156.18522 65.03477)
			(xy 156.19896 65.03477) (xy 156.19896 65.0485) (xy 156.21269 65.0485) (xy 156.21269 65.06223) (xy 156.22642 65.06223)
			(xy 156.22642 65.07596) (xy 156.24015 65.07596) (xy 156.24015 65.08969) (xy 156.25388 65.08969) (xy 156.25388 65.10343)
			(xy 156.26761 65.10343) (xy 156.26761 65.11716) (xy 156.28135 65.11716) (xy 156.28135 65.13089) (xy 156.29508 65.13089)
			(xy 156.29508 65.14462) (xy 156.30881 65.14462) (xy 156.30881 65.15835) (xy 156.32254 65.15835) (xy 156.32254 65.17208)
			(xy 156.33627 65.17208) (xy 156.33627 65.18582) (xy 156.35 65.18582) (xy 156.35 65.19955) (xy 156.36374 65.19955)
			(xy 156.36374 65.21328) (xy 156.37747 65.21328) (xy 156.37747 65.22701) (xy 156.3912 65.22701) (xy 156.3912 65.24074)
			(xy 156.40493 65.24074) (xy 156.40493 65.25447) (xy 156.41866 65.25447) (xy 156.41866 65.26821) (xy 156.43239 65.26821)
			(xy 156.43239 65.28194) (xy 156.44613 65.28194) (xy 156.44613 65.29567) (xy 156.47359 65.29567) (xy 156.47359 65.3094)
			(xy 156.48732 65.3094) (xy 156.48732 65.32313) (xy 156.50105 65.32313) (xy 156.50105 65.33686) (xy 156.51478 65.33686)
			(xy 156.51478 65.3506) (xy 156.52852 65.3506) (xy 156.52852 65.36433) (xy 156.54225 65.36433) (xy 156.54225 65.37806)
			(xy 156.55598 65.37806) (xy 156.55598 65.39179) (xy 156.56971 65.39179) (xy 156.56971 65.40552) (xy 156.58344 65.40552)
			(xy 156.58344 65.41925) (xy 156.59717 65.41925) (xy 156.59717 65.43299) (xy 156.61091 65.43299) (xy 156.61091 65.44672)
			(xy 156.62464 65.44672) (xy 156.62464 65.46045) (xy 156.63837 65.46045) (xy 156.63837 65.47418) (xy 156.6521 65.47418)
			(xy 156.6521 65.48791) (xy 156.66583 65.48791) (xy 156.66583 65.50165) (xy 156.67957 65.50165) (xy 156.67957 65.51538)
			(xy 156.6933 65.51538) (xy 156.6933 65.52911) (xy 156.70703 65.52911) (xy 156.70703 65.54284) (xy 156.72076 65.54284)
			(xy 156.72076 65.55657) (xy 156.73449 65.55657) (xy 156.73449 65.57031) (xy 156.74823 65.57031) (xy 156.74823 65.58404)
			(xy 156.76196 65.58404) (xy 156.76196 65.59777) (xy 156.77569 65.59777) (xy 156.77569 65.6115) (xy 156.78942 65.6115)
			(xy 156.78942 65.62523) (xy 156.81688 65.62523) (xy 156.81688 65.6115) (xy 156.83062 65.6115) (xy 156.83062 65.59777)
			(xy 156.84435 65.59777) (xy 156.84435 65.58404) (xy 156.85808 65.58404) (xy 156.85808 65.57031) (xy 156.87181 65.57031)
			(xy 156.87181 65.55657) (xy 156.88554 65.55657) (xy 156.88554 65.54284) (xy 156.89927 65.54284) (xy 156.89927 65.52911)
			(xy 156.91301 65.52911) (xy 156.91301 65.51538) (xy 156.92674 65.51538) (xy 156.92674 65.50165) (xy 156.94047 65.50165)
			(xy 156.94047 65.48791) (xy 156.94047 65.47418) (xy 156.9542 65.47418) (xy 156.9542 65.46045) (xy 156.96793 65.46045)
			(xy 156.96793 65.44672) (xy 156.96793 65.43299) (xy 156.98166 65.43299) (xy 156.98166 65.41925) (xy 156.9954 65.41925)
			(xy 156.9954 65.40552) (xy 156.9954 65.39179) (xy 156.9954 65.37806) (xy 156.9954 65.36433) (xy 156.9954 65.3506)
			(xy 156.9954 65.33686) (xy 156.9954 65.32313) (xy 156.9954 65.3094) (xy 156.9954 65.29567) (xy 156.9954 65.28194)
			(xy 156.9954 65.26821) (xy 156.9954 65.25447) (xy 156.9954 65.24074) (xy 156.9954 65.22701) (xy 156.9954 65.21328)
			(xy 156.9954 65.19955) (xy 156.9954 65.18582) (xy 156.9954 65.17208) (xy 156.9954 65.15835) (xy 156.9954 65.14462)
			(xy 156.9954 65.13089) (xy 156.9954 65.11716) (xy 156.9954 65.10343) (xy 156.9954 65.08969) (xy 156.9954 65.07596)
			(xy 156.9954 65.06223) (xy 156.9954 65.0485) (xy 156.9954 65.03477) (xy 156.9954 65.02104) (xy 156.9954 65.0073)
			(xy 156.9954 64.99357) (xy 156.9954 64.97984) (xy 156.9954 64.96611) (xy 156.9954 64.95238) (xy 156.9954 64.93864)
			(xy 156.9954 64.92491) (xy 156.9954 64.91118) (xy 156.9954 64.89745) (xy 156.9954 64.88372) (xy 156.9954 64.86998)
			(xy 156.9954 64.85625) (xy 156.9954 64.84252) (xy 156.9954 64.82879) (xy 156.9954 64.81506) (xy 156.9954 64.80133)
			(xy 156.98166 64.80133) (xy 156.98166 64.78759) (xy 156.98166 64.77386) (xy 156.96793 64.77386) (xy 156.96793 64.76013)
			(xy 156.96793 64.7464) (xy 156.9542 64.7464) (xy 156.9542 64.73267) (xy 156.94047 64.73267) (xy 156.94047 64.71894)
			(xy 156.94047 64.7052) (xy 156.92674 64.7052) (xy 156.92674 64.69147) (xy 156.91301 64.69147) (xy 156.91301 64.67774)
			(xy 156.89927 64.67774) (xy 156.89927 64.66401) (xy 156.88554 64.66401) (xy 156.88554 64.65028) (xy 156.87181 64.65028)
			(xy 156.87181 64.63655) (xy 156.85808 64.63655) (xy 156.85808 64.62281) (xy 156.84435 64.62281) (xy 156.84435 64.60908)
			(xy 156.83062 64.60908) (xy 156.83062 64.59535) (xy 156.81688 64.59535) (xy 156.81688 64.58162) (xy 156.80315 64.58162)
			(xy 156.80315 64.56789) (xy 156.78942 64.56789) (xy 156.78942 64.55416) (xy 156.77569 64.55416) (xy 156.77569 64.54042)
			(xy 156.76196 64.54042) (xy 156.76196 64.52669) (xy 156.74823 64.52669) (xy 156.74823 64.51296) (xy 156.73449 64.51296)
			(xy 156.73449 64.49923) (xy 156.72076 64.49923) (xy 156.72076 64.4855) (xy 156.6933 64.4855) (xy 156.6933 64.47176)
			(xy 156.67957 64.47176) (xy 156.67957 64.45803) (xy 156.66583 64.45803) (xy 156.66583 64.4443) (xy 156.6521 64.4443)
			(xy 156.6521 64.43057) (xy 156.63837 64.43057) (xy 156.63837 64.41684) (xy 156.62464 64.41684) (xy 156.62464 64.4031)
			(xy 156.61091 64.4031) (xy 156.61091 64.38937) (xy 156.59717 64.38937) (xy 156.59717 64.37564) (xy 156.58344 64.37564)
			(xy 156.58344 64.36191) (xy 156.56971 64.36191) (xy 156.56971 64.34818) (xy 156.55598 64.34818) (xy 156.55598 64.33445)
			(xy 156.54225 64.33445) (xy 156.54225 64.32071) (xy 156.52852 64.32071) (xy 156.52852 64.30698) (xy 156.51478 64.30698)
			(xy 156.51478 64.29325) (xy 156.50105 64.29325) (xy 156.50105 64.27952) (xy 156.48732 64.27952) (xy 156.48732 64.26579)
			(xy 156.47359 64.26579) (xy 156.47359 64.25206) (xy 156.45986 64.25206) (xy 156.45986 64.23833) (xy 156.44613 64.23833)
			(xy 156.44613 64.22459) (xy 156.43239 64.22459) (xy 156.43239 64.21086) (xy 156.41866 64.21086) (xy 156.41866 64.19713)
			(xy 156.40493 64.19713) (xy 156.40493 64.1834) (xy 156.3912 64.1834) (xy 156.3912 64.16967) (xy 156.37747 64.16967)
			(xy 156.37747 64.15594) (xy 156.36374 64.15594) (xy 156.36374 64.1422) (xy 156.35 64.1422) (xy 156.35 64.12847)
			(xy 156.33627 64.12847) (xy 156.33627 64.11474) (xy 156.32254 64.11474) (xy 156.32254 64.10101) (xy 156.30881 64.10101)
			(xy 156.30881 64.08728) (xy 156.29508 64.08728) (xy 156.29508 64.07355) (xy 156.28135 64.07355) (xy 156.28135 64.05981)
			(xy 156.26761 64.05981) (xy 156.26761 64.04608) (xy 156.25388 64.04608) (xy 156.25388 64.03235) (xy 156.24015 64.03235)
			(xy 156.24015 64.01862) (xy 156.22642 64.01862) (xy 156.22642 64.00489) (xy 156.21269 64.00489) (xy 156.21269 63.99115)
			(xy 156.19896 63.99115) (xy 156.19896 63.97742) (xy 156.18522 63.97742) (xy 156.18522 63.96369) (xy 156.17149 63.96369)
			(xy 156.17149 63.94996) (xy 156.15776 63.94996) (xy 156.15776 63.93623) (xy 156.14403 63.93623) (xy 156.14403 63.92249)
			(xy 156.13029 63.92249) (xy 156.13029 63.90876) (xy 156.11656 63.90876) (xy 156.11656 63.89503) (xy 156.10283 63.89503)
			(xy 156.10283 63.8813) (xy 156.0891 63.8813) (xy 156.0891 63.86757) (xy 156.07537 63.86757) (xy 156.07537 63.85384)
			(xy 156.06164 63.85384) (xy 156.06164 63.8401) (xy 156.0479 63.8401) (xy 156.0479 63.82637) (xy 156.03417 63.82637)
			(xy 156.03417 63.81264) (xy 156.02044 63.81264) (xy 156.02044 63.79891) (xy 156.00671 63.79891) (xy 156.00671 63.78518)
			(xy 155.99298 63.78518) (xy 155.99298 63.77145) (xy 155.97925 63.77145) (xy 155.97925 63.75771) (xy 155.96551 63.75771)
			(xy 155.96551 63.74398) (xy 155.95178 63.74398) (xy 155.95178 63.73025) (xy 155.93805 63.73025) (xy 155.93805 63.71652)
			(xy 155.92432 63.71652) (xy 155.92432 63.70279) (xy 156.66583 63.70279) (xy 156.66583 63.71652) (xy 156.66583 63.73025)
			(xy 156.66583 63.74398) (xy 156.66583 63.75771) (xy 156.66583 63.77145) (xy 156.66583 63.78518) (xy 156.66583 63.79891)
			(xy 156.66583 63.81264) (xy 156.66583 63.82637) (xy 156.66583 63.8401) (xy 156.66583 63.85384) (xy 156.66583 63.86757)
			(xy 156.66583 63.8813) (xy 156.66583 63.89503) (xy 156.66583 63.90876) (xy 156.66583 63.92249) (xy 156.66583 63.93623)
			(xy 156.66583 63.94996) (xy 156.66583 63.96369) (xy 156.66583 63.97742) (xy 156.66583 63.99115) (xy 156.66583 64.00489)
			(xy 156.66583 64.01862) (xy 156.66583 64.03235) (xy 156.66583 64.04608) (xy 156.66583 64.05981) (xy 156.66583 64.07355)
			(xy 156.66583 64.08728) (xy 156.66583 64.10101) (xy 156.66583 64.11474) (xy 156.66583 64.12847) (xy 156.66583 64.1422)
			(xy 156.66583 64.15594) (xy 156.66583 64.16967) (xy 156.66583 64.1834) (xy 156.66583 64.19713) (xy 156.66583 64.21086)
			(xy 156.66583 64.22459) (xy 156.66583 64.23833) (xy 156.66583 64.25206) (xy 156.66583 64.26579) (xy 156.66583 64.27952)
			(xy 156.66583 64.29325) (xy 156.66583 64.30698) (xy 156.66583 64.32071) (xy 156.66583 64.33445) (xy 156.66583 64.34818)
			(xy 156.66583 64.36191) (xy 156.67957 64.36191) (xy 156.67957 64.37564) (xy 156.6933 64.37564) (xy 156.6933 64.38937)
			(xy 156.73449 64.38937) (xy 156.73449 64.4031) (xy 156.78942 64.4031) (xy 156.78942 64.38937) (xy 156.80315 64.38937)
			(xy 156.80315 64.4031) (xy 158.16259 64.4031) (xy 158.16259 64.41684) (xy 158.17633 64.41684) (xy 158.17633 64.43057)
			(xy 158.19006 64.43057) (xy 158.19006 64.4443) (xy 158.19006 64.45803) (xy 158.19006 64.47176) (xy 158.19006 64.4855)
			(xy 158.19006 64.49923) (xy 158.19006 64.51296) (xy 158.19006 64.52669) (xy 158.19006 64.54042) (xy 158.19006 64.55416)
			(xy 158.19006 64.56789) (xy 158.19006 64.58162) (xy 158.19006 64.59535) (xy 158.19006 64.60908) (xy 158.19006 64.62281)
			(xy 158.19006 64.63655) (xy 158.19006 64.65028) (xy 158.19006 64.66401) (xy 158.19006 64.67774) (xy 158.19006 64.69147)
			(xy 158.19006 64.7052) (xy 158.19006 64.71894) (xy 158.19006 64.73267) (xy 158.19006 64.7464) (xy 158.19006 64.76013)
			(xy 158.19006 64.77386) (xy 158.19006 64.78759) (xy 158.19006 64.80133) (xy 158.19006 64.81506) (xy 158.19006 64.82879)
			(xy 158.19006 64.84252) (xy 158.19006 64.85625) (xy 158.19006 64.86998) (xy 158.19006 64.88372) (xy 158.19006 64.89745)
			(xy 158.19006 64.91118) (xy 158.19006 64.92491) (xy 158.19006 64.93864) (xy 158.19006 64.95238) (xy 158.19006 64.96611)
			(xy 158.19006 64.97984) (xy 158.19006 64.99357) (xy 158.19006 65.0073) (xy 158.19006 65.02104) (xy 158.19006 65.03477)
			(xy 158.19006 65.0485) (xy 158.19006 65.06223) (xy 158.19006 65.07596) (xy 158.19006 65.08969) (xy 158.19006 65.10343)
			(xy 158.19006 65.11716) (xy 158.19006 65.13089) (xy 158.19006 65.14462) (xy 158.19006 65.15835) (xy 158.19006 65.17208)
			(xy 158.19006 65.18582) (xy 158.19006 65.19955) (xy 158.19006 65.21328) (xy 158.19006 65.22701) (xy 158.19006 65.24074)
			(xy 158.19006 65.25447) (xy 158.19006 65.26821) (xy 158.19006 65.28194) (xy 158.19006 65.29567) (xy 158.19006 65.3094)
			(xy 158.19006 65.32313) (xy 158.19006 65.33686) (xy 158.19006 65.3506) (xy 158.19006 65.36433) (xy 158.19006 65.37806)
			(xy 158.19006 65.39179) (xy 158.19006 65.40552) (xy 158.19006 65.41925) (xy 158.19006 65.43299) (xy 158.19006 65.44672)
			(xy 158.19006 65.46045) (xy 158.19006 65.47418) (xy 158.19006 65.48791) (xy 158.19006 65.50165) (xy 158.19006 65.51538)
			(xy 158.19006 65.52911) (xy 158.19006 65.54284) (xy 158.19006 65.55657) (xy 158.19006 65.57031) (xy 158.19006 65.58404)
			(xy 158.19006 65.59777) (xy 158.19006 65.6115) (xy 158.19006 65.62523) (xy 158.19006 65.63896) (xy 158.19006 65.6527)
			(xy 158.19006 65.66643) (xy 158.19006 65.68016) (xy 158.19006 65.69389) (xy 158.19006 65.70762) (xy 158.19006 65.72135)
			(xy 158.19006 65.73509) (xy 158.19006 65.74882) (xy 158.19006 65.76255) (xy 158.19006 65.77628) (xy 158.19006 65.79001)
			(xy 158.19006 65.80374) (xy 158.19006 65.81748) (xy 158.19006 65.83121) (xy 158.19006 65.84494) (xy 158.19006 65.85867)
			(xy 158.19006 65.8724) (xy 158.19006 65.88613) (xy 158.17633 65.88613) (xy 158.17633 65.89987) (xy 158.17633 65.9136)
			(xy 158.14886 65.9136) (xy 158.14886 65.92733) (xy 156.72076 65.92733) (xy 156.72076 65.94106) (xy 156.6933 65.94106)
			(xy 156.6933 65.95479) (xy 156.67957 65.95479) (xy 156.67957 65.96852) (xy 156.66583 65.96852) (xy 156.66583 65.98226)
			(xy 156.66583 65.99599) (xy 156.66583 66.00972) (xy 156.66583 66.02345) (xy 156.66583 66.03718) (xy 156.66583 66.05092)
			(xy 156.66583 66.06465) (xy 156.66583 66.07838) (xy 156.66583 66.09211) (xy 156.66583 66.10584) (xy 156.66583 66.11958)
			(xy 156.66583 66.13331) (xy 156.66583 66.14704) (xy 156.66583 66.16077) (xy 156.66583 66.1745) (xy 156.66583 66.18823)
			(xy 156.66583 66.20197) (xy 156.66583 66.2157) (xy 156.66583 66.22943) (xy 156.66583 66.24316) (xy 156.66583 66.25689)
			(xy 156.66583 66.27062) (xy 156.66583 66.28436) (xy 156.66583 66.29809) (xy 156.66583 66.31182) (xy 156.66583 66.32555)
			(xy 156.66583 66.33928) (xy 156.66583 66.35301) (xy 156.66583 66.36675) (xy 156.66583 66.38048) (xy 156.66583 66.39421)
			(xy 156.66583 66.40794) (xy 156.66583 66.42167) (xy 156.66583 66.4354) (xy 156.66583 66.44914) (xy 156.66583 66.46287)
			(xy 156.66583 66.4766) (xy 156.66583 66.49033) (xy 156.66583 66.50406) (xy 156.66583 66.51779) (xy 156.66583 66.53153)
			(xy 156.66583 66.54526) (xy 156.66583 66.55899) (xy 156.66583 66.57272) (xy 156.66583 66.58645) (xy 156.66583 66.60019)
			(xy 156.66583 66.61392) (xy 156.67957 66.61392) (xy 156.67957 66.62765) (xy 156.6933 66.62765) (xy 156.6933 66.64138)
			(xy 156.70703 66.64138) (xy 156.70703 66.65511) (xy 158.45096 66.65511) (xy 158.45096 66.64138) (xy 158.49216 66.64138)
			(xy 158.49216 66.62765) (xy 158.51962 66.62765) (xy 158.51962 66.61392) (xy 158.53335 66.61392) (xy 158.53335 66.60019)
			(xy 158.54708 66.60019) (xy 158.54708 66.58645) (xy 158.56082 66.58645) (xy 158.56082 66.57272) (xy 158.57455 66.57272)
			(xy 158.57455 66.55899) (xy 158.58828 66.55899) (xy 158.58828 66.54526) (xy 158.60201 66.54526) (xy 158.60201 66.53153)
			(xy 158.61574 66.53153) (xy 158.61574 66.51779) (xy 158.62947 66.51779) (xy 158.62947 66.50406) (xy 158.64321 66.50406)
			(xy 158.64321 66.49033) (xy 158.65694 66.49033) (xy 158.65694 66.4766) (xy 158.67067 66.4766) (xy 158.67067 66.46287)
			(xy 158.6844 66.46287) (xy 158.6844 66.44914) (xy 158.69813 66.44914) (xy 158.69813 66.4354) (xy 158.71186 66.4354)
			(xy 158.71186 66.42167) (xy 158.7256 66.42167) (xy 158.7256 66.40794) (xy 158.73933 66.40794) (xy 158.73933 66.39421)
			(xy 158.75306 66.39421) (xy 158.75306 66.38048) (xy 158.76679 66.38048) (xy 158.76679 66.36675) (xy 158.78052 66.36675)
			(xy 158.78052 66.35301) (xy 158.79426 66.35301) (xy 158.79426 66.33928) (xy 158.80799 66.33928) (xy 158.80799 66.32555)
			(xy 158.82172 66.32555) (xy 158.82172 66.31182) (xy 158.83545 66.31182) (xy 158.83545 66.29809) (xy 158.84918 66.29809)
			(xy 158.84918 66.28436) (xy 158.86292 66.28436) (xy 158.86292 66.27062) (xy 158.87665 66.27062) (xy 158.87665 66.25689)
			(xy 158.89038 66.25689) (xy 158.89038 66.24316) (xy 158.90411 66.24316) (xy 158.90411 66.22943) (xy 158.91784 66.22943)
			(xy 158.91784 66.2157) (xy 158.91784 66.20197) (xy 158.93157 66.20197) (xy 158.93157 66.18823) (xy 158.93157 66.1745)
			(xy 158.93157 66.16077) (xy 158.94531 66.16077) (xy 158.94531 66.14704) (xy 158.94531 66.13331) (xy 158.94531 66.11958)
			(xy 158.94531 66.10584) (xy 158.94531 66.09211) (xy 158.94531 66.07838) (xy 158.94531 66.06465) (xy 158.94531 66.05092)
			(xy 158.94531 66.03718) (xy 158.94531 66.02345) (xy 158.94531 66.00972) (xy 158.94531 65.99599) (xy 158.94531 65.98226)
			(xy 158.94531 65.96852) (xy 158.94531 65.95479) (xy 158.94531 65.94106) (xy 158.94531 65.92733) (xy 158.94531 65.9136)
			(xy 158.94531 65.89987) (xy 158.94531 65.88613) (xy 158.94531 65.8724) (xy 158.94531 65.85867) (xy 158.94531 65.84494)
			(xy 158.94531 65.83121) (xy 158.94531 65.81748) (xy 158.94531 65.80374) (xy 158.94531 65.79001) (xy 158.94531 65.77628)
			(xy 158.94531 65.76255) (xy 158.94531 65.74882) (xy 158.94531 65.73509) (xy 158.94531 65.72135) (xy 158.94531 65.70762)
			(xy 158.94531 65.69389) (xy 158.94531 65.68016) (xy 158.94531 65.66643) (xy 158.94531 65.6527) (xy 158.94531 65.63896)
			(xy 158.94531 65.62523) (xy 158.94531 65.6115) (xy 158.94531 65.59777) (xy 158.94531 65.58404) (xy 158.94531 65.57031)
			(xy 158.94531 65.55657) (xy 158.94531 65.54284) (xy 158.94531 65.52911) (xy 158.94531 65.51538) (xy 158.94531 65.50165)
			(xy 158.94531 65.48791) (xy 158.94531 65.47418) (xy 158.94531 65.46045) (xy 158.94531 65.44672) (xy 158.94531 65.43299)
			(xy 158.94531 65.41925) (xy 158.94531 65.40552) (xy 158.94531 65.39179) (xy 158.94531 65.37806) (xy 158.94531 65.36433)
			(xy 158.94531 65.3506) (xy 158.94531 65.33686) (xy 158.94531 65.32313) (xy 158.94531 65.3094) (xy 158.94531 65.29567)
			(xy 158.94531 65.28194) (xy 158.94531 65.26821) (xy 158.94531 65.25447) (xy 158.94531 65.24074) (xy 158.94531 65.22701)
			(xy 158.94531 65.21328) (xy 158.94531 65.19955) (xy 158.94531 65.18582) (xy 158.94531 65.17208) (xy 158.94531 65.15835)
			(xy 158.94531 65.14462) (xy 158.94531 65.13089) (xy 158.94531 65.11716) (xy 158.94531 65.10343) (xy 158.94531 65.08969)
			(xy 158.94531 65.07596) (xy 158.94531 65.06223) (xy 158.94531 65.0485) (xy 158.94531 65.03477) (xy 158.94531 65.02104)
			(xy 158.94531 65.0073) (xy 158.94531 64.99357) (xy 158.94531 64.97984) (xy 158.94531 64.96611) (xy 158.94531 64.95238)
			(xy 158.94531 64.93864) (xy 158.94531 64.92491) (xy 158.94531 64.91118) (xy 158.94531 64.89745) (xy 158.94531 64.88372)
			(xy 158.94531 64.86998) (xy 158.94531 64.85625) (xy 158.94531 64.84252) (xy 158.94531 64.82879) (xy 158.94531 64.81506)
			(xy 158.94531 64.80133) (xy 158.94531 64.78759) (xy 158.94531 64.77386) (xy 158.94531 64.76013) (xy 158.94531 64.7464)
			(xy 158.94531 64.73267) (xy 158.94531 64.71894) (xy 158.94531 64.7052) (xy 158.94531 64.69147) (xy 158.94531 64.67774)
			(xy 158.94531 64.66401) (xy 158.94531 64.65028) (xy 158.94531 64.63655) (xy 158.94531 64.62281) (xy 158.94531 64.60908)
			(xy 158.94531 64.59535) (xy 158.94531 64.58162) (xy 158.94531 64.56789) (xy 158.94531 64.55416) (xy 158.94531 64.54042)
			(xy 158.94531 64.52669) (xy 158.94531 64.51296) (xy 158.94531 64.49923) (xy 158.94531 64.4855) (xy 158.94531 64.47176)
			(xy 158.94531 64.45803) (xy 158.94531 64.4443) (xy 158.94531 64.43057) (xy 158.94531 64.41684) (xy 158.94531 64.4031)
			(xy 158.94531 64.38937) (xy 158.94531 64.37564) (xy 158.94531 64.36191) (xy 158.94531 64.34818) (xy 158.94531 64.33445)
			(xy 158.94531 64.32071) (xy 158.94531 64.30698) (xy 158.94531 64.29325) (xy 158.94531 64.27952) (xy 158.94531 64.26579)
			(xy 158.94531 64.25206) (xy 158.94531 64.23833) (xy 158.94531 64.22459) (xy 158.94531 64.21086) (xy 158.94531 64.19713)
			(xy 158.94531 64.1834) (xy 158.94531 64.16967) (xy 158.93157 64.16967) (xy 158.93157 64.15594) (xy 158.93157 64.1422)
			(xy 158.93157 64.12847) (xy 158.93157 64.11474) (xy 158.91784 64.11474) (xy 158.91784 64.10101) (xy 158.91784 64.08728)
			(xy 158.90411 64.08728) (xy 158.90411 64.07355) (xy 158.89038 64.07355) (xy 158.89038 64.05981) (xy 158.87665 64.05981)
			(xy 158.87665 64.04608) (xy 158.86292 64.04608) (xy 158.86292 64.03235) (xy 158.84918 64.03235) (xy 158.84918 64.01862)
			(xy 158.83545 64.01862) (xy 158.83545 64.00489) (xy 158.82172 64.00489) (xy 158.82172 63.99115) (xy 158.80799 63.99115)
			(xy 158.80799 63.97742) (xy 158.79426 63.97742) (xy 158.79426 63.96369) (xy 158.78052 63.96369) (xy 158.78052 63.94996)
			(xy 158.76679 63.94996) (xy 158.76679 63.93623) (xy 158.75306 63.93623) (xy 158.75306 63.92249) (xy 158.73933 63.92249)
			(xy 158.73933 63.90876) (xy 158.7256 63.90876) (xy 158.7256 63.89503) (xy 158.71186 63.89503) (xy 158.71186 63.8813)
			(xy 158.69813 63.8813) (xy 158.69813 63.86757) (xy 158.6844 63.86757) (xy 158.6844 63.85384) (xy 158.67067 63.85384)
			(xy 158.67067 63.8401) (xy 158.65694 63.8401) (xy 158.65694 63.82637) (xy 158.64321 63.82637) (xy 158.64321 63.81264)
			(xy 158.62947 63.81264) (xy 158.62947 63.79891) (xy 158.61574 63.79891) (xy 158.61574 63.78518) (xy 158.60201 63.78518)
			(xy 158.60201 63.77145) (xy 158.58828 63.77145) (xy 158.58828 63.75771) (xy 158.57455 63.75771) (xy 158.57455 63.74398)
			(xy 158.56082 63.74398) (xy 158.56082 63.73025) (xy 158.54708 63.73025) (xy 158.54708 63.71652) (xy 158.53335 63.71652)
			(xy 158.53335 63.70279) (xy 158.50589 63.70279) (xy 158.50589 63.68906) (xy 158.46469 63.68906) (xy 158.46469 63.67532)
			(xy 158.4235 63.67532) (xy 158.4235 63.66159) (xy 156.77569 63.66159) (xy 156.77569 63.67532) (xy 156.76196 63.67532)
			(xy 156.76196 63.66159) (xy 156.73449 63.66159) (xy 156.73449 63.67532) (xy 156.6933 63.67532) (xy 156.6933 63.68906)
			(xy 156.67957 63.68906) (xy 156.67957 63.70279) (xy 156.66583 63.70279) (xy 155.92432 63.70279) (xy 155.91059 63.70279)
			(xy 155.91059 63.68906) (xy 155.89686 63.68906) (xy 155.89686 63.67532) (xy 155.88312 63.67532) (xy 155.88312 63.66159)
			(xy 155.86939 63.66159) (xy 155.86939 63.64786) (xy 155.85566 63.64786) (xy 155.85566 63.63413) (xy 155.84193 63.63413)
			(xy 155.84193 63.6204) (xy 155.8282 63.6204) (xy 155.8282 63.60667) (xy 155.81447 63.60667) (xy 155.81447 63.59293)
			(xy 155.80073 63.59293) (xy 155.80073 63.5792) (xy 155.787 63.5792) (xy 155.787 63.56547) (xy 155.75954 63.56547)
			(xy 155.75954 63.55174) (xy 155.74581 63.55174) (xy 155.74581 63.53801) (xy 155.73208 63.53801) (xy 155.73208 63.52428)
			(xy 155.71834 63.52428) (xy 155.71834 63.51054) (xy 155.70461 63.51054) (xy 155.70461 63.49681) (xy 155.69088 63.49681)
			(xy 155.69088 63.48308) (xy 155.67715 63.48308) (xy 155.67715 63.46935) (xy 155.66342 63.46935) (xy 155.66342 63.45562)
			(xy 155.64968 63.45562) (xy 155.64968 63.44188) (xy 155.63595 63.44188) (xy 155.63595 63.42815) (xy 155.62222 63.42815)
			(xy 155.62222 63.41442) (xy 155.60849 63.41442) (xy 155.60849 63.40069) (xy 155.59476 63.40069) (xy 155.59476 63.38696)
			(xy 155.58102 63.38696) (xy 155.58102 63.37322) (xy 155.56729 63.37322) (xy 155.56729 63.35949) (xy 155.55356 63.35949)
			(xy 155.55356 63.34576) (xy 155.53983 63.34576) (xy 155.53983 63.33203) (xy 155.5261 63.33203) (xy 155.5261 63.3183)
			(xy 155.5261 63.30457) (xy 155.5261 63.29083) (xy 155.5261 63.2771) (xy 155.5261 63.26337) (xy 155.5261 63.24964)
			(xy 155.5261 63.23591) (xy 155.5261 63.22218) (xy 155.5261 63.20844) (xy 155.5261 63.19471) (xy 155.5261 63.18098)
			(xy 155.5261 63.16725) (xy 155.5261 63.15352) (xy 155.5261 63.13979) (xy 155.5261 63.12605) (xy 155.5261 63.11232)
			(xy 155.5261 63.09859) (xy 155.5261 63.08486) (xy 155.5261 63.07113) (xy 155.5261 63.0574) (xy 155.5261 63.04366)
			(xy 155.5261 63.02993) (xy 155.5261 63.0162) (xy 155.5261 63.00247) (xy 155.5261 62.98874) (xy 155.5261 62.97501)
			(xy 155.5261 62.96127) (xy 155.5261 62.94754) (xy 155.5261 62.93381) (xy 155.5261 62.92008) (xy 155.5261 62.90635)
			(xy 155.5261 62.89261) (xy 155.5261 62.87888) (xy 155.5261 62.86515) (xy 155.5261 62.85142) (xy 155.5261 62.83769)
			(xy 155.5261 62.82395) (xy 155.5261 62.81022) (xy 155.5261 62.79649) (xy 155.5261 62.78276) (xy 155.5261 62.76903)
			(xy 155.5261 62.7553) (xy 155.5261 62.74156) (xy 155.5261 62.72783) (xy 155.5261 62.7141) (xy 155.5261 62.70037)
			(xy 155.5261 62.68664) (xy 155.5261 62.67291) (xy 155.5261 62.65917) (xy 155.5261 62.64544) (xy 155.5261 62.63171)
			(xy 155.5261 62.61798) (xy 155.5261 62.60425) (xy 155.5261 62.59052) (xy 155.5261 62.57678) (xy 155.5261 62.56305)
			(xy 155.5261 62.54932) (xy 155.5261 62.53559) (xy 155.5261 62.52186) (xy 155.5261 62.50813) (xy 155.5261 62.49439)
			(xy 155.5261 62.48066) (xy 155.5261 62.46693) (xy 155.5261 62.4532) (xy 155.5261 62.43947) (xy 155.5261 62.42574)
			(xy 155.5261 62.412) (xy 155.5261 62.39827) (xy 155.5261 62.38454) (xy 155.5261 62.37081) (xy 155.5261 62.35708)
			(xy 155.5261 62.34334) (xy 155.5261 62.32961) (xy 155.5261 62.31588) (xy 155.5261 62.30215) (xy 155.5261 62.28842)
			(xy 155.5261 62.27468) (xy 155.5261 62.26095) (xy 155.5261 62.24722) (xy 155.5261 62.23349) (xy 155.5261 62.21976)
			(xy 155.5261 62.20603) (xy 155.5261 62.19229) (xy 155.5261 62.17856) (xy 155.5261 62.16483) (xy 155.5261 62.1511)
			(xy 155.5261 62.13737) (xy 155.5261 62.12364) (xy 155.5261 62.1099) (xy 155.5261 62.09617) (xy 155.5261 62.08244)
			(xy 155.5261 62.06871) (xy 155.5261 62.05498) (xy 155.5261 62.04125) (xy 155.5261 62.02751) (xy 155.5261 62.01378)
			(xy 155.5261 62.00005) (xy 155.5261 61.98632) (xy 155.5261 61.97259) (xy 155.5261 61.95886) (xy 155.5261 61.94512)
			(xy 155.5261 61.93139) (xy 155.5261 61.91766) (xy 155.5261 61.90393) (xy 155.5261 61.8902) (xy 155.5261 61.87646)
			(xy 155.5261 61.86273) (xy 155.5261 61.849) (xy 155.5261 61.83527) (xy 155.5261 61.82154) (xy 155.5261 61.8078)
			(xy 155.5261 61.79407) (xy 155.5261 61.78034) (xy 155.5261 61.76661) (xy 155.5261 61.75288) (xy 155.5261 61.73915)
			(xy 155.5261 61.72541) (xy 155.5261 61.71168) (xy 155.5261 61.69795) (xy 155.5261 61.68422) (xy 155.5261 61.67049)
			(xy 155.5261 61.65676) (xy 155.5261 61.64302) (xy 155.5261 61.62929) (xy 155.5261 61.61556) (xy 155.5261 61.60183)
			(xy 155.5261 61.5881) (xy 155.5261 61.57437) (xy 155.5261 61.56063) (xy 155.5261 61.5469) (xy 155.5261 61.53317)
			(xy 155.5261 61.51944) (xy 155.5261 61.50571) (xy 155.5261 61.49198) (xy 155.5261 61.47824) (xy 155.5261 61.46451)
			(xy 155.5261 61.45078) (xy 155.5261 61.43705) (xy 155.5261 61.42332) (xy 155.5261 61.40959) (xy 155.5261 61.39585)
			(xy 155.5261 61.38212) (xy 155.5261 61.36839) (xy 155.5261 61.35466) (xy 155.5261 61.34093) (xy 155.5261 61.32719)
			(xy 155.5261 61.31346) (xy 155.5261 61.29973) (xy 155.5261 61.286) (xy 155.5261 61.27227) (xy 155.5261 61.25853)
			(xy 155.5261 61.2448) (xy 155.5261 61.23107) (xy 155.5261 61.21734) (xy 155.5261 61.20361) (xy 155.5261 61.18988)
			(xy 155.5261 61.17614) (xy 155.5261 61.16241) (xy 155.5261 61.14868) (xy 155.5261 61.13495) (xy 155.5261 61.12122)
			(xy 155.5261 61.10749) (xy 155.5261 61.09375) (xy 155.5261 61.08002) (xy 155.5261 61.06629) (xy 155.5261 61.05256)
			(xy 155.5261 61.03883) (xy 155.5261 61.0251) (xy 155.5261 61.01136) (xy 155.5261 60.99763) (xy 155.5261 60.9839)
			(xy 155.5261 60.97017) (xy 155.5261 60.95644) (xy 155.5261 60.94271) (xy 155.5261 60.92897) (xy 155.5261 60.91524)
			(xy 155.5261 60.90151) (xy 155.5261 60.88778) (xy 155.5261 60.87405) (xy 155.5261 60.86032) (xy 155.5261 60.84658)
			(xy 155.5261 60.83285) (xy 155.5261 60.81912) (xy 155.5261 60.80539) (xy 155.5261 60.79166) (xy 155.5261 60.77792)
			(xy 155.5261 60.76419) (xy 155.5261 60.75046) (xy 155.5261 60.73673) (xy 155.5261 60.723) (xy 155.5261 60.70926)
			(xy 155.5261 60.69553) (xy 155.5261 60.6818) (xy 155.5261 60.66807) (xy 155.5261 60.65434) (xy 155.5261 60.64061)
			(xy 155.5261 60.62687) (xy 155.5261 60.61314) (xy 155.5261 60.59941) (xy 155.5261 60.58568) (xy 155.5261 60.57195)
			(xy 155.5261 60.55822) (xy 155.5261 60.54448) (xy 155.5261 60.53075) (xy 155.5261 60.51702) (xy 155.5261 60.50329)
			(xy 155.5261 60.48956) (xy 155.5261 60.47583) (xy 155.5261 60.46209) (xy 155.5261 60.44836) (xy 155.5261 60.43463)
			(xy 155.75954 60.43463) (xy 155.75954 60.44836) (xy 155.75954 60.46209) (xy 155.75954 60.47583) (xy 155.75954 60.48956)
			(xy 155.75954 60.50329) (xy 155.75954 60.51702) (xy 155.75954 60.53075) (xy 155.75954 60.54448) (xy 155.75954 60.55822)
			(xy 155.75954 60.57195) (xy 155.75954 60.58568) (xy 155.75954 60.59941) (xy 155.75954 60.61314) (xy 155.75954 60.62687)
			(xy 155.75954 60.64061) (xy 155.75954 60.65434) (xy 155.75954 60.66807) (xy 155.75954 60.6818) (xy 155.75954 60.69553)
			(xy 155.75954 60.70926) (xy 155.75954 60.723) (xy 155.75954 60.73673) (xy 155.75954 60.75046) (xy 155.75954 60.76419)
			(xy 155.75954 60.77792) (xy 155.75954 60.79166) (xy 155.75954 60.80539) (xy 155.75954 60.81912) (xy 155.75954 60.83285)
			(xy 155.75954 60.84658) (xy 155.75954 60.86032) (xy 155.75954 60.87405) (xy 155.75954 60.88778) (xy 155.75954 60.90151)
			(xy 155.75954 60.91524) (xy 155.75954 60.92897) (xy 155.75954 60.94271) (xy 155.75954 60.95644) (xy 155.75954 60.97017)
			(xy 155.75954 60.9839) (xy 155.75954 60.99763) (xy 155.75954 61.01136) (xy 155.75954 61.0251) (xy 155.75954 61.03883)
			(xy 155.75954 61.05256) (xy 155.75954 61.06629) (xy 155.75954 61.08002) (xy 155.75954 61.09375) (xy 155.75954 61.10749)
			(xy 155.75954 61.12122) (xy 155.75954 61.13495) (xy 155.75954 61.14868) (xy 155.75954 61.16241) (xy 155.80073 61.16241)
			(xy 155.80073 61.14868) (xy 155.81447 61.14868) (xy 155.81447 61.16241) (xy 156.00671 61.16241) (xy 156.00671 61.17614)
			(xy 156.00671 61.18988) (xy 156.00671 61.20361) (xy 156.00671 61.21734) (xy 156.00671 61.23107) (xy 156.00671 61.2448)
			(xy 156.00671 61.25853) (xy 156.00671 61.27227) (xy 156.00671 61.286) (xy 156.00671 61.29973) (xy 156.00671 61.31346)
			(xy 156.00671 61.32719) (xy 156.00671 61.34093) (xy 156.00671 61.35466) (xy 156.00671 61.36839) (xy 156.00671 61.38212)
			(xy 156.00671 61.39585) (xy 156.00671 61.40959) (xy 156.00671 61.42332) (xy 156.00671 61.43705) (xy 156.00671 61.45078)
			(xy 156.00671 61.46451) (xy 156.00671 61.47824) (xy 156.00671 61.49198) (xy 156.00671 61.50571) (xy 156.00671 61.51944)
			(xy 156.00671 61.53317) (xy 156.00671 61.5469) (xy 156.00671 61.56063) (xy 156.00671 61.57437) (xy 156.00671 61.5881)
			(xy 156.00671 61.60183) (xy 156.00671 61.61556) (xy 156.00671 61.62929) (xy 156.00671 61.64302) (xy 156.00671 61.65676)
			(xy 156.00671 61.67049) (xy 156.00671 61.68422) (xy 156.00671 61.69795) (xy 156.00671 61.71168) (xy 156.00671 61.72541)
			(xy 156.00671 61.73915) (xy 156.00671 61.75288) (xy 156.00671 61.76661) (xy 156.00671 61.78034) (xy 156.00671 61.79407)
			(xy 156.00671 61.8078) (xy 156.00671 61.82154) (xy 156.00671 61.83527) (xy 156.00671 61.849) (xy 156.00671 61.86273)
			(xy 156.00671 61.87646) (xy 156.00671 61.8902) (xy 156.00671 61.90393) (xy 156.00671 61.91766) (xy 156.00671 61.93139)
			(xy 156.00671 61.94512) (xy 156.00671 61.95886) (xy 156.00671 61.97259) (xy 156.00671 61.98632) (xy 156.00671 62.00005)
			(xy 156.00671 62.01378) (xy 156.00671 62.02751) (xy 156.00671 62.04125) (xy 156.00671 62.05498) (xy 156.00671 62.06871)
			(xy 156.00671 62.08244) (xy 156.00671 62.09617) (xy 156.00671 62.1099) (xy 156.00671 62.12364) (xy 156.00671 62.13737)
			(xy 156.00671 62.1511) (xy 156.00671 62.16483) (xy 156.00671 62.17856) (xy 156.00671 62.19229) (xy 156.00671 62.20603)
			(xy 156.00671 62.21976) (xy 156.00671 62.23349) (xy 156.00671 62.24722) (xy 156.00671 62.26095) (xy 156.00671 62.27468)
			(xy 156.00671 62.28842) (xy 156.00671 62.30215) (xy 156.00671 62.31588) (xy 156.00671 62.32961) (xy 156.00671 62.34334)
			(xy 156.00671 62.35708) (xy 156.00671 62.37081) (xy 156.00671 62.38454) (xy 156.00671 62.39827) (xy 156.00671 62.412)
			(xy 156.00671 62.42574) (xy 156.00671 62.43947) (xy 156.00671 62.4532) (xy 156.00671 62.46693) (xy 156.00671 62.48066)
			(xy 156.00671 62.49439) (xy 156.00671 62.50813) (xy 156.00671 62.52186) (xy 156.00671 62.53559) (xy 156.00671 62.54932)
			(xy 156.00671 62.56305) (xy 156.00671 62.57678) (xy 156.00671 62.59052) (xy 156.00671 62.60425) (xy 156.00671 62.61798)
			(xy 156.00671 62.63171) (xy 156.00671 62.64544) (xy 156.00671 62.65917) (xy 156.00671 62.67291) (xy 156.00671 62.68664)
			(xy 156.00671 62.70037) (xy 156.00671 62.7141) (xy 156.00671 62.72783) (xy 156.00671 62.74156) (xy 156.00671 62.7553)
			(xy 156.00671 62.76903) (xy 156.00671 62.78276) (xy 156.00671 62.79649) (xy 156.00671 62.81022) (xy 156.00671 62.82395)
			(xy 156.00671 62.83769) (xy 156.00671 62.85142) (xy 156.00671 62.86515) (xy 156.00671 62.87888) (xy 156.00671 62.89261)
			(xy 156.00671 62.90635) (xy 156.00671 62.92008) (xy 156.00671 62.93381) (xy 156.00671 62.94754) (xy 156.00671 62.96127)
			(xy 156.00671 62.97501) (xy 156.00671 62.98874) (xy 156.00671 63.00247) (xy 156.00671 63.0162) (xy 156.00671 63.02993)
			(xy 156.00671 63.04366) (xy 156.00671 63.0574) (xy 156.00671 63.07113) (xy 156.00671 63.08486) (xy 156.00671 63.09859)
			(xy 156.00671 63.11232) (xy 156.00671 63.12605) (xy 156.00671 63.13979) (xy 156.00671 63.15352) (xy 156.00671 63.16725)
			(xy 156.00671 63.18098) (xy 156.00671 63.19471) (xy 156.00671 63.20844) (xy 156.00671 63.22218) (xy 156.00671 63.23591)
			(xy 156.00671 63.24964) (xy 156.00671 63.26337) (xy 156.00671 63.2771) (xy 156.00671 63.29083) (xy 156.00671 63.30457)
			(xy 156.00671 63.3183) (xy 156.00671 63.33203) (xy 156.00671 63.34576) (xy 156.00671 63.35949) (xy 156.00671 63.37322)
			(xy 156.02044 63.37322) (xy 156.02044 63.38696) (xy 156.03417 63.38696) (xy 156.03417 63.40069) (xy 156.0479 63.40069)
			(xy 156.0479 63.41442) (xy 156.6521 63.41442) (xy 156.6521 63.40069) (xy 156.67957 63.40069) (xy 156.67957 63.38696)
			(xy 156.6933 63.38696) (xy 156.6933 63.37322) (xy 156.6933 63.35949) (xy 156.70703 63.35949) (xy 156.70703 63.34576)
			(xy 156.70703 63.33203) (xy 156.70703 63.3183) (xy 156.70703 63.30457) (xy 156.70703 63.29083) (xy 156.70703 63.2771)
			(xy 156.70703 63.26337) (xy 156.70703 63.24964) (xy 156.70703 63.23591) (xy 156.70703 63.22218) (xy 156.70703 63.20844)
			(xy 156.70703 63.19471) (xy 156.70703 63.18098) (xy 156.70703 63.16725) (xy 156.70703 63.15352) (xy 156.70703 63.13979)
			(xy 156.70703 63.12605) (xy 156.70703 63.11232) (xy 156.70703 63.09859) (xy 156.70703 63.08486) (xy 156.70703 63.07113)
			(xy 156.70703 63.0574) (xy 156.70703 63.04366) (xy 156.70703 63.02993) (xy 156.70703 63.0162) (xy 156.70703 63.00247)
			(xy 156.70703 62.98874) (xy 156.70703 62.97501) (xy 156.70703 62.96127) (xy 156.70703 62.94754) (xy 156.70703 62.93381)
			(xy 156.70703 62.92008) (xy 156.70703 62.90635) (xy 156.70703 62.89261) (xy 156.70703 62.87888) (xy 156.70703 62.86515)
			(xy 156.70703 62.85142) (xy 156.70703 62.83769) (xy 156.70703 62.82395) (xy 156.70703 62.81022) (xy 156.70703 62.79649)
			(xy 156.70703 62.78276) (xy 156.70703 62.76903) (xy 156.70703 62.7553) (xy 156.70703 62.74156) (xy 156.70703 62.72783)
			(xy 156.70703 62.7141) (xy 156.70703 62.70037) (xy 156.70703 62.68664) (xy 156.70703 62.67291) (xy 156.70703 62.65917)
			(xy 156.70703 62.64544) (xy 156.70703 62.63171) (xy 156.70703 62.61798) (xy 156.70703 62.60425) (xy 156.70703 62.59052)
			(xy 156.70703 62.57678) (xy 156.70703 62.56305) (xy 156.70703 62.54932) (xy 156.70703 62.53559) (xy 156.70703 62.52186)
			(xy 156.70703 62.50813) (xy 156.70703 62.49439) (xy 156.70703 62.48066) (xy 156.70703 62.46693) (xy 156.70703 62.4532)
			(xy 156.70703 62.43947) (xy 156.70703 62.42574) (xy 156.70703 62.412) (xy 156.70703 62.39827) (xy 156.70703 62.38454)
			(xy 156.70703 62.37081) (xy 156.70703 62.35708) (xy 156.70703 62.34334) (xy 156.70703 62.32961) (xy 156.70703 62.31588)
			(xy 156.70703 62.30215) (xy 156.70703 62.28842) (xy 156.70703 62.27468) (xy 156.70703 62.26095) (xy 156.70703 62.24722)
			(xy 156.70703 62.23349) (xy 156.70703 62.21976) (xy 156.70703 62.20603) (xy 156.70703 62.19229) (xy 156.70703 62.17856)
			(xy 156.70703 62.16483) (xy 156.70703 62.1511) (xy 156.70703 62.13737) (xy 156.70703 62.12364) (xy 156.70703 62.1099)
			(xy 156.70703 62.09617) (xy 156.70703 62.08244) (xy 156.70703 62.06871) (xy 156.70703 62.05498) (xy 156.70703 62.04125)
			(xy 156.70703 62.02751) (xy 156.70703 62.01378) (xy 156.70703 62.00005) (xy 156.70703 61.98632) (xy 156.70703 61.97259)
			(xy 156.70703 61.95886) (xy 156.70703 61.94512) (xy 156.70703 61.93139) (xy 156.70703 61.91766) (xy 156.70703 61.90393)
			(xy 156.70703 61.8902) (xy 156.70703 61.87646) (xy 156.70703 61.86273) (xy 156.70703 61.849) (xy 156.70703 61.83527)
			(xy 156.70703 61.82154) (xy 156.70703 61.8078) (xy 156.70703 61.79407) (xy 156.70703 61.78034) (xy 156.70703 61.76661)
			(xy 156.70703 61.75288) (xy 156.70703 61.73915) (xy 156.70703 61.72541) (xy 156.70703 61.71168) (xy 156.70703 61.69795)
			(xy 156.70703 61.68422) (xy 156.70703 61.67049) (xy 156.70703 61.65676) (xy 156.70703 61.64302) (xy 156.70703 61.62929)
			(xy 156.70703 61.61556) (xy 156.70703 61.60183) (xy 156.70703 61.5881) (xy 156.70703 61.57437) (xy 156.70703 61.56063)
			(xy 156.70703 61.5469) (xy 156.70703 61.53317) (xy 156.70703 61.51944) (xy 156.70703 61.50571) (xy 156.70703 61.49198)
			(xy 156.70703 61.47824) (xy 156.70703 61.46451) (xy 156.70703 61.45078) (xy 156.70703 61.43705) (xy 156.70703 61.42332)
			(xy 156.70703 61.40959) (xy 156.70703 61.39585) (xy 156.70703 61.38212) (xy 156.70703 61.36839) (xy 156.70703 61.35466)
			(xy 156.70703 61.34093) (xy 156.70703 61.32719) (xy 156.70703 61.31346) (xy 156.70703 61.29973) (xy 156.70703 61.286)
			(xy 156.70703 61.27227) (xy 156.70703 61.25853) (xy 156.70703 61.2448) (xy 156.70703 61.23107) (xy 156.70703 61.21734)
			(xy 156.70703 61.20361) (xy 156.70703 61.18988) (xy 156.70703 61.17614) (xy 156.70703 61.16241) (xy 157.17391 61.16241)
			(xy 157.17391 61.17614) (xy 157.17391 61.18988) (xy 157.17391 61.20361) (xy 157.17391 61.21734) (xy 157.17391 61.23107)
			(xy 157.17391 61.2448) (xy 157.17391 61.25853) (xy 157.17391 61.27227) (xy 157.17391 61.286) (xy 157.17391 61.29973)
			(xy 157.17391 61.31346) (xy 157.17391 61.32719) (xy 157.17391 61.34093) (xy 157.17391 61.35466) (xy 157.17391 61.36839)
			(xy 157.17391 61.38212) (xy 157.17391 61.39585) (xy 157.17391 61.40959) (xy 157.17391 61.42332) (xy 157.17391 61.43705)
			(xy 157.17391 61.45078) (xy 157.17391 61.46451) (xy 157.17391 61.47824) (xy 157.17391 61.49198) (xy 157.17391 61.50571)
			(xy 157.17391 61.51944) (xy 157.17391 61.53317) (xy 157.17391 61.5469) (xy 157.17391 61.56063) (xy 157.17391 61.57437)
			(xy 157.17391 61.5881) (xy 157.17391 61.60183) (xy 157.17391 61.61556) (xy 157.17391 61.62929) (xy 157.17391 61.64302)
			(xy 157.17391 61.65676) (xy 157.17391 61.67049) (xy 157.17391 61.68422) (xy 157.17391 61.69795) (xy 157.17391 61.71168)
			(xy 157.17391 61.72541) (xy 157.17391 61.73915) (xy 157.17391 61.75288) (xy 157.17391 61.76661) (xy 157.17391 61.78034)
			(xy 157.17391 61.79407) (xy 157.17391 61.8078) (xy 157.17391 61.82154) (xy 157.17391 61.83527) (xy 157.17391 61.849)
			(xy 157.17391 61.86273) (xy 157.17391 61.87646) (xy 157.17391 61.8902) (xy 157.17391 61.90393) (xy 157.17391 61.91766)
			(xy 157.17391 61.93139) (xy 157.17391 61.94512) (xy 157.17391 61.95886) (xy 157.17391 61.97259) (xy 157.17391 61.98632)
			(xy 157.17391 62.00005) (xy 157.17391 62.01378) (xy 157.17391 62.02751) (xy 157.17391 62.04125) (xy 157.17391 62.05498)
			(xy 157.17391 62.06871) (xy 157.17391 62.08244) (xy 157.17391 62.09617) (xy 157.17391 62.1099) (xy 157.17391 62.12364)
			(xy 157.17391 62.13737) (xy 157.17391 62.1511) (xy 157.17391 62.16483) (xy 157.17391 62.17856) (xy 157.17391 62.19229)
			(xy 157.17391 62.20603) (xy 157.17391 62.21976) (xy 157.17391 62.23349) (xy 157.17391 62.24722) (xy 157.17391 62.26095)
			(xy 157.17391 62.27468) (xy 157.17391 62.28842) (xy 157.17391 62.30215) (xy 157.17391 62.31588) (xy 157.17391 62.32961)
			(xy 157.17391 62.34334) (xy 157.17391 62.35708) (xy 157.17391 62.37081) (xy 157.17391 62.38454) (xy 157.17391 62.39827)
			(xy 157.17391 62.412) (xy 157.17391 62.42574) (xy 157.17391 62.43947) (xy 157.17391 62.4532) (xy 157.17391 62.46693)
			(xy 157.17391 62.48066) (xy 157.17391 62.49439) (xy 157.17391 62.50813) (xy 157.17391 62.52186) (xy 157.17391 62.53559)
			(xy 157.17391 62.54932) (xy 157.17391 62.56305) (xy 157.17391 62.57678) (xy 157.17391 62.59052) (xy 157.17391 62.60425)
			(xy 157.17391 62.61798) (xy 157.17391 62.63171) (xy 157.17391 62.64544) (xy 157.17391 62.65917) (xy 157.17391 62.67291)
			(xy 157.17391 62.68664) (xy 157.17391 62.70037) (xy 157.17391 62.7141) (xy 157.17391 62.72783) (xy 157.17391 62.74156)
			(xy 157.17391 62.7553) (xy 157.17391 62.76903) (xy 157.17391 62.78276) (xy 157.17391 62.79649) (xy 157.17391 62.81022)
			(xy 157.17391 62.82395) (xy 157.17391 62.83769) (xy 157.17391 62.85142) (xy 157.17391 62.86515) (xy 157.17391 62.87888)
			(xy 157.17391 62.89261) (xy 157.17391 62.90635) (xy 157.17391 62.92008) (xy 157.17391 62.93381) (xy 157.17391 62.94754)
			(xy 157.17391 62.96127) (xy 157.17391 62.97501) (xy 157.17391 62.98874) (xy 157.17391 63.00247) (xy 157.17391 63.0162)
			(xy 157.17391 63.02993) (xy 157.17391 63.04366) (xy 157.17391 63.0574) (xy 157.17391 63.07113) (xy 157.17391 63.08486)
			(xy 157.17391 63.09859) (xy 157.17391 63.11232) (xy 157.17391 63.12605) (xy 157.17391 63.13979) (xy 157.17391 63.15352)
			(xy 157.17391 63.16725) (xy 157.17391 63.18098) (xy 157.17391 63.19471) (xy 157.17391 63.20844) (xy 157.17391 63.22218)
			(xy 157.17391 63.23591) (xy 157.17391 63.24964) (xy 157.17391 63.26337) (xy 157.17391 63.2771) (xy 157.17391 63.29083)
			(xy 157.17391 63.30457) (xy 157.17391 63.3183) (xy 157.17391 63.33203) (xy 157.17391 63.34576) (xy 157.17391 63.35949)
			(xy 157.18764 63.35949) (xy 157.18764 63.37322) (xy 157.18764 63.38696) (xy 157.20137 63.38696) (xy 157.20137 63.40069)
			(xy 157.2151 63.40069) (xy 157.2151 63.41442) (xy 157.88796 63.41442) (xy 157.88796 63.40069) (xy 157.91542 63.40069)
			(xy 157.91542 63.38696) (xy 157.91542 63.37322) (xy 157.92916 63.37322) (xy 157.92916 63.35949) (xy 157.92916 63.34576)
			(xy 157.92916 63.33203) (xy 157.92916 63.3183) (xy 157.92916 63.30457) (xy 157.92916 63.29083) (xy 157.92916 63.2771)
			(xy 157.92916 63.26337) (xy 157.92916 63.24964) (xy 157.92916 63.23591) (xy 157.92916 63.22218) (xy 157.92916 63.20844)
			(xy 157.92916 63.19471) (xy 157.92916 63.18098) (xy 157.92916 63.16725) (xy 157.92916 63.15352) (xy 157.92916 63.13979)
			(xy 157.92916 63.12605) (xy 157.92916 63.11232) (xy 157.92916 63.09859) (xy 157.92916 63.08486) (xy 157.92916 63.07113)
			(xy 157.92916 63.0574) (xy 157.92916 63.04366) (xy 157.92916 63.02993) (xy 157.92916 63.0162) (xy 157.92916 63.00247)
			(xy 157.92916 62.98874) (xy 157.92916 62.97501) (xy 157.92916 62.96127) (xy 157.92916 62.94754) (xy 157.92916 62.93381)
			(xy 157.92916 62.92008) (xy 157.92916 62.90635) (xy 157.92916 62.89261) (xy 157.92916 62.87888) (xy 157.92916 62.86515)
			(xy 157.92916 62.85142) (xy 157.92916 62.83769) (xy 157.92916 62.82395) (xy 157.92916 62.81022) (xy 157.92916 62.79649)
			(xy 157.92916 62.78276) (xy 157.92916 62.76903) (xy 157.92916 62.7553) (xy 157.92916 62.74156) (xy 157.92916 62.72783)
			(xy 157.92916 62.7141) (xy 157.92916 62.70037) (xy 157.92916 62.68664) (xy 157.92916 62.67291) (xy 157.92916 62.65917)
			(xy 157.92916 62.64544) (xy 157.92916 62.63171) (xy 157.92916 62.61798) (xy 157.92916 62.60425) (xy 157.92916 62.59052)
			(xy 157.92916 62.57678) (xy 157.92916 62.56305) (xy 157.92916 62.54932) (xy 157.92916 62.53559) (xy 157.92916 62.52186)
			(xy 157.92916 62.50813) (xy 157.92916 62.49439) (xy 157.92916 62.48066) (xy 157.92916 62.46693) (xy 157.92916 62.4532)
			(xy 157.92916 62.43947) (xy 157.92916 62.42574) (xy 157.92916 62.412) (xy 157.92916 62.39827) (xy 157.92916 62.38454)
			(xy 157.92916 62.37081) (xy 157.92916 62.35708) (xy 157.92916 62.34334) (xy 157.92916 62.32961) (xy 157.92916 62.31588)
			(xy 157.92916 62.30215) (xy 157.92916 62.28842) (xy 157.92916 62.27468) (xy 157.92916 62.26095) (xy 157.92916 62.24722)
			(xy 157.92916 62.23349) (xy 157.92916 62.21976) (xy 157.92916 62.20603) (xy 157.92916 62.19229) (xy 157.92916 62.17856)
			(xy 157.92916 62.16483) (xy 157.92916 62.1511) (xy 157.92916 62.13737) (xy 157.92916 62.12364) (xy 157.92916 62.1099)
			(xy 157.92916 62.09617) (xy 157.92916 62.08244) (xy 157.92916 62.06871) (xy 157.92916 62.05498) (xy 157.92916 62.04125)
			(xy 157.92916 62.02751) (xy 157.92916 62.01378) (xy 157.92916 62.00005) (xy 157.92916 61.98632) (xy 157.92916 61.97259)
			(xy 157.92916 61.95886) (xy 157.92916 61.94512) (xy 157.92916 61.93139) (xy 157.92916 61.91766) (xy 157.92916 61.90393)
			(xy 157.92916 61.8902) (xy 157.92916 61.87646) (xy 157.92916 61.86273) (xy 157.92916 61.849) (xy 157.92916 61.83527)
			(xy 157.92916 61.82154) (xy 157.92916 61.8078) (xy 157.92916 61.79407) (xy 157.92916 61.78034) (xy 157.92916 61.76661)
			(xy 157.92916 61.75288) (xy 157.92916 61.73915) (xy 157.92916 61.72541) (xy 157.92916 61.71168) (xy 157.92916 61.69795)
			(xy 157.92916 61.68422) (xy 157.92916 61.67049) (xy 157.92916 61.65676) (xy 157.92916 61.64302) (xy 157.92916 61.62929)
			(xy 157.92916 61.61556) (xy 157.92916 61.60183) (xy 157.92916 61.5881) (xy 157.92916 61.57437) (xy 157.92916 61.56063)
			(xy 157.92916 61.5469) (xy 157.92916 61.53317) (xy 157.92916 61.51944) (xy 157.92916 61.50571) (xy 157.92916 61.49198)
			(xy 157.92916 61.47824) (xy 157.92916 61.46451) (xy 157.92916 61.45078) (xy 157.92916 61.43705) (xy 157.92916 61.42332)
			(xy 157.92916 61.40959) (xy 157.92916 61.39585) (xy 157.92916 61.38212) (xy 157.92916 61.36839) (xy 157.92916 61.35466)
			(xy 157.92916 61.34093) (xy 157.92916 61.32719) (xy 157.92916 61.31346) (xy 157.92916 61.29973) (xy 157.92916 61.286)
			(xy 157.92916 61.27227) (xy 157.92916 61.25853) (xy 157.92916 61.2448) (xy 157.92916 61.23107) (xy 157.92916 61.21734)
			(xy 157.92916 61.20361) (xy 157.92916 61.18988) (xy 157.92916 61.17614) (xy 157.92916 61.16241) (xy 157.92916 61.14868)
			(xy 157.92916 61.13495) (xy 157.92916 61.12122) (xy 157.92916 61.10749) (xy 157.92916 61.09375) (xy 157.92916 61.08002)
			(xy 157.92916 61.06629) (xy 157.92916 61.05256) (xy 157.92916 61.03883) (xy 157.92916 61.0251) (xy 157.92916 61.01136)
			(xy 157.92916 60.99763) (xy 157.92916 60.9839) (xy 157.92916 60.97017) (xy 157.92916 60.95644) (xy 157.92916 60.94271)
			(xy 157.92916 60.92897) (xy 157.92916 60.91524) (xy 157.92916 60.90151) (xy 157.92916 60.88778) (xy 157.92916 60.87405)
			(xy 157.92916 60.86032) (xy 157.92916 60.84658) (xy 157.92916 60.83285) (xy 157.92916 60.81912) (xy 157.92916 60.80539)
			(xy 157.92916 60.79166) (xy 157.92916 60.77792) (xy 157.92916 60.76419) (xy 157.92916 60.75046) (xy 157.92916 60.73673)
			(xy 157.92916 60.723) (xy 157.92916 60.70926) (xy 157.92916 60.69553) (xy 157.92916 60.6818) (xy 157.92916 60.66807)
			(xy 157.92916 60.65434) (xy 157.92916 60.64061) (xy 157.92916 60.62687) (xy 157.92916 60.61314) (xy 157.92916 60.59941)
			(xy 157.92916 60.58568) (xy 157.92916 60.57195) (xy 157.92916 60.55822) (xy 157.92916 60.54448) (xy 157.92916 60.53075)
			(xy 157.92916 60.51702) (xy 157.92916 60.50329) (xy 157.92916 60.48956) (xy 157.92916 60.47583) (xy 157.91542 60.47583)
			(xy 157.91542 60.46209) (xy 158.27245 60.46209) (xy 158.27245 60.47583) (xy 158.27245 60.48956) (xy 158.27245 60.50329)
			(xy 158.27245 60.51702) (xy 158.27245 60.53075) (xy 158.27245 60.54448) (xy 158.27245 60.55822) (xy 158.27245 60.57195)
			(xy 158.27245 60.58568) (xy 158.27245 60.59941) (xy 158.27245 60.61314) (xy 158.27245 60.62687) (xy 158.27245 60.64061)
			(xy 158.27245 60.65434) (xy 158.27245 60.66807) (xy 158.27245 60.6818) (xy 158.27245 60.69553) (xy 158.27245 60.70926)
			(xy 158.27245 60.723) (xy 158.27245 60.73673) (xy 158.27245 60.75046) (xy 158.27245 60.76419) (xy 158.27245 60.77792)
			(xy 158.27245 60.79166) (xy 158.27245 60.80539) (xy 158.27245 60.81912) (xy 158.27245 60.83285) (xy 158.27245 60.84658)
			(xy 158.27245 60.86032) (xy 158.27245 60.87405) (xy 158.27245 60.88778) (xy 158.27245 60.90151) (xy 158.27245 60.91524)
			(xy 158.27245 60.92897) (xy 158.27245 60.94271) (xy 158.27245 60.95644) (xy 158.27245 60.97017) (xy 158.27245 60.9839)
			(xy 158.27245 60.99763) (xy 158.27245 61.01136) (xy 158.27245 61.0251) (xy 158.27245 61.03883) (xy 158.27245 61.05256)
			(xy 158.27245 61.06629) (xy 158.27245 61.08002) (xy 158.27245 61.09375) (xy 158.27245 61.10749) (xy 158.27245 61.12122)
			(xy 158.27245 61.13495) (xy 158.27245 61.14868) (xy 158.27245 61.16241) (xy 158.27245 61.17614) (xy 158.27245 61.18988)
			(xy 158.27245 61.20361) (xy 158.27245 61.21734) (xy 158.27245 61.23107) (xy 158.27245 61.2448) (xy 158.27245 61.25853)
			(xy 158.27245 61.27227) (xy 158.27245 61.286) (xy 158.27245 61.29973) (xy 158.27245 61.31346) (xy 158.27245 61.32719)
			(xy 158.27245 61.34093) (xy 158.27245 61.35466) (xy 158.27245 61.36839) (xy 158.27245 61.38212) (xy 158.27245 61.39585)
			(xy 158.27245 61.40959) (xy 158.27245 61.42332) (xy 158.27245 61.43705) (xy 158.27245 61.45078) (xy 158.27245 61.46451)
			(xy 158.27245 61.47824) (xy 158.27245 61.49198) (xy 158.27245 61.50571) (xy 158.27245 61.51944) (xy 158.27245 61.53317)
			(xy 158.27245 61.5469) (xy 158.27245 61.56063) (xy 158.27245 61.57437) (xy 158.27245 61.5881) (xy 158.27245 61.60183)
			(xy 158.27245 61.61556) (xy 158.27245 61.62929) (xy 158.27245 61.64302) (xy 158.27245 61.65676) (xy 158.27245 61.67049)
			(xy 158.27245 61.68422) (xy 158.27245 61.69795) (xy 158.27245 61.71168) (xy 158.27245 61.72541) (xy 158.27245 61.73915)
			(xy 158.27245 61.75288) (xy 158.27245 61.76661) (xy 158.27245 61.78034) (xy 158.27245 61.79407) (xy 158.27245 61.8078)
			(xy 158.27245 61.82154) (xy 158.27245 61.83527) (xy 158.27245 61.849) (xy 158.27245 61.86273) (xy 158.27245 61.87646)
			(xy 158.27245 61.8902) (xy 158.27245 61.90393) (xy 158.27245 61.91766) (xy 158.27245 61.93139) (xy 158.27245 61.94512)
			(xy 158.27245 61.95886) (xy 158.27245 61.97259) (xy 158.27245 61.98632) (xy 158.27245 62.00005) (xy 158.27245 62.01378)
			(xy 158.27245 62.02751) (xy 158.27245 62.04125) (xy 158.27245 62.05498) (xy 158.27245 62.06871) (xy 158.27245 62.08244)
			(xy 158.27245 62.09617) (xy 158.27245 62.1099) (xy 158.27245 62.12364) (xy 158.27245 62.13737) (xy 158.27245 62.1511)
			(xy 158.27245 62.16483) (xy 158.27245 62.17856) (xy 158.27245 62.19229) (xy 158.27245 62.20603) (xy 158.27245 62.21976)
			(xy 158.27245 62.23349) (xy 158.27245 62.24722) (xy 158.27245 62.26095) (xy 158.27245 62.27468) (xy 158.27245 62.28842)
			(xy 158.27245 62.30215) (xy 158.27245 62.31588) (xy 158.27245 62.32961) (xy 158.27245 62.34334) (xy 158.27245 62.35708)
			(xy 158.27245 62.37081) (xy 158.27245 62.38454) (xy 158.27245 62.39827) (xy 158.27245 62.412) (xy 158.27245 62.42574)
			(xy 158.27245 62.43947) (xy 158.27245 62.4532) (xy 158.27245 62.46693) (xy 158.27245 62.48066) (xy 158.27245 62.49439)
			(xy 158.27245 62.50813) (xy 158.27245 62.52186) (xy 158.27245 62.53559) (xy 158.27245 62.54932) (xy 158.27245 62.56305)
			(xy 158.27245 62.57678) (xy 158.27245 62.59052) (xy 158.27245 62.60425) (xy 158.27245 62.61798) (xy 158.27245 62.63171)
			(xy 158.27245 62.64544) (xy 158.27245 62.65917) (xy 158.27245 62.67291) (xy 158.27245 62.68664) (xy 158.27245 62.70037)
			(xy 158.27245 62.7141) (xy 158.27245 62.72783) (xy 158.27245 62.74156) (xy 158.27245 62.7553) (xy 158.27245 62.76903)
			(xy 158.27245 62.78276) (xy 158.27245 62.79649) (xy 158.27245 62.81022) (xy 158.27245 62.82395) (xy 158.27245 62.83769)
			(xy 158.27245 62.85142) (xy 158.27245 62.86515) (xy 158.27245 62.87888) (xy 158.27245 62.89261) (xy 158.27245 62.90635)
			(xy 158.27245 62.92008) (xy 158.27245 62.93381) (xy 158.27245 62.94754) (xy 158.27245 62.96127) (xy 158.27245 62.97501)
			(xy 158.27245 62.98874) (xy 158.27245 63.00247) (xy 158.27245 63.0162) (xy 158.27245 63.02993) (xy 158.27245 63.04366)
			(xy 158.27245 63.0574) (xy 158.27245 63.07113) (xy 158.27245 63.08486) (xy 158.27245 63.09859) (xy 158.27245 63.11232)
			(xy 158.27245 63.12605) (xy 158.27245 63.13979) (xy 158.27245 63.15352) (xy 158.27245 63.16725) (xy 158.27245 63.18098)
			(xy 158.27245 63.19471) (xy 158.27245 63.20844) (xy 158.27245 63.22218) (xy 158.27245 63.23591) (xy 158.27245 63.24964)
			(xy 158.27245 63.26337) (xy 158.27245 63.2771) (xy 158.27245 63.29083) (xy 158.27245 63.30457) (xy 158.27245 63.3183)
			(xy 158.27245 63.33203) (xy 158.27245 63.34576) (xy 158.27245 63.35949) (xy 158.27245 63.37322) (xy 158.27245 63.38696)
			(xy 158.28618 63.38696) (xy 158.28618 63.40069) (xy 158.29991 63.40069) (xy 158.29991 63.41442) (xy 158.9865 63.41442)
			(xy 158.9865 63.40069) (xy 159.00023 63.40069) (xy 159.00023 63.38696) (xy 159.01396 63.38696) (xy 159.01396 63.37322)
			(xy 159.01396 63.35949) (xy 159.0277 63.35949) (xy 159.0277 63.34576) (xy 159.0277 63.33203) (xy 159.0277 63.3183)
			(xy 159.0277 63.30457) (xy 159.0277 63.29083) (xy 159.0277 63.2771) (xy 159.0277 63.26337) (xy 159.0277 63.24964)
			(xy 159.0277 63.23591) (xy 159.0277 63.22218) (xy 159.0277 63.20844) (xy 159.0277 63.19471) (xy 159.0277 63.18098)
			(xy 159.0277 63.16725) (xy 159.0277 63.15352) (xy 159.0277 63.13979) (xy 159.0277 63.12605) (xy 159.0277 63.11232)
			(xy 159.0277 63.09859) (xy 159.0277 63.08486) (xy 159.0277 63.07113) (xy 159.0277 63.0574) (xy 159.0277 63.04366)
			(xy 159.0277 63.02993) (xy 159.0277 63.0162) (xy 159.0277 63.00247) (xy 159.0277 62.98874) (xy 159.0277 62.97501)
			(xy 159.0277 62.96127) (xy 159.0277 62.94754) (xy 159.0277 62.93381) (xy 159.0277 62.92008) (xy 159.0277 62.90635)
			(xy 159.0277 62.89261) (xy 159.0277 62.87888) (xy 159.0277 62.86515) (xy 159.0277 62.85142) (xy 159.0277 62.83769)
			(xy 159.0277 62.82395) (xy 159.0277 62.81022) (xy 159.0277 62.79649) (xy 159.0277 62.78276) (xy 159.0277 62.76903)
			(xy 159.0277 62.7553) (xy 159.0277 62.74156) (xy 159.0277 62.72783) (xy 159.0277 62.7141) (xy 159.0277 62.70037)
			(xy 159.0277 62.68664) (xy 159.0277 62.67291) (xy 159.0277 62.65917) (xy 159.0277 62.64544) (xy 159.0277 62.63171)
			(xy 159.0277 62.61798) (xy 159.0277 62.60425) (xy 159.0277 62.59052) (xy 159.0277 62.57678) (xy 159.0277 62.56305)
			(xy 159.0277 62.54932) (xy 159.0277 62.53559) (xy 159.0277 62.52186) (xy 159.0277 62.50813) (xy 159.0277 62.49439)
			(xy 159.0277 62.48066) (xy 159.0277 62.46693) (xy 159.0277 62.4532) (xy 159.0277 62.43947) (xy 159.0277 62.42574)
			(xy 159.0277 62.412) (xy 159.0277 62.39827) (xy 159.0277 62.38454) (xy 159.0277 62.37081) (xy 159.0277 62.35708)
			(xy 159.0277 62.34334) (xy 159.0277 62.32961) (xy 159.0277 62.31588) (xy 159.0277 62.30215) (xy 159.0277 62.28842)
			(xy 159.0277 62.27468) (xy 159.0277 62.26095) (xy 159.0277 62.24722) (xy 159.0277 62.23349) (xy 159.0277 62.21976)
			(xy 159.0277 62.20603) (xy 159.0277 62.19229) (xy 159.0277 62.17856) (xy 159.0277 62.16483) (xy 159.0277 62.1511)
			(xy 159.0277 62.13737) (xy 159.0277 62.12364) (xy 159.0277 62.1099) (xy 159.0277 62.09617) (xy 159.0277 62.08244)
			(xy 159.0277 62.06871) (xy 159.0277 62.05498) (xy 159.0277 62.04125) (xy 159.0277 62.02751) (xy 159.0277 62.01378)
			(xy 159.0277 62.00005) (xy 159.0277 61.98632) (xy 159.0277 61.97259) (xy 159.0277 61.95886) (xy 159.0277 61.94512)
			(xy 159.0277 61.93139) (xy 159.0277 61.91766) (xy 159.0277 61.90393) (xy 159.0277 61.8902) (xy 159.0277 61.87646)
			(xy 159.0277 61.86273) (xy 159.0277 61.849) (xy 159.0277 61.83527) (xy 159.0277 61.82154) (xy 159.0277 61.8078)
			(xy 159.0277 61.79407) (xy 159.0277 61.78034) (xy 159.0277 61.76661) (xy 159.0277 61.75288) (xy 159.0277 61.73915)
			(xy 159.0277 61.72541) (xy 159.0277 61.71168) (xy 159.0277 61.69795) (xy 159.0277 61.68422) (xy 159.0277 61.67049)
			(xy 159.0277 61.65676) (xy 159.0277 61.64302) (xy 159.0277 61.62929) (xy 159.0277 61.61556) (xy 159.0277 61.60183)
			(xy 159.0277 61.5881) (xy 159.0277 61.57437) (xy 159.0277 61.56063) (xy 159.0277 61.5469) (xy 159.0277 61.53317)
			(xy 159.0277 61.51944) (xy 159.0277 61.50571) (xy 159.0277 61.49198) (xy 159.0277 61.47824) (xy 159.0277 61.46451)
			(xy 159.0277 61.45078) (xy 159.0277 61.43705) (xy 159.0277 61.42332) (xy 159.0277 61.40959) (xy 159.0277 61.39585)
			(xy 159.0277 61.38212) (xy 159.0277 61.36839) (xy 159.0277 61.35466) (xy 159.0277 61.34093) (xy 159.0277 61.32719)
			(xy 159.0277 61.31346) (xy 159.0277 61.29973) (xy 159.0277 61.286) (xy 159.0277 61.27227) (xy 159.0277 61.25853)
			(xy 159.0277 61.2448) (xy 159.0277 61.23107) (xy 159.0277 61.21734) (xy 159.0277 61.20361) (xy 159.0277 61.18988)
			(xy 159.0277 61.17614) (xy 159.0277 61.16241) (xy 159.0277 61.14868) (xy 159.0277 61.13495) (xy 159.0277 61.12122)
			(xy 159.0277 61.10749) (xy 159.0277 61.09375) (xy 159.0277 61.08002) (xy 159.0277 61.06629) (xy 159.0277 61.05256)
			(xy 159.0277 61.03883) (xy 159.0277 61.0251) (xy 159.0277 61.01136) (xy 159.0277 60.99763) (xy 159.0277 60.9839)
			(xy 159.0277 60.97017) (xy 159.0277 60.95644) (xy 159.0277 60.94271) (xy 159.0277 60.92897) (xy 159.0277 60.91524)
			(xy 159.0277 60.90151) (xy 159.0277 60.88778) (xy 159.0277 60.87405) (xy 159.0277 60.86032) (xy 159.0277 60.84658)
			(xy 159.0277 60.83285) (xy 159.0277 60.81912) (xy 159.0277 60.80539) (xy 159.0277 60.79166) (xy 159.0277 60.77792)
			(xy 159.0277 60.76419) (xy 159.0277 60.75046) (xy 159.0277 60.73673) (xy 159.0277 60.723) (xy 159.0277 60.70926)
			(xy 159.0277 60.69553) (xy 159.0277 60.6818) (xy 159.0277 60.66807) (xy 159.0277 60.65434) (xy 159.0277 60.64061)
			(xy 159.0277 60.62687) (xy 159.0277 60.61314) (xy 159.0277 60.59941) (xy 159.0277 60.58568) (xy 159.0277 60.57195)
			(xy 159.0277 60.55822) (xy 159.0277 60.54448) (xy 159.0277 60.53075) (xy 159.0277 60.51702) (xy 159.0277 60.50329)
			(xy 159.19248 60.50329) (xy 159.19248 60.51702) (xy 159.19248 60.53075) (xy 159.19248 60.54448) (xy 159.19248 60.55822)
			(xy 159.19248 60.57195) (xy 159.19248 60.58568) (xy 159.19248 60.59941) (xy 159.19248 60.61314) (xy 159.19248 60.62687)
			(xy 159.19248 60.64061) (xy 159.19248 60.65434) (xy 159.19248 60.66807) (xy 159.19248 60.6818) (xy 159.19248 60.69553)
			(xy 159.19248 60.70926) (xy 159.19248 60.723) (xy 159.19248 60.73673) (xy 159.19248 60.75046) (xy 159.19248 60.76419)
			(xy 159.19248 60.77792) (xy 159.19248 60.79166) (xy 159.19248 60.80539) (xy 159.19248 60.81912) (xy 159.19248 60.83285)
			(xy 159.19248 60.84658) (xy 159.19248 60.86032) (xy 159.19248 60.87405) (xy 159.19248 60.88778) (xy 159.19248 60.90151)
			(xy 159.19248 60.91524) (xy 159.19248 60.92897) (xy 159.19248 60.94271) (xy 159.19248 60.95644) (xy 159.19248 60.97017)
			(xy 159.19248 60.9839) (xy 159.19248 60.99763) (xy 159.19248 61.01136) (xy 159.19248 61.0251) (xy 159.19248 61.03883)
			(xy 159.19248 61.05256) (xy 159.19248 61.06629) (xy 159.19248 61.08002) (xy 159.20621 61.08002) (xy 159.20621 61.09375)
			(xy 159.20621 61.10749) (xy 159.20621 61.12122) (xy 159.21994 61.12122) (xy 159.21994 61.13495) (xy 159.23367 61.13495)
			(xy 159.23367 61.14868) (xy 159.27487 61.14868) (xy 159.27487 61.16241) (xy 159.93399 61.16241) (xy 159.93399 61.17614)
			(xy 159.94772 61.17614) (xy 159.94772 61.18988) (xy 159.96146 61.18988) (xy 159.96146 61.20361) (xy 159.96146 61.21734)
			(xy 159.96146 61.23107) (xy 159.96146 61.2448) (xy 159.96146 61.25853) (xy 159.96146 61.27227) (xy 159.96146 61.286)
			(xy 159.96146 61.29973) (xy 159.96146 61.31346) (xy 159.96146 61.32719) (xy 159.96146 61.34093) (xy 159.96146 61.35466)
			(xy 159.96146 61.36839) (xy 159.96146 61.38212) (xy 159.96146 61.39585) (xy 159.96146 61.40959) (xy 159.96146 61.42332)
			(xy 159.96146 61.43705) (xy 159.96146 61.45078) (xy 159.96146 61.46451) (xy 159.96146 61.47824) (xy 159.96146 61.49198)
			(xy 159.96146 61.50571) (xy 159.96146 61.51944) (xy 159.96146 61.53317) (xy 159.96146 61.5469) (xy 159.96146 61.56063)
			(xy 159.96146 61.57437) (xy 159.96146 61.5881) (xy 159.96146 61.60183) (xy 159.96146 61.61556) (xy 159.96146 61.62929)
			(xy 159.96146 61.64302) (xy 159.96146 61.65676) (xy 159.96146 61.67049) (xy 159.96146 61.68422) (xy 159.96146 61.69795)
			(xy 159.96146 61.71168) (xy 159.96146 61.72541) (xy 159.96146 61.73915) (xy 159.96146 61.75288) (xy 159.96146 61.76661)
			(xy 159.96146 61.78034) (xy 159.96146 61.79407) (xy 159.96146 61.8078) (xy 159.96146 61.82154) (xy 159.96146 61.83527)
			(xy 159.96146 61.849) (xy 159.96146 61.86273) (xy 159.96146 61.87646) (xy 159.96146 61.8902) (xy 159.96146 61.90393)
			(xy 159.96146 61.91766) (xy 159.96146 61.93139) (xy 159.96146 61.94512) (xy 159.96146 61.95886) (xy 159.96146 61.97259)
			(xy 159.96146 61.98632) (xy 159.96146 62.00005) (xy 159.96146 62.01378) (xy 159.96146 62.02751) (xy 159.96146 62.04125)
			(xy 159.96146 62.05498) (xy 159.96146 62.06871) (xy 159.96146 62.08244) (xy 159.96146 62.09617) (xy 159.96146 62.1099)
			(xy 159.96146 62.12364) (xy 159.96146 62.13737) (xy 159.96146 62.1511) (xy 159.96146 62.16483) (xy 159.96146 62.17856)
			(xy 159.96146 62.19229) (xy 159.96146 62.20603) (xy 159.96146 62.21976) (xy 159.96146 62.23349) (xy 159.96146 62.24722)
			(xy 159.96146 62.26095) (xy 159.96146 62.27468) (xy 159.96146 62.28842) (xy 159.96146 62.30215) (xy 159.96146 62.31588)
			(xy 159.96146 62.32961) (xy 159.96146 62.34334) (xy 159.96146 62.35708) (xy 159.96146 62.37081) (xy 159.96146 62.38454)
			(xy 159.96146 62.39827) (xy 159.96146 62.412) (xy 159.96146 62.42574) (xy 159.96146 62.43947) (xy 159.96146 62.4532)
			(xy 159.96146 62.46693) (xy 159.96146 62.48066) (xy 159.96146 62.49439) (xy 159.96146 62.50813) (xy 159.96146 62.52186)
			(xy 159.96146 62.53559) (xy 159.96146 62.54932) (xy 159.96146 62.56305) (xy 159.96146 62.57678) (xy 159.96146 62.59052)
			(xy 159.96146 62.60425) (xy 159.96146 62.61798) (xy 159.96146 62.63171) (xy 159.96146 62.64544) (xy 159.96146 62.65917)
			(xy 159.96146 62.67291) (xy 159.96146 62.68664) (xy 159.96146 62.70037) (xy 159.96146 62.7141) (xy 159.96146 62.72783)
			(xy 159.96146 62.74156) (xy 159.96146 62.7553) (xy 159.96146 62.76903) (xy 159.96146 62.78276) (xy 159.96146 62.79649)
			(xy 159.96146 62.81022) (xy 159.96146 62.82395) (xy 159.96146 62.83769) (xy 159.96146 62.85142) (xy 159.96146 62.86515)
			(xy 159.96146 62.87888) (xy 159.96146 62.89261) (xy 159.96146 62.90635) (xy 159.96146 62.92008) (xy 159.96146 62.93381)
			(xy 159.96146 62.94754) (xy 159.96146 62.96127) (xy 159.96146 62.97501) (xy 159.96146 62.98874) (xy 159.96146 63.00247)
			(xy 159.96146 63.0162) (xy 159.96146 63.02993) (xy 159.96146 63.04366) (xy 159.96146 63.0574) (xy 159.96146 63.07113)
			(xy 159.96146 63.08486) (xy 159.96146 63.09859) (xy 159.96146 63.11232) (xy 159.96146 63.12605) (xy 159.96146 63.13979)
			(xy 159.96146 63.15352) (xy 159.96146 63.16725) (xy 159.96146 63.18098) (xy 159.96146 63.19471) (xy 159.96146 63.20844)
			(xy 159.96146 63.22218) (xy 159.96146 63.23591) (xy 159.96146 63.24964) (xy 159.96146 63.26337) (xy 159.96146 63.2771)
			(xy 159.96146 63.29083) (xy 159.96146 63.30457) (xy 159.96146 63.3183) (xy 159.96146 63.33203) (xy 159.96146 63.34576)
			(xy 159.97519 63.34576) (xy 159.97519 63.35949) (xy 159.97519 63.37322) (xy 159.97519 63.38696) (xy 159.98892 63.38696)
			(xy 159.98892 63.40069) (xy 160.00265 63.40069) (xy 160.00265 63.41442) (xy 160.67551 63.41442) (xy 160.67551 63.40069)
			(xy 160.68924 63.40069) (xy 160.68924 63.38696) (xy 160.70297 63.38696) (xy 160.70297 63.37322) (xy 160.7167 63.37322)
			(xy 160.7167 63.35949) (xy 160.7167 63.34576) (xy 160.7167 63.33203) (xy 160.7167 63.3183) (xy 160.7167 63.30457)
			(xy 160.7167 63.29083) (xy 160.7167 63.2771) (xy 160.7167 63.26337) (xy 160.7167 63.24964) (xy 160.7167 63.23591)
			(xy 160.7167 63.22218) (xy 160.7167 63.20844) (xy 160.7167 63.19471) (xy 160.7167 63.18098) (xy 160.7167 63.16725)
			(xy 160.7167 63.15352) (xy 160.7167 63.13979) (xy 160.7167 63.12605) (xy 160.7167 63.11232) (xy 160.7167 63.09859)
			(xy 160.7167 63.08486) (xy 160.7167 63.07113) (xy 160.7167 63.0574) (xy 160.7167 63.04366) (xy 160.7167 63.02993)
			(xy 160.7167 63.0162) (xy 160.7167 63.00247) (xy 160.7167 62.98874) (xy 160.7167 62.97501) (xy 160.7167 62.96127)
			(xy 160.7167 62.94754) (xy 160.7167 62.93381) (xy 160.7167 62.92008) (xy 160.7167 62.90635) (xy 160.7167 62.89261)
			(xy 160.7167 62.87888) (xy 160.7167 62.86515) (xy 160.7167 62.85142) (xy 160.7167 62.83769) (xy 160.7167 62.82395)
			(xy 160.7167 62.81022) (xy 160.7167 62.79649) (xy 160.7167 62.78276) (xy 160.7167 62.76903) (xy 160.7167 62.7553)
			(xy 160.7167 62.74156) (xy 160.7167 62.72783) (xy 160.7167 62.7141) (xy 160.7167 62.70037) (xy 160.7167 62.68664)
			(xy 160.7167 62.67291) (xy 160.7167 62.65917) (xy 160.7167 62.64544) (xy 160.7167 62.63171) (xy 160.7167 62.61798)
			(xy 160.7167 62.60425) (xy 160.7167 62.59052) (xy 160.7167 62.57678) (xy 160.7167 62.56305) (xy 160.7167 62.54932)
			(xy 160.7167 62.53559) (xy 160.7167 62.52186) (xy 160.7167 62.50813) (xy 160.7167 62.49439) (xy 160.7167 62.48066)
			(xy 160.7167 62.46693) (xy 160.7167 62.4532) (xy 160.7167 62.43947) (xy 160.7167 62.42574) (xy 160.7167 62.412)
			(xy 160.7167 62.39827) (xy 160.7167 62.38454) (xy 160.7167 62.37081) (xy 160.7167 62.35708) (xy 160.7167 62.34334)
			(xy 160.7167 62.32961) (xy 160.7167 62.31588) (xy 160.7167 62.30215) (xy 160.7167 62.28842) (xy 160.7167 62.27468)
			(xy 160.7167 62.26095) (xy 160.7167 62.24722) (xy 160.7167 62.23349) (xy 160.7167 62.21976) (xy 160.7167 62.20603)
			(xy 160.7167 62.19229) (xy 160.7167 62.17856) (xy 160.7167 62.16483) (xy 160.7167 62.1511) (xy 160.7167 62.13737)
			(xy 160.7167 62.12364) (xy 160.7167 62.1099) (xy 160.7167 62.09617) (xy 160.7167 62.08244) (xy 160.7167 62.06871)
			(xy 160.7167 62.05498) (xy 160.7167 62.04125) (xy 160.7167 62.02751) (xy 160.7167 62.01378) (xy 160.7167 62.00005)
			(xy 160.7167 61.98632) (xy 160.7167 61.97259) (xy 160.7167 61.95886) (xy 160.7167 61.94512) (xy 160.7167 61.93139)
			(xy 160.7167 61.91766) (xy 160.7167 61.90393) (xy 160.7167 61.8902) (xy 160.7167 61.87646) (xy 160.7167 61.86273)
			(xy 160.7167 61.849) (xy 160.7167 61.83527) (xy 160.7167 61.82154) (xy 160.7167 61.8078) (xy 160.7167 61.79407)
			(xy 160.7167 61.78034) (xy 160.7167 61.76661) (xy 160.7167 61.75288) (xy 160.7167 61.73915) (xy 160.7167 61.72541)
			(xy 160.7167 61.71168) (xy 160.7167 61.69795) (xy 160.7167 61.68422) (xy 160.7167 61.67049) (xy 160.7167 61.65676)
			(xy 160.7167 61.64302) (xy 160.7167 61.62929) (xy 160.7167 61.61556) (xy 160.7167 61.60183) (xy 160.7167 61.5881)
			(xy 160.7167 61.57437) (xy 160.7167 61.56063) (xy 160.7167 61.5469) (xy 160.7167 61.53317) (xy 160.7167 61.51944)
			(xy 160.7167 61.50571) (xy 160.7167 61.49198) (xy 160.7167 61.47824) (xy 160.7167 61.46451) (xy 160.7167 61.45078)
			(xy 160.7167 61.43705) (xy 160.7167 61.42332) (xy 160.7167 61.40959) (xy 160.7167 61.39585) (xy 160.7167 61.38212)
			(xy 160.7167 61.36839) (xy 160.7167 61.35466) (xy 160.7167 61.34093) (xy 160.7167 61.32719) (xy 160.7167 61.31346)
			(xy 160.7167 61.29973) (xy 160.7167 61.286) (xy 160.7167 61.27227) (xy 160.7167 61.25853) (xy 160.7167 61.2448)
			(xy 160.7167 61.23107) (xy 160.7167 61.21734) (xy 160.73043 61.21734) (xy 160.73043 61.20361) (xy 160.73043 61.18988)
			(xy 160.74416 61.18988) (xy 160.74416 61.17614) (xy 160.7579 61.17614) (xy 160.7579 61.16241) (xy 161.41702 61.16241)
			(xy 161.41702 61.14868) (xy 161.44448 61.14868) (xy 161.44448 61.13495) (xy 161.45822 61.13495) (xy 161.45822 61.12122)
			(xy 161.47195 61.12122) (xy 161.47195 61.10749) (xy 161.48568 61.10749) (xy 161.48568 61.09375) (xy 161.48568 61.08002)
			(xy 161.48568 61.06629) (xy 161.48568 61.05256) (xy 161.48568 61.03883) (xy 161.48568 61.0251) (xy 161.48568 61.01136)
			(xy 161.48568 60.99763) (xy 161.48568 60.9839) (xy 161.48568 60.97017) (xy 161.48568 60.95644) (xy 161.48568 60.94271)
			(xy 161.48568 60.92897) (xy 161.48568 60.91524) (xy 161.48568 60.90151) (xy 161.48568 60.88778) (xy 161.48568 60.87405)
			(xy 161.48568 60.86032) (xy 161.48568 60.84658) (xy 161.48568 60.83285) (xy 161.48568 60.81912) (xy 161.48568 60.80539)
			(xy 161.48568 60.79166) (xy 161.48568 60.77792) (xy 161.48568 60.76419) (xy 161.48568 60.75046) (xy 161.48568 60.73673)
			(xy 161.48568 60.723) (xy 161.48568 60.70926) (xy 161.48568 60.69553) (xy 161.48568 60.6818) (xy 161.48568 60.66807)
			(xy 161.48568 60.65434) (xy 161.48568 60.64061) (xy 161.48568 60.62687) (xy 161.48568 60.61314) (xy 161.48568 60.59941)
			(xy 161.48568 60.58568) (xy 161.48568 60.57195) (xy 161.48568 60.55822) (xy 161.48568 60.54448) (xy 161.48568 60.53075)
			(xy 161.48568 60.51702) (xy 161.48568 60.50329) (xy 161.48568 60.48956) (xy 161.48568 60.47583) (xy 161.47195 60.47583)
			(xy 161.47195 60.46209) (xy 161.47195 60.44836) (xy 161.45822 60.44836) (xy 161.45822 60.43463) (xy 161.41702 60.43463)
			(xy 161.41702 60.4209) (xy 159.30233 60.4209) (xy 159.30233 60.43463) (xy 159.2886 60.43463) (xy 159.2886 60.4209)
			(xy 159.26113 60.4209) (xy 159.26113 60.43463) (xy 159.23367 60.43463) (xy 159.23367 60.44836) (xy 159.21994 60.44836)
			(xy 159.21994 60.46209) (xy 159.20621 60.46209) (xy 159.20621 60.47583) (xy 159.20621 60.48956) (xy 159.20621 60.50329)
			(xy 159.19248 60.50329) (xy 159.0277 60.50329) (xy 159.0277 60.48956) (xy 159.01396 60.48956) (xy 159.01396 60.47583)
			(xy 159.01396 60.46209) (xy 159.00023 60.46209) (xy 159.00023 60.44836) (xy 159.00023 60.43463) (xy 158.95904 60.43463)
			(xy 158.95904 60.4209) (xy 158.32738 60.4209) (xy 158.32738 60.43463) (xy 158.29991 60.43463) (xy 158.29991 60.44836)
			(xy 158.28618 60.44836) (xy 158.28618 60.46209) (xy 158.27245 60.46209) (xy 157.91542 60.46209) (xy 157.91542 60.44836)
			(xy 157.90169 60.44836) (xy 157.90169 60.43463) (xy 157.8605 60.43463) (xy 157.8605 60.4209) (xy 155.75954 60.4209)
			(xy 155.75954 60.43463) (xy 155.5261 60.43463) (xy 155.5261 60.4209) (xy 155.5261 60.40717) (xy 155.5261 60.39344)
			(xy 155.5261 60.3797) (xy 155.5261 60.36597) (xy 155.5261 60.35224) (xy 155.5261 60.33851) (xy 155.5261 60.32478)
			(xy 155.5261 60.31105) (xy 155.5261 60.29731) (xy 155.5261 60.28358) (xy 155.5261 60.26985) (xy 155.5261 60.25612)
			(xy 155.5261 60.24239) (xy 155.5261 60.22865) (xy 155.5261 60.21492) (xy 155.5261 60.20119) (xy 155.5261 60.18746)
			(xy 155.5261 60.17373) (xy 155.5261 60.15999) (xy 155.5261 60.14626) (xy 155.5261 60.13253) (xy 155.5261 60.1188)
			(xy 155.5261 60.10507) (xy 155.5261 60.09134) (xy 155.5261 60.0776) (xy 155.5261 60.06387) (xy 155.5261 60.05014)
			(xy 155.5261 60.03641) (xy 155.5261 60.02268) (xy 155.5261 60.00895) (xy 155.5261 59.99521) (xy 155.5261 59.98148)
			(xy 155.5261 59.96775) (xy 155.5261 59.95402) (xy 155.5261 59.94029) (xy 155.5261 59.92656) (xy 155.5261 59.91282)
			(xy 155.5261 59.89909) (xy 155.5261 59.88536) (xy 155.5261 59.87163) (xy 155.5261 59.8579) (xy 155.5261 59.84417)
			(xy 155.5261 59.83043) (xy 155.5261 59.8167) (xy 155.5261 59.80297) (xy 155.5261 59.78924) (xy 155.5261 59.77551)
			(xy 155.5261 59.76177) (xy 155.5261 59.74804) (xy 155.5261 59.73431) (xy 155.5261 59.72058) (xy 155.5261 59.70685)
			(xy 155.5261 59.69311) (xy 155.5261 59.67938) (xy 155.5261 59.66565) (xy 155.5261 59.65192) (xy 155.5261 59.63819)
			(xy 155.5261 59.62446) (xy 155.5261 59.61072) (xy 155.5261 59.59699) (xy 155.5261 59.58326) (xy 155.5261 59.56953)
			(xy 155.5261 59.5558) (xy 155.5261 59.54207) (xy 155.5261 59.52833) (xy 155.5261 59.5146) (xy 155.5261 59.50087)
			(xy 155.5261 59.48714) (xy 155.5261 59.47341) (xy 155.5261 59.45968) (xy 155.5261 59.44594) (xy 155.5261 59.43221)
			(xy 155.5261 59.41848) (xy 155.5261 59.40475) (xy 155.5261 59.39102) (xy 155.5261 59.37729) (xy 155.5261 59.36355)
			(xy 155.5261 59.34982) (xy 155.5261 59.33609) (xy 155.5261 59.32236) (xy 155.5261 59.30863) (xy 155.5261 59.2949)
			(xy 155.5261 59.28116) (xy 155.5261 59.26743) (xy 155.5261 59.2537) (xy 155.5261 59.23997) (xy 155.5261 59.22624)
			(xy 155.5261 59.2125) (xy 155.5261 59.19877) (xy 155.5261 59.18504) (xy 155.5261 59.17131) (xy 155.5261 59.15758)
			(xy 155.5261 59.14384) (xy 155.5261 59.13011) (xy 155.5261 59.11638) (xy 155.5261 59.10265) (xy 155.5261 59.08892)
			(xy 155.5261 59.07519) (xy 155.5261 59.06145) (xy 155.5261 59.04772) (xy 155.5261 59.03399) (xy 155.5261 59.02026)
			(xy 155.5261 59.00653) (xy 155.5261 58.9928) (xy 155.5261 58.97906) (xy 155.5261 58.96533) (xy 155.5261 58.9516)
			(xy 155.5261 58.93787) (xy 155.5261 58.92414) (xy 155.5261 58.91041) (xy 155.5261 58.89667) (xy 155.5261 58.88294)
			(xy 155.5261 58.86921) (xy 155.5261 58.85548) (xy 155.5261 58.84175) (xy 155.5261 58.82802) (xy 155.5261 58.81428)
			(xy 155.5261 58.80055) (xy 155.5261 58.78682) (xy 155.27893 58.78682) (xy 155.27893 58.80055) (xy 155.224 58.80055)
			(xy 155.224 58.81428) (xy 155.19654 58.81428) (xy 155.19654 58.82802) (xy 155.18281 58.82802) (xy 155.18281 58.84175)
			(xy 155.16907 58.84175) (xy 155.16907 58.85548) (xy 155.15534 58.85548) (xy 155.15534 58.86921) (xy 155.14161 58.86921)
			(xy 155.14161 58.88294) (xy 155.12788 58.88294) (xy 155.12788 58.89667) (xy 155.11415 58.89667) (xy 155.11415 58.91041)
			(xy 155.10041 58.91041) (xy 155.10041 58.92414) (xy 155.08668 58.92414) (xy 155.08668 58.93787) (xy 155.07295 58.93787)
			(xy 155.07295 58.9516) (xy 155.05922 58.9516) (xy 155.05922 58.96533) (xy 155.04549 58.96533) (xy 155.04549 58.97906)
			(xy 155.03175 58.97906) (xy 155.03175 58.9928) (xy 155.01802 58.9928) (xy 155.01802 59.00653) (xy 155.00429 59.00653)
			(xy 155.00429 59.02026) (xy 154.99056 59.02026) (xy 154.99056 59.03399) (xy 154.97683 59.03399) (xy 154.97683 59.04772)
			(xy 154.9631 59.04772) (xy 154.9631 59.06145) (xy 154.94936 59.06145) (xy 154.94936 59.07519) (xy 154.93563 59.07519)
			(xy 154.93563 59.08892) (xy 154.9219 59.08892) (xy 154.9219 59.10265) (xy 154.90817 59.10265) (xy 154.90817 59.11638)
			(xy 154.89444 59.11638) (xy 154.89444 59.13011) (xy 154.88071 59.13011) (xy 154.88071 59.14384) (xy 154.86697 59.14384)
			(xy 154.86697 59.15758) (xy 154.85324 59.15758) (xy 154.85324 59.17131) (xy 154.83951 59.17131) (xy 154.83951 59.18504)
			(xy 154.82578 59.18504) (xy 154.82578 59.19877) (xy 154.81205 59.19877) (xy 154.81205 59.2125) (xy 154.81205 59.22624)
			(xy 154.79832 59.22624) (xy 154.79832 59.23997) (xy 154.79832 59.2537) (xy 154.79832 59.26743) (xy 154.79832 59.28116)
			(xy 154.78458 59.28116) (xy 152.16182 59.28116) (xy 152.16182 59.26743) (xy 152.18928 59.26743) (xy 152.18928 59.2537)
			(xy 152.20302 59.2537) (xy 152.20302 59.23997) (xy 152.23048 59.23997) (xy 152.23048 59.22624) (xy 152.24421 59.22624)
			(xy 152.24421 59.2125) (xy 152.27167 59.2125) (xy 152.27167 59.19877) (xy 152.28541 59.19877) (xy 152.28541 59.18504)
			(xy 152.31287 59.18504) (xy 152.31287 59.17131) (xy 152.3266 59.17131) (xy 152.3266 59.15758) (xy 152.35406 59.15758)
			(xy 152.35406 59.14384) (xy 152.38153 59.14384) (xy 152.38153 59.13011) (xy 152.39526 59.13011) (xy 152.39526 59.11638)
			(xy 152.42272 59.11638) (xy 152.42272 59.10265) (xy 152.45019 59.10265) (xy 152.45019 59.08892) (xy 152.46392 59.08892)
			(xy 152.46392 59.07519) (xy 152.49138 59.07519) (xy 152.49138 59.06145) (xy 152.51885 59.06145) (xy 152.51885 59.04772)
			(xy 152.54631 59.04772) (xy 152.54631 59.03399) (xy 152.56004 59.03399) (xy 152.56004 59.02026) (xy 152.58751 59.02026)
			(xy 152.58751 59.00653) (xy 152.61497 59.00653) (xy 152.61497 58.9928) (xy 152.64243 58.9928) (xy 152.64243 58.97906)
			(xy 152.6699 58.97906) (xy 152.6699 58.96533) (xy 152.69736 58.96533) (xy 152.69736 58.9516) (xy 152.72482 58.9516)
			(xy 152.72482 58.93787) (xy 152.75229 58.93787) (xy 152.75229 58.92414) (xy 152.77975 58.92414) (xy 152.77975 58.91041)
			(xy 152.79348 58.91041) (xy 152.79348 58.89667) (xy 152.82094 58.89667) (xy 152.82094 58.88294) (xy 152.86214 58.88294)
			(xy 152.86214 58.86921) (xy 152.8896 58.86921) (xy 152.8896 58.85548) (xy 152.91707 58.85548) (xy 152.91707 58.84175)
			(xy 152.94453 58.84175) (xy 152.94453 58.82802) (xy 152.97199 58.82802) (xy 152.97199 58.81428) (xy 153.01319 58.81428)
			(xy 153.01319 58.80055) (xy 153.04065 58.80055) (xy 153.04065 58.78682) (xy 153.06812 58.78682) (xy 153.06812 58.77309)
			(xy 153.10931 58.77309) (xy 153.10931 58.75936) (xy 153.13678 58.75936) (xy 153.13678 58.74563) (xy 153.17797 58.74563)
			(xy 153.17797 58.73189) (xy 153.20543 58.73189) (xy 153.20543 58.71816) (xy 153.24663 58.71816) (xy 153.24663 58.70443)
			(xy 153.27409 58.70443) (xy 153.27409 58.6907) (xy 153.31529 58.6907) (xy 153.31529 58.67697) (xy 153.35648 58.67697)
			(xy 153.35648 58.66323) (xy 153.39768 58.66323) (xy 153.39768 58.6495) (xy 153.43887 58.6495) (xy 153.43887 58.63577)
			(xy 153.48007 58.63577) (xy 153.48007 58.62204) (xy 153.52126 58.62204) (xy 153.52126 58.60831) (xy 153.56246 58.60831)
			(xy 153.56246 58.59457) (xy 153.60365 58.59457) (xy 153.60365 58.58084) (xy 153.65858 58.58084) (xy 153.65858 58.56711)
			(xy 153.69978 58.56711) (xy 153.69978 58.55338) (xy 153.7547 58.55338) (xy 153.7547 58.53965) (xy 153.80963 58.53965)
			(xy 153.80963 58.52592) (xy 153.86456 58.52592) (xy 153.86456 58.51218) (xy 153.91948 58.51218) (xy 153.91948 58.49845)
			(xy 153.98814 58.49845) (xy 153.98814 58.48472) (xy 154.0568 58.48472) (xy 154.0568 58.47099) (xy 154.12546 58.47099)
			(xy 154.12546 58.45726) (xy 154.20785 58.45726) (xy 154.20785 58.44353) (xy 154.29024 58.44353) (xy 154.29024 58.42979)
			(xy 154.37263 58.42979) (xy 154.37263 58.41606) (xy 154.49622 58.41606) (xy 154.49622 58.40233) (xy 154.64727 58.40233)
			(xy 154.64727 58.3886) (xy 154.86697 58.3886) (xy 154.86697 58.37487) (xy 154.88071 58.37487) (xy 154.88071 58.3886)
			(xy 154.89444 58.3886) (xy 154.89444 58.37487) (xy 155.23773 58.37487) (xy 155.23773 58.3886) (xy 155.4849 58.3886)
			(xy 155.4849 58.40233) (xy 155.63595 58.40233) (xy 155.63595 58.41606) (xy 155.74581 58.41606) (xy 155.74581 58.42979)
			(xy 155.84193 58.42979) (xy 155.84193 58.44353) (xy 155.92432 58.44353) (xy 155.92432 58.45726) (xy 156.02044 58.45726)
			(xy 156.02044 58.47099) (xy 156.07537 58.47099) (xy 156.07537 58.48472) (xy 156.14403 58.48472) (xy 156.14403 58.49845)
			(xy 156.21269 58.49845) (xy 156.21269 58.51218) (xy 156.26761 58.51218) (xy 156.26761 58.52592) (xy 156.32254 58.52592)
			(xy 156.32254 58.53965) (xy 156.37747 58.53965) (xy 156.37747 58.55338) (xy 156.43239 58.55338) (xy 156.43239 58.56711)
			(xy 156.47359 58.56711) (xy 156.47359 58.58084) (xy 156.52852 58.58084) (xy 156.52852 58.59457) (xy 156.56971 58.59457)
			(xy 156.56971 58.60831) (xy 156.61091 58.60831) (xy 156.61091 58.62204) (xy 156.6521 58.62204) (xy 156.6521 58.63577)
			(xy 156.70703 58.63577) (xy 156.70703 58.6495) (xy 156.73449 58.6495) (xy 156.73449 58.66323) (xy 156.77569 58.66323)
			(xy 156.77569 58.67697) (xy 156.81688 58.67697) (xy 156.81688 58.6907) (xy 156.85808 58.6907) (xy 156.85808 58.70443)
			(xy 156.88554 58.70443) (xy 156.88554 58.71816) (xy 156.92674 58.71816) (xy 156.92674 58.73189) (xy 156.96793 58.73189)
			(xy 156.96793 58.74563) (xy 156.9954 58.74563) (xy 156.9954 58.75936) (xy 157.03659 58.75936) (xy 157.03659 58.77309)
			(xy 157.06405 58.77309) (xy 157.06405 58.78682) (xy 157.09152 58.78682) (xy 157.09152 58.80055) (xy 157.13271 58.80055)
			(xy 157.13271 58.81428) (xy 157.16018 58.81428) (xy 157.16018 58.82802) (xy 157.18764 58.82802) (xy 157.18764 58.84175)
			(xy 157.2151 58.84175) (xy 157.2151 58.85548) (xy 157.24257 58.85548) (xy 157.24257 58.86921) (xy 157.27003 58.86921)
			(xy 157.27003 58.88294) (xy 157.31123 58.88294) (xy 157.31123 58.89667) (xy 157.33869 58.89667) (xy 157.33869 58.91041)
			(xy 157.36615 58.91041) (xy 157.36615 58.92414) (xy 157.39362 58.92414) (xy 157.39362 58.93787) (xy 157.42108 58.93787)
			(xy 157.42108 58.9516) (xy 157.43481 58.9516) (xy 157.43481 58.96533) (xy 157.46228 58.96533) (xy 157.46228 58.97906)
			(xy 157.48974 58.97906) (xy 157.48974 58.9928) (xy 157.5172 58.9928) (xy 157.5172 59.00653) (xy 157.54467 59.00653)
			(xy 157.54467 59.02026) (xy 157.57213 59.02026) (xy 157.57213 59.03399) (xy 157.59959 59.03399) (xy 157.59959 59.04772)
			(xy 157.61332 59.04772) (xy 157.61332 59.06145) (xy 157.64079 59.06145) (xy 157.64079 59.07519) (xy 157.66825 59.07519)
			(xy 157.66825 59.08892) (xy 157.68198 59.08892) (xy 157.68198 59.10265) (xy 157.70945 59.10265) (xy 157.70945 59.11638)
			(xy 157.73691 59.11638) (xy 157.73691 59.13011) (xy 157.75064 59.13011) (xy 157.75064 59.14384) (xy 157.77811 59.14384)
			(xy 157.77811 59.15758) (xy 157.80557 59.15758) (xy 157.80557 59.17131) (xy 157.8193 59.17131) (xy 157.8193 59.18504)
			(xy 157.84677 59.18504) (xy 157.84677 59.19877) (xy 157.8605 59.19877) (xy 157.8605 59.2125) (xy 157.88796 59.2125)
			(xy 157.88796 59.22624) (xy 157.90169 59.22624) (xy 157.90169 59.23997) (xy 157.92916 59.23997) (xy 157.92916 59.2537)
			(xy 157.94289 59.2537) (xy 157.94289 59.26743) (xy 157.97035 59.26743) (xy 157.97035 59.28116) (xy 157.98408 59.28116)
			(xy 157.98408 59.2949) (xy 158.01155 59.2949) (xy 158.01155 59.30863) (xy 158.02528 59.30863) (xy 158.02528 59.32236)
			(xy 158.05274 59.32236) (xy 158.05274 59.33609) (xy 158.06647 59.33609) (xy 158.06647 59.34982) (xy 158.0802 59.34982)
			(xy 158.0802 59.36355) (xy 158.10767 59.36355) (xy 158.10767 59.37729) (xy 158.1214 59.37729) (xy 158.1214 59.39102)
			(xy 158.13513 59.39102) (xy 158.13513 59.40475) (xy 158.16259 59.40475) (xy 158.16259 59.41848) (xy 158.17633 59.41848)
			(xy 158.17633 59.43221) (xy 158.19006 59.43221) (xy 158.19006 59.44594) (xy 158.21752 59.44594) (xy 158.21752 59.45968)
			(xy 158.23125 59.45968) (xy 158.23125 59.47341) (xy 158.24498 59.47341) (xy 158.24498 59.48714) (xy 158.25872 59.48714)
			(xy 158.25872 59.50087) (xy 158.28618 59.50087) (xy 158.28618 59.5146) (xy 158.29991 59.5146) (xy 158.29991 59.52833)
			(xy 158.31364 59.52833) (xy 158.31364 59.54207) (xy 158.32738 59.54207) (xy 158.32738 59.5558) (xy 158.35484 59.5558)
			(xy 158.35484 59.56953) (xy 158.36857 59.56953) (xy 158.36857 59.58326) (xy 158.3823 59.58326) (xy 158.3823 59.59699)
			(xy 158.39604 59.59699) (xy 158.39604 59.61072) (xy 158.40977 59.61072) (xy 158.40977 59.62446) (xy 158.43723 59.62446)
			(xy 158.43723 59.63819) (xy 158.45096 59.63819) (xy 158.45096 59.65192) (xy 158.46469 59.65192) (xy 158.46469 59.66565)
			(xy 158.47843 59.66565) (xy 158.47843 59.67938) (xy 158.49216 59.67938) (xy 158.49216 59.69311) (xy 158.50589 59.69311)
			(xy 158.50589 59.70685) (xy 158.51962 59.70685) (xy 158.51962 59.72058) (xy 158.53335 59.72058) (xy 158.53335 59.73431)
			(xy 158.54708 59.73431) (xy 158.54708 59.74804) (xy 158.57455 59.74804) (xy 158.57455 59.76177) (xy 158.58828 59.76177)
			(xy 158.58828 59.77551) (xy 158.60201 59.77551) (xy 158.60201 59.78924) (xy 158.61574 59.78924) (xy 158.61574 59.80297)
			(xy 158.62947 59.80297) (xy 158.62947 59.8167) (xy 158.64321 59.8167) (xy 158.64321 59.83043) (xy 158.65694 59.83043)
			(xy 158.65694 59.84417) (xy 158.67067 59.84417) (xy 158.67067 59.8579) (xy 158.6844 59.8579) (xy 158.6844 59.87163)
			(xy 158.69813 59.87163) (xy 158.69813 59.88536) (xy 158.71186 59.88536) (xy 158.71186 59.89909) (xy 158.7256 59.89909)
			(xy 158.7256 59.91282) (xy 158.73933 59.91282) (xy 158.73933 59.92656) (xy 158.75306 59.92656) (xy 158.75306 59.94029)
			(xy 158.76679 59.94029) (xy 158.76679 59.95402) (xy 158.78052 59.95402) (xy 158.78052 59.96775) (xy 158.79426 59.96775)
			(xy 158.79426 59.98148) (xy 158.80799 59.98148) (xy 158.80799 59.99521) (xy 158.82172 59.99521) (xy 158.82172 60.00895)
			(xy 158.83545 60.00895) (xy 158.83545 60.02268) (xy 158.84918 60.02268) (xy 158.84918 60.03641) (xy 158.84918 60.05014)
			(xy 158.86292 60.05014) (xy 158.86292 60.06387) (xy 158.87665 60.06387) (xy 158.87665 60.0776) (xy 158.89038 60.0776)
			(xy 158.89038 60.09134) (xy 158.90411 60.09134) (xy 158.90411 60.10507) (xy 158.91784 60.10507) (xy 158.91784 60.1188)
			(xy 158.93157 60.1188) (xy 158.93157 60.13253) (xy 158.94531 60.13253) (xy 158.94531 60.14626) (xy 158.95904 60.14626)
			(xy 158.95904 60.15999) (xy 158.95904 60.17373) (xy 158.97277 60.17373) (xy 158.97277 60.18746) (xy 158.9865 60.18746)
			(xy 158.9865 60.20119) (xy 159.20621 60.20119) (xy 159.20621 60.18746) (xy 159.19248 60.18746) (xy 159.19248 60.17373)
			(xy 159.17874 60.17373) (xy 159.17874 60.15999) (xy 159.16501 60.15999) (xy 159.16501 60.14626) (xy 159.16501 60.13253)
			(xy 159.15128 60.13253) (xy 159.15128 60.1188) (xy 159.13755 60.1188) (xy 159.13755 60.10507) (xy 159.12382 60.10507)
			(xy 159.12382 60.09134) (xy 159.11009 60.09134) (xy 159.11009 60.0776) (xy 159.09635 60.0776) (xy 159.09635 60.06387)
			(xy 159.09635 60.05014) (xy 159.08262 60.05014) (xy 159.08262 60.03641) (xy 159.06889 60.03641) (xy 159.06889 60.02268)
			(xy 159.05516 60.02268) (xy 159.05516 60.00895) (xy 159.04143 60.00895) (xy 159.04143 59.99521) (xy 159.0277 59.99521)
			(xy 159.0277 59.98148) (xy 159.01396 59.98148) (xy 159.01396 59.96775) (xy 159.00023 59.96775) (xy 159.00023 59.95402)
			(xy 158.9865 59.95402) (xy 158.9865 59.94029) (xy 158.9865 59.92656) (xy 158.97277 59.92656) (xy 158.97277 59.91282)
			(xy 158.95904 59.91282) (xy 158.95904 59.89909) (xy 158.94531 59.89909) (xy 158.94531 59.88536) (xy 158.93157 59.88536)
			(xy 158.93157 59.87163) (xy 158.91784 59.87163) (xy 158.91784 59.8579) (xy 158.90411 59.8579) (xy 158.90411 59.84417)
			(xy 158.89038 59.84417) (xy 158.89038 59.83043) (xy 158.87665 59.83043) (xy 158.87665 59.8167) (xy 158.86292 59.8167)
			(xy 158.86292 59.80297) (xy 158.84918 59.80297) (xy 158.84918 59.78924) (xy 158.83545 59.78924) (xy 158.83545 59.77551)
			(xy 158.82172 59.77551) (xy 158.82172 59.76177) (xy 158.80799 59.76177) (xy 158.80799 59.74804) (xy 158.79426 59.74804)
			(xy 158.79426 59.73431) (xy 158.78052 59.73431) (xy 158.78052 59.72058) (xy 158.76679 59.72058) (xy 158.76679 59.70685)
			(xy 158.75306 59.70685) (xy 158.75306 59.69311) (xy 158.73933 59.69311) (xy 158.73933 59.67938) (xy 158.7256 59.67938)
			(xy 158.7256 59.66565) (xy 158.71186 59.66565) (xy 158.71186 59.65192) (xy 158.69813 59.65192) (xy 158.69813 59.63819)
			(xy 158.6844 59.63819) (xy 158.6844 59.62446) (xy 158.67067 59.62446) (xy 158.67067 59.61072) (xy 158.65694 59.61072)
			(xy 158.65694 59.59699) (xy 158.62947 59.59699) (xy 158.62947 59.58326) (xy 158.61574 59.58326) (xy 158.61574 59.56953)
			(xy 158.60201 59.56953) (xy 158.60201 59.5558) (xy 158.58828 59.5558) (xy 158.58828 59.54207) (xy 158.57455 59.54207)
			(xy 158.57455 59.52833) (xy 158.56082 59.52833) (xy 158.56082 59.5146) (xy 158.54708 59.5146) (xy 158.54708 59.50087)
			(xy 158.53335 59.50087) (xy 158.53335 59.48714) (xy 158.50589 59.48714) (xy 158.50589 59.47341) (xy 158.49216 59.47341)
			(xy 158.49216 59.45968) (xy 158.47843 59.45968) (xy 158.47843 59.44594) (xy 158.46469 59.44594) (xy 158.46469 59.43221)
			(xy 158.45096 59.43221) (xy 158.45096 59.41848) (xy 158.4235 59.41848) (xy 158.4235 59.40475) (xy 158.40977 59.40475)
			(xy 158.40977 59.39102) (xy 158.39604 59.39102) (xy 158.39604 59.37729) (xy 158.3823 59.37729) (xy 158.3823 59.36355)
			(xy 158.35484 59.36355) (xy 158.35484 59.34982) (xy 158.34111 59.34982) (xy 158.34111 59.33609) (xy 158.32738 59.33609)
			(xy 158.32738 59.32236) (xy 158.31364 59.32236) (xy 158.31364 59.30863) (xy 158.28618 59.30863) (xy 158.28618 59.2949)
			(xy 158.27245 59.2949) (xy 158.27245 59.28116) (xy 158.25872 59.28116) (xy 158.25872 59.26743) (xy 158.23125 59.26743)
			(xy 158.23125 59.2537) (xy 158.21752 59.2537) (xy 158.21752 59.23997) (xy 158.20379 59.23997) (xy 158.20379 59.22624)
			(xy 158.17633 59.22624) (xy 158.17633 59.2125) (xy 158.16259 59.2125) (xy 158.16259 59.19877) (xy 158.13513 59.19877)
			(xy 158.13513 59.18504) (xy 158.1214 59.18504) (xy 158.1214 59.17131) (xy 158.10767 59.17131) (xy 158.10767 59.15758)
			(xy 158.0802 59.15758) (xy 158.0802 59.14384) (xy 158.06647 59.14384) (xy 158.06647 59.13011) (xy 158.03901 59.13011)
			(xy 158.03901 59.11638) (xy 158.02528 59.11638) (xy 158.02528 59.10265) (xy 157.99781 59.10265) (xy 157.99781 59.08892)
			(xy 157.98408 59.08892) (xy 157.98408 59.07519) (xy 157.95662 59.07519) (xy 157.95662 59.06145) (xy 157.94289 59.06145)
			(xy 157.94289 59.04772) (xy 157.91542 59.04772) (xy 157.91542 59.03399) (xy 157.90169 59.03399) (xy 157.90169 59.02026)
			(xy 157.87423 59.02026) (xy 157.87423 59.00653) (xy 157.84677 59.00653) (xy 157.84677 58.9928) (xy 157.83303 58.9928)
			(xy 157.83303 58.97906) (xy 157.80557 58.97906) (xy 157.80557 58.96533) (xy 157.77811 58.96533) (xy 157.77811 58.9516)
			(xy 157.76437 58.9516) (xy 157.76437 58.93787) (xy 157.73691 58.93787) (xy 157.73691 58.92414) (xy 157.70945 58.92414)
			(xy 157.70945 58.91041) (xy 157.69571 58.91041) (xy 157.69571 58.89667) (xy 157.66825 58.89667) (xy 157.66825 58.88294)
			(xy 157.64079 58.88294) (xy 157.64079 58.86921) (xy 157.61332 58.86921) (xy 157.61332 58.85548) (xy 157.58586 58.85548)
			(xy 157.58586 58.84175) (xy 157.57213 58.84175) (xy 157.57213 58.82802) (xy 157.54467 58.82802) (xy 157.54467 58.81428)
			(xy 157.5172 58.81428) (xy 157.5172 58.80055) (xy 157.48974 58.80055) (xy 157.48974 58.78682) (xy 157.46228 58.78682)
			(xy 157.46228 58.77309) (xy 157.43481 58.77309) (xy 157.43481 58.75936) (xy 157.40735 58.75936) (xy 157.40735 58.74563)
			(xy 157.37989 58.74563) (xy 157.37989 58.73189) (xy 157.35242 58.73189) (xy 157.35242 58.71816) (xy 157.32496 58.71816)
			(xy 157.32496 58.70443) (xy 157.28376 58.70443) (xy 157.28376 58.6907) (xy 157.2563 58.6907) (xy 157.2563 58.67697)
			(xy 157.22884 58.67697) (xy 157.22884 58.66323) (xy 157.20137 58.66323) (xy 157.20137 58.6495) (xy 157.16018 58.6495)
			(xy 157.16018 58.63577) (xy 157.13271 58.63577) (xy 157.13271 58.62204) (xy 157.10525 58.62204) (xy 157.10525 58.60831)
			(xy 157.06405 58.60831) (xy 157.06405 58.59457) (xy 157.03659 58.59457) (xy 157.03659 58.58084) (xy 156.9954 58.58084)
			(xy 156.9954 58.56711) (xy 156.96793 58.56711) (xy 156.96793 58.55338) (xy 156.92674 58.55338) (xy 156.92674 58.53965)
			(xy 156.88554 58.53965) (xy 156.88554 58.52592) (xy 156.84435 58.52592) (xy 156.84435 58.51218) (xy 156.81688 58.51218)
			(xy 156.81688 58.49845) (xy 156.77569 58.49845) (xy 156.77569 58.48472) (xy 156.73449 58.48472) (xy 156.73449 58.47099)
			(xy 156.6933 58.47099) (xy 156.6933 58.45726) (xy 156.63837 58.45726) (xy 156.63837 58.44353) (xy 156.59717 58.44353)
			(xy 156.59717 58.42979) (xy 156.55598 58.42979) (xy 156.55598 58.41606) (xy 156.50105 58.41606) (xy 156.50105 58.40233)
			(xy 156.45986 58.40233) (xy 156.45986 58.3886) (xy 156.40493 58.3886) (xy 156.40493 58.37487) (xy 156.35 58.37487)
			(xy 156.35 58.36114) (xy 156.29508 58.36114) (xy 156.29508 58.3474) (xy 156.24015 58.3474) (xy 156.24015 58.33367)
			(xy 156.17149 58.33367) (xy 156.17149 58.31994) (xy 156.10283 58.31994) (xy 156.10283 58.30621) (xy 156.03417 58.30621)
			(xy 156.03417 58.29248) (xy 155.95178 58.29248) (xy 155.95178 58.27875) (xy 155.85566 58.27875) (xy 155.85566 58.26501)
			(xy 155.77327 58.26501) (xy 155.77327 58.25128) (xy 155.66342 58.25128) (xy 155.66342 58.23755) (xy 155.5261 58.23755)
			(xy 155.5261 58.22382) (xy 155.32012 58.22382) (xy 155.32012 58.21009) (xy 154.81205 58.21009) (xy 154.81205 58.22382)
			(xy 154.60607 58.22382) (xy 154.60607 58.23755) (xy 154.48248 58.23755) (xy 154.48248 58.25128) (xy 154.37263 58.25128)
			(xy 154.37263 58.26501) (xy 154.26278 58.26501) (xy 154.26278 58.27875) (xy 154.18039 58.27875) (xy 154.18039 58.29248)
			(xy 154.098 58.29248) (xy 154.098 58.30621) (xy 154.02934 58.30621) (xy 154.02934 58.31994) (xy 153.96068 58.31994)
			(xy 153.96068 58.33367) (xy 153.89202 58.33367) (xy 153.89202 58.3474) (xy 153.83709 58.3474) (xy 153.83709 58.36114)
			(xy 153.78217 58.36114) (xy 153.78217 58.37487) (xy 153.72724 58.37487) (xy 153.72724 58.3886) (xy 153.67231 58.3886)
			(xy 153.67231 58.40233) (xy 153.63112 58.40233) (xy 153.63112 58.41606) (xy 153.57619 58.41606) (xy 153.57619 58.42979)
			(xy 153.53499 58.42979) (xy 153.53499 58.44353) (xy 153.4938 58.44353) (xy 153.4938 58.45726) (xy 153.43887 58.45726)
			(xy 153.43887 58.47099) (xy 153.39768 58.47099) (xy 153.39768 58.48472) (xy 153.35648 58.48472) (xy 153.35648 58.49845)
			(xy 153.32902 58.49845) (xy 153.32902 58.51218) (xy 153.28782 58.51218) (xy 153.28782 58.52592) (xy 153.24663 58.52592)
			(xy 153.24663 58.53965) (xy 153.20543 58.53965) (xy 153.20543 58.55338) (xy 153.17797 58.55338) (xy 153.17797 58.56711)
			(xy 153.13678 58.56711) (xy 153.13678 58.58084) (xy 153.09558 58.58084) (xy 153.09558 58.59457) (xy 153.06812 58.59457)
			(xy 153.06812 58.60831) (xy 153.02692 58.60831) (xy 153.02692 58.62204) (xy 152.99946 58.62204) (xy 152.99946 58.63577)
			(xy 152.97199 58.63577) (xy 152.97199 58.6495) (xy 152.9308 58.6495) (xy 152.9308 58.66323) (xy 152.90333 58.66323)
			(xy 152.90333 58.67697) (xy 152.87587 58.67697) (xy 152.87587 58.6907) (xy 152.84841 58.6907) (xy 152.84841 58.70443)
			(xy 152.82094 58.70443) (xy 152.82094 58.71816) (xy 152.77975 58.71816) (xy 152.77975 58.73189) (xy 152.75229 58.73189)
			(xy 152.75229 58.74563) (xy 152.73855 58.74563) (xy 152.73855 58.75936) (xy 152.71109 58.75936) (xy 152.71109 58.77309)
			(xy 152.6699 58.77309) (xy 152.6699 58.78682) (xy 152.64243 58.78682) (xy 152.64243 58.80055) (xy 152.6287 58.80055)
			(xy 152.6287 58.81428) (xy 152.58751 58.81428) (xy 152.58751 58.82802) (xy 152.57377 58.82802) (xy 152.57377 58.84175)
			(xy 152.54631 58.84175) (xy 152.54631 58.85548) (xy 152.51885 58.85548) (xy 152.51885 58.86921) (xy 152.49138 58.86921)
			(xy 152.49138 58.88294) (xy 152.46392 58.88294) (xy 152.46392 58.89667) (xy 152.45019 58.89667) (xy 152.45019 58.91041)
			(xy 152.42272 58.91041) (xy 152.42272 58.92414) (xy 152.39526 58.92414) (xy 152.39526 58.93787) (xy 152.3678 58.93787)
			(xy 152.3678 58.9516) (xy 152.35406 58.9516) (xy 152.35406 58.96533) (xy 152.3266 58.96533) (xy 152.3266 58.97906)
			(xy 152.29914 58.97906) (xy 152.29914 58.9928) (xy 152.28541 58.9928) (xy 152.28541 59.00653) (xy 152.25794 59.00653)
			(xy 152.25794 59.02026) (xy 152.24421 59.02026) (xy 152.24421 59.03399) (xy 152.21675 59.03399) (xy 152.21675 59.04772)
			(xy 152.18928 59.04772) (xy 152.18928 59.06145) (xy 152.17555 59.06145) (xy 152.17555 59.07519) (xy 152.14809 59.07519)
			(xy 152.14809 59.08892) (xy 152.13436 59.08892) (xy 152.13436 59.10265) (xy 152.10689 59.10265) (xy 152.10689 59.11638)
			(xy 152.09316 59.11638) (xy 152.09316 59.13011) (xy 152.0657 59.13011) (xy 152.0657 59.14384) (xy 152.05197 59.14384)
			(xy 152.05197 59.15758) (xy 152.0245 59.15758) (xy 152.0245 59.17131) (xy 152.01077 59.17131) (xy 152.01077 59.18504)
			(xy 151.99704 59.18504) (xy 151.99704 59.19877) (xy 151.96958 59.19877) (xy 151.96958 59.2125) (xy 151.95584 59.2125)
			(xy 151.95584 59.22624) (xy 151.94211 59.22624) (xy 151.94211 59.23997) (xy 151.91465 59.23997) (xy 151.91465 59.2537)
			(xy 151.90092 59.2537) (xy 151.90092 59.26743) (xy 151.87345 59.26743) (xy 151.87345 59.28116) (xy 151.85972 59.28116)
			(xy 151.85972 59.2949) (xy 151.84599 59.2949) (xy 151.84599 59.30863) (xy 151.83226 59.30863) (xy 151.83226 59.32236)
			(xy 151.80479 59.32236) (xy 151.80479 59.33609) (xy 151.79106 59.33609) (xy 151.79106 59.34982) (xy 151.77733 59.34982)
			(xy 151.77733 59.36355) (xy 151.74987 59.36355) (xy 151.74987 59.37729) (xy 151.73614 59.37729) (xy 151.73614 59.39102)
			(xy 151.7224 59.39102) (xy 151.7224 59.40475) (xy 151.70867 59.40475) (xy 151.70867 59.41848) (xy 151.69494 59.41848)
			(xy 151.69494 59.43221) (xy 151.66748 59.43221) (xy 151.66748 59.44594) (xy 151.65375 59.44594) (xy 151.65375 59.45968)
			(xy 151.64001 59.45968) (xy 151.64001 59.47341) (xy 151.62628 59.47341) (xy 151.62628 59.48714) (xy 151.61255 59.48714)
			(xy 151.61255 59.50087) (xy 151.58509 59.50087) (xy 151.58509 59.5146) (xy 151.57136 59.5146) (xy 151.57136 59.52833)
			(xy 151.55762 59.52833) (xy 151.55762 59.54207) (xy 151.54389 59.54207) (xy 151.54389 59.5558) (xy 151.53016 59.5558)
			(xy 151.53016 59.56953) (xy 151.51643 59.56953) (xy 151.51643 59.58326) (xy 151.5027 59.58326) (xy 151.5027 59.59699)
			(xy 151.48896 59.59699) (xy 151.48896 59.61072) (xy 151.47523 59.61072) (xy 151.47523 59.62446) (xy 151.44777 59.62446)
			(xy 151.44777 59.63819) (xy 151.43404 59.63819) (xy 151.43404 59.65192) (xy 151.4203 59.65192) (xy 151.4203 59.66565)
			(xy 151.40657 59.66565) (xy 151.40657 59.67938) (xy 151.39284 59.67938) (xy 151.39284 59.69311) (xy 151.37911 59.69311)
			(xy 151.37911 59.70685) (xy 151.36538 59.70685) (xy 151.36538 59.72058) (xy 151.35165 59.72058) (xy 151.35165 59.73431)
			(xy 151.33791 59.73431) (xy 151.33791 59.74804) (xy 151.32418 59.74804) (xy 151.32418 59.76177) (xy 151.31045 59.76177)
			(xy 151.31045 59.77551) (xy 151.29672 59.77551) (xy 151.29672 59.78924) (xy 151.28299 59.78924) (xy 151.28299 59.80297)
			(xy 151.26926 59.80297) (xy 151.26926 59.8167) (xy 151.25552 59.8167) (xy 151.25552 59.83043) (xy 151.24179 59.83043)
			(xy 151.24179 59.84417) (xy 151.22806 59.84417) (xy 151.22806 59.8579) (xy 151.21433 59.8579) (xy 151.21433 59.87163)
			(xy 151.2006 59.87163) (xy 151.2006 59.88536) (xy 151.18687 59.88536) (xy 151.18687 59.89909) (xy 151.17313 59.89909)
			(xy 151.17313 59.91282) (xy 151.1594 59.91282) (xy 151.1594 59.92656) (xy 151.1594 59.94029) (xy 151.14567 59.94029)
			(xy 151.14567 59.95402) (xy 151.13194 59.95402) (xy 151.13194 59.96775) (xy 151.11821 59.96775) (xy 151.11821 59.98148)
			(xy 151.10448 59.98148) (xy 151.10448 59.99521) (xy 151.09074 59.99521) (xy 151.09074 60.00895) (xy 151.07701 60.00895)
			(xy 151.07701 60.02268) (xy 151.06328 60.02268) (xy 151.06328 60.03641) (xy 151.04955 60.03641) (xy 151.04955 60.05014)
			(xy 151.04955 60.06387) (xy 151.03582 60.06387) (xy 151.03582 60.0776) (xy 151.02209 60.0776) (xy 151.02209 60.09134)
			(xy 151.00835 60.09134) (xy 151.00835 60.10507) (xy 150.99462 60.10507) (xy 150.99462 60.1188) (xy 150.98089 60.1188)
			(xy 150.98089 60.13253) (xy 150.98089 60.14626) (xy 150.96716 60.14626) (xy 150.96716 60.15999) (xy 150.95343 60.15999)
			(xy 150.95343 60.17373) (xy 150.93969 60.17373) (xy 150.93969 60.18746) (xy 150.92596 60.18746) (xy 150.92596 60.20119)
			(xy 150.91223 60.20119) (xy 150.91223 60.21492) (xy 150.91223 60.22865) (xy 150.8985 60.22865) (xy 150.8985 60.24239)
			(xy 150.88477 60.24239) (xy 150.88477 60.25612) (xy 150.87103 60.25612) (xy 150.87103 60.26985) (xy 150.87103 60.28358)
			(xy 150.8573 60.28358) (xy 150.8573 60.29731) (xy 150.84357 60.29731) (xy 150.84357 60.31105) (xy 150.82984 60.31105)
			(xy 150.82984 60.32478) (xy 150.81611 60.32478) (xy 150.81611 60.33851) (xy 150.81611 60.35224) (xy 150.80238 60.35224)
			(xy 150.80238 60.36597) (xy 150.78864 60.36597) (xy 150.78864 60.3797) (xy 150.77491 60.3797) (xy 150.77491 60.39344)
			(xy 150.77491 60.40717) (xy 150.76118 60.40717) (xy 150.76118 60.4209) (xy 150.74745 60.4209) (xy 150.74745 60.43463)
			(xy 150.74745 60.44836) (xy 150.73372 60.44836) (xy 150.73372 60.46209) (xy 150.71999 60.46209) (xy 150.71999 60.47583)
			(xy 150.70625 60.47583) (xy 150.70625 60.48956) (xy 150.70625 60.50329) (xy 150.69252 60.50329) (xy 150.69252 60.51702)
			(xy 150.67879 60.51702) (xy 150.67879 60.53075) (xy 150.67879 60.54448) (xy 150.66506 60.54448) (xy 150.66506 60.55822)
			(xy 150.65133 60.55822) (xy 150.65133 60.57195) (xy 150.65133 60.58568) (xy 150.6376 60.58568) (xy 150.6376 60.59941)
			(xy 150.62386 60.59941) (xy 150.62386 60.61314) (xy 150.62386 60.62687) (xy 150.61013 60.62687) (xy 150.61013 60.64061)
			(xy 150.5964 60.64061) (xy 150.5964 60.65434) (xy 150.5964 60.66807) (xy 150.58267 60.66807) (xy 150.58267 60.6818)
			(xy 150.56894 60.6818) (xy 150.56894 60.69553) (xy 150.56894 60.70926) (xy 150.55521 60.70926) (xy 150.55521 60.723)
			(xy 150.55521 60.73673) (xy 150.54147 60.73673) (xy 150.54147 60.75046) (xy 150.52774 60.75046) (xy 150.52774 60.76419)
			(xy 150.52774 60.77792) (xy 150.51401 60.77792) (xy 150.51401 60.79166) (xy 150.51401 60.80539) (xy 150.50028 60.80539)
			(xy 150.50028 60.81912) (xy 150.48655 60.81912) (xy 150.48655 60.83285) (xy 150.48655 60.84658) (xy 150.47282 60.84658)
			(xy 150.47282 60.86032) (xy 150.47282 60.87405) (xy 150.45908 60.87405) (xy 150.45908 60.88778) (xy 150.44535 60.88778)
			(xy 150.44535 60.90151) (xy 150.44535 60.91524) (xy 150.43162 60.91524) (xy 150.43162 60.92897) (xy 150.43162 60.94271)
			(xy 150.41789 60.94271) (xy 150.41789 60.95644) (xy 150.41789 60.97017) (xy 150.40416 60.97017) (xy 150.40416 60.9839)
			(xy 150.40416 60.99763) (xy 150.39042 60.99763) (xy 150.39042 61.01136) (xy 150.37669 61.01136) (xy 150.37669 61.0251)
			(xy 150.37669 61.03883) (xy 150.36296 61.03883) (xy 150.36296 61.05256) (xy 150.36296 61.06629) (xy 150.34923 61.06629)
			(xy 150.34923 61.08002) (xy 150.34923 61.09375) (xy 150.3355 61.09375) (xy 150.3355 61.10749) (xy 150.3355 61.12122)
			(xy 150.32176 61.12122) (xy 150.32176 61.13495) (xy 150.32176 61.14868) (xy 150.30803 61.14868) (xy 150.30803 61.16241)
			(xy 150.30803 61.17614) (xy 150.2943 61.17614) (xy 150.2943 61.18988) (xy 150.2943 61.20361) (xy 150.28057 61.20361)
			(xy 150.28057 61.21734) (xy 150.28057 61.23107) (xy 150.26684 61.23107) (xy 150.26684 61.2448) (xy 150.26684 61.25853)
			(xy 150.25311 61.25853) (xy 150.25311 61.27227) (xy 150.25311 61.286) (xy 150.25311 61.29973) (xy 150.23937 61.29973)
			(xy 150.23937 61.31346) (xy 150.23937 61.32719) (xy 150.22564 61.32719) (xy 150.22564 61.34093) (xy 150.22564 61.35466)
			(xy 150.21191 61.35466) (xy 150.21191 61.36839) (xy 150.21191 61.38212) (xy 150.19818 61.38212) (xy 150.19818 61.39585)
			(xy 150.19818 61.40959) (xy 150.19818 61.42332) (xy 150.18445 61.42332) (xy 150.18445 61.43705) (xy 150.18445 61.45078)
			(xy 150.17072 61.45078) (xy 150.17072 61.46451) (xy 150.17072 61.47824) (xy 150.15698 61.47824) (xy 150.15698 61.49198)
			(xy 150.15698 61.50571) (xy 150.15698 61.51944) (xy 150.14325 61.51944) (xy 150.14325 61.53317) (xy 150.14325 61.5469)
			(xy 150.12952 61.5469) (xy 150.12952 61.56063) (xy 150.12952 61.57437) (xy 150.12952 61.5881) (xy 150.11579 61.5881)
			(xy 150.11579 61.60183) (xy 150.11579 61.61556) (xy 150.10206 61.61556) (xy 150.10206 61.62929) (xy 150.10206 61.64302)
			(xy 150.10206 61.65676) (xy 150.08833 61.65676) (xy 150.08833 61.67049) (xy 150.08833 61.68422) (xy 150.08833 61.69795)
			(xy 150.07459 61.69795) (xy 150.07459 61.71168) (xy 150.07459 61.72541) (xy 150.06086 61.72541) (xy 150.06086 61.73915)
			(xy 150.06086 61.75288) (xy 150.06086 61.76661) (xy 150.04713 61.76661) (xy 150.04713 61.78034) (xy 150.04713 61.79407)
			(xy 150.04713 61.8078) (xy 150.0334 61.8078) (xy 150.0334 61.82154) (xy 150.0334 61.83527) (xy 150.0334 61.849)
			(xy 150.01967 61.849) (xy 150.01967 61.86273) (xy 150.01967 61.87646) (xy 150.01967 61.8902) (xy 150.00594 61.8902)
			(xy 150.00594 61.90393) (xy 150.00594 61.91766) (xy 150.00594 61.93139) (xy 149.9922 61.93139) (xy 149.9922 61.94512)
			(xy 149.9922 61.95886) (xy 149.9922 61.97259) (xy 149.9922 61.98632) (xy 149.97847 61.98632) (xy 149.97847 62.00005)
			(xy 149.97847 62.01378) (xy 149.97847 62.02751) (xy 149.96474 62.02751) (xy 149.96474 62.04125) (xy 149.96474 62.05498)
			(xy 149.96474 62.06871) (xy 149.96474 62.08244) (xy 149.95101 62.08244) (xy 149.95101 62.09617) (xy 149.95101 62.1099)
			(xy 149.95101 62.12364) (xy 149.93728 62.12364) (xy 149.93728 62.13737) (xy 149.93728 62.1511) (xy 149.93728 62.16483)
			(xy 149.93728 62.17856) (xy 149.92355 62.17856) (xy 149.92355 62.19229) (xy 149.92355 62.20603) (xy 149.92355 62.21976)
			(xy 149.92355 62.23349) (xy 149.90981 62.23349) (xy 149.90981 62.24722) (xy 149.90981 62.26095) (xy 149.90981 62.27468)
			(xy 149.90981 62.28842) (xy 149.89608 62.28842) (xy 149.89608 62.30215) (xy 149.89608 62.31588) (xy 149.89608 62.32961)
			(xy 149.89608 62.34334) (xy 149.88235 62.34334) (xy 149.88235 62.35708) (xy 149.88235 62.37081) (xy 149.88235 62.38454)
			(xy 149.88235 62.39827) (xy 149.88235 62.412) (xy 149.86862 62.412) (xy 149.86862 62.42574) (xy 149.86862 62.43947)
			(xy 149.86862 62.4532) (xy 149.86862 62.46693) (xy 149.86862 62.48066) (xy 149.85489 62.48066) (xy 149.85489 62.49439)
			(xy 149.85489 62.50813) (xy 149.85489 62.52186) (xy 149.85489 62.53559) (xy 149.85489 62.54932) (xy 149.84115 62.54932)
			(xy 149.84115 62.56305) (xy 149.84115 62.57678) (xy 149.84115 62.59052) (xy 149.84115 62.60425) (xy 149.84115 62.61798)
			(xy 149.82742 62.61798) (xy 149.82742 62.63171) (xy 149.82742 62.64544) (xy 149.82742 62.65917) (xy 149.82742 62.67291)
			(xy 149.82742 62.68664) (xy 149.82742 62.70037) (xy 149.81369 62.70037) (xy 149.81369 62.7141) (xy 149.81369 62.72783)
			(xy 149.81369 62.74156) (xy 149.81369 62.7553) (xy 149.81369 62.76903) (xy 149.81369 62.78276) (xy 149.81369 62.79649)
			(xy 149.79996 62.79649) (xy 149.79996 62.81022) (xy 149.79996 62.82395) (xy 149.79996 62.83769) (xy 149.79996 62.85142)
			(xy 149.79996 62.86515) (xy 149.79996 62.87888) (xy 149.79996 62.89261) (xy 149.79996 62.90635) (xy 149.78623 62.90635)
			(xy 149.78623 62.92008) (xy 149.78623 62.93381) (xy 149.78623 62.94754) (xy 149.78623 62.96127) (xy 149.78623 62.97501)
			(xy 149.78623 62.98874) (xy 149.78623 63.00247) (xy 149.78623 63.0162) (xy 149.78623 63.02993) (xy 149.78623 63.04366)
			(xy 149.77249 63.04366) (xy 149.77249 63.0574) (xy 149.77249 63.07113) (xy 149.77249 63.08486) (xy 149.77249 63.09859)
			(xy 149.77249 63.11232) (xy 149.77249 63.12605) (xy 149.77249 63.13979) (xy 149.77249 63.15352) (xy 149.77249 63.16725)
			(xy 149.77249 63.18098) (xy 149.77249 63.19471) (xy 149.77249 63.20844) (xy 149.77249 63.22218) (xy 149.77249 63.23591)
			(xy 149.75876 63.23591) (xy 145.22729 63.23591) (xy 145.21356 63.23591) (xy 145.21356 63.22218) (xy 145.21356 63.20844)
			(xy 145.21356 63.19471) (xy 145.21356 63.18098) (xy 145.21356 63.16725) (xy 145.21356 63.15352) (xy 145.19982 63.15352)
			(xy 145.19982 63.13979) (xy 145.19982 63.12605) (xy 145.19982 63.11232) (xy 145.19982 63.09859) (xy 145.18609 63.09859)
			(xy 145.18609 63.08486) (xy 145.18609 63.07113) (xy 145.18609 63.0574) (xy 145.17236 63.0574) (xy 145.17236 63.04366)
			(xy 145.17236 63.02993) (xy 145.17236 63.0162) (xy 145.15863 63.0162) (xy 145.15863 63.00247) (xy 145.15863 62.98874)
			(xy 145.1449 62.98874) (xy 145.1449 62.97501) (xy 145.1449 62.96127) (xy 145.13116 62.96127) (xy 145.13116 62.94754)
			(xy 145.13116 62.93381) (xy 145.11743 62.93381) (xy 145.11743 62.92008) (xy 145.11743 62.90635) (xy 145.1037 62.90635)
			(xy 145.1037 62.89261) (xy 145.1037 62.87888) (xy 145.08997 62.87888) (xy 145.08997 62.86515) (xy 145.07624 62.86515)
			(xy 145.07624 62.85142) (xy 145.07624 62.83769) (xy 145.0625 62.83769) (xy 145.0625 62.82395) (xy 145.04877 62.82395)
			(xy 145.04877 62.81022) (xy 145.04877 62.79649) (xy 145.03504 62.79649) (xy 145.03504 62.78276) (xy 145.02131 62.78276)
			(xy 145.02131 62.76903) (xy 145.00758 62.76903) (xy 145.00758 62.7553) (xy 144.99385 62.7553) (xy 144.99385 62.74156)
			(xy 144.98011 62.74156) (xy 144.98011 62.72783) (xy 144.96638 62.72783) (xy 144.96638 62.7141) (xy 144.95265 62.7141)
			(xy 144.95265 62.70037) (xy 144.93892 62.70037) (xy 144.93892 62.68664) (xy 144.92519 62.68664) (xy 144.92519 62.67291)
			(xy 144.91146 62.67291) (xy 144.91146 62.65917) (xy 144.89772 62.65917) (xy 144.89772 62.64544) (xy 144.87026 62.64544)
			(xy 144.87026 62.63171) (xy 144.85653 62.63171) (xy 144.85653 62.61798) (xy 144.8428 62.61798) (xy 144.8428 62.60425)
			(xy 144.81533 62.60425) (xy 144.81533 62.59052) (xy 144.8016 62.59052) (xy 144.8016 62.57678) (xy 144.77414 62.57678)
			(xy 144.77414 62.56305) (xy 144.74668 62.56305) (xy 144.74668 62.54932) (xy 144.71921 62.54932) (xy 144.71921 62.53559)
			(xy 144.69175 62.53559) (xy 144.69175 62.52186) (xy 144.65055 62.52186) (xy 144.65055 62.50813) (xy 144.62309 62.50813)
			(xy 144.62309 62.49439) (xy 144.56816 62.49439) (xy 144.56816 62.48066) (xy 144.51323 62.48066) (xy 144.51323 62.46693)
			(xy 144.43084 62.46693) (xy 144.43084 62.4532) (xy 137.30407 62.4532) (xy 137.30407 62.43947) (xy 137.22167 62.43947)
			(xy 137.22167 62.42574) (xy 137.16675 62.42574) (xy 137.16675 62.412) (xy 137.12555 62.412) (xy 137.12555 62.39827)
			(xy 137.08436 62.39827) (xy 137.08436 62.38454) (xy 137.05689 62.38454) (xy 137.05689 62.37081) (xy 137.02943 62.37081)
			(xy 137.02943 62.35708) (xy 136.98823 62.35708) (xy 136.98823 62.34334) (xy 136.9745 62.34334) (xy 136.9745 62.32961)
			(xy 136.94704 62.32961) (xy 136.94704 62.31588) (xy 136.91958 62.31588) (xy 136.91958 62.30215) (xy 136.90584 62.30215)
			(xy 136.90584 62.28842) (xy 136.87838 62.28842) (xy 136.87838 62.27468) (xy 136.86465 62.27468) (xy 136.86465 62.26095)
			(xy 136.85092 62.26095) (xy 136.85092 62.24722) (xy 136.82345 62.24722) (xy 136.82345 62.23349) (xy 136.80972 62.23349)
			(xy 136.80972 62.21976) (xy 136.79599 62.21976) (xy 136.79599 62.20603) (xy 136.78226 62.20603) (xy 136.78226 62.19229)
			(xy 136.76853 62.19229) (xy 136.76853 62.17856) (xy 136.7548 62.17856) (xy 136.7548 62.16483) (xy 136.74106 62.16483)
			(xy 136.74106 62.1511) (xy 136.72733 62.1511) (xy 136.72733 62.13737) (xy 136.7136 62.13737) (xy 136.7136 62.12364)
			(xy 136.7136 62.1099) (xy 136.69987 62.1099) (xy 136.69987 62.09617) (xy 136.68614 62.09617) (xy 136.68614 62.08244)
			(xy 136.6724 62.08244) (xy 136.6724 62.06871) (xy 136.65867 62.06871) (xy 136.65867 62.05498) (xy 136.65867 62.04125)
			(xy 136.64494 62.04125) (xy 136.64494 62.02751) (xy 136.63121 62.02751) (xy 136.63121 62.01378) (xy 136.63121 62.00005)
			(xy 136.61748 62.00005) (xy 136.61748 61.98632) (xy 136.61748 61.97259) (xy 136.60374 61.97259) (xy 136.60374 61.95886)
			(xy 136.60374 61.94512) (xy 136.59001 61.94512) (xy 136.59001 61.93139) (xy 136.59001 61.91766) (xy 136.57628 61.91766)
			(xy 136.57628 61.90393) (xy 136.57628 61.8902) (xy 136.56255 61.8902) (xy 136.56255 61.87646) (xy 136.56255 61.86273)
			(xy 136.56255 61.849) (xy 136.54882 61.849) (xy 136.54882 61.83527) (xy 136.54882 61.82154) (xy 136.54882 61.8078)
			(xy 136.53509 61.8078) (xy 136.53509 61.79407) (xy 136.53509 61.78034) (xy 136.53509 61.76661) (xy 136.53509 61.75288)
			(xy 136.52136 61.75288) (xy 136.52136 61.73915) (xy 136.52136 61.72541) (xy 136.52136 61.71168) (xy 136.52136 61.69795)
			(xy 136.52136 61.68422) (xy 136.50762 61.68422) (xy 136.50762 61.67049) (xy 136.50762 61.65676) (xy 136.50762 61.64302)
			(xy 136.50762 61.62929) (xy 136.50762 61.61556) (xy 136.50762 61.60183) (xy 136.50762 61.5881) (xy 136.50762 61.57437)
			(xy 136.50762 61.56063) (xy 136.50762 61.5469) (xy 136.50762 61.53317) (xy 136.50762 61.51944) (xy 136.50762 61.50571)
			(xy 136.50762 61.49198) (xy 136.50762 61.47824) (xy 136.50762 61.46451) (xy 136.50762 61.45078) (xy 136.50762 61.43705)
			(xy 136.50762 61.42332) (xy 136.52136 61.42332) (xy 136.52136 61.40959) (xy 136.52136 61.39585) (xy 136.52136 61.38212)
			(xy 136.52136 61.36839) (xy 136.52136 61.35466) (xy 136.53509 61.35466) (xy 136.53509 61.34093) (xy 136.53509 61.32719)
			(xy 136.53509 61.31346) (xy 136.53509 61.29973) (xy 136.54882 61.29973) (xy 136.54882 61.286) (xy 136.54882 61.27227)
			(xy 136.54882 61.25853) (xy 136.56255 61.25853) (xy 136.56255 61.2448) (xy 136.56255 61.23107) (xy 136.57628 61.23107)
			(xy 136.57628 61.21734) (xy 136.57628 61.20361) (xy 136.57628 61.18988) (xy 136.59001 61.18988) (xy 136.59001 61.17614)
			(xy 136.59001 61.16241) (xy 136.60374 61.16241) (xy 136.60374 61.14868) (xy 136.60374 61.13495) (xy 136.61748 61.13495)
			(xy 136.61748 61.12122) (xy 136.61748 61.10749) (xy 136.63121 61.10749) (xy 136.63121 61.09375) (xy 136.64494 61.09375)
			(xy 136.64494 61.08002) (xy 136.64494 61.06629) (xy 136.65867 61.06629) (xy 136.65867 61.05256) (xy 136.6724 61.05256)
			(xy 136.6724 61.03883) (xy 136.6724 61.0251) (xy 136.68614 61.0251) (xy 136.68614 61.01136) (xy 136.69987 61.01136)
			(xy 136.69987 60.99763) (xy 136.7136 60.99763) (xy 136.7136 60.9839) (xy 136.72733 60.9839) (xy 136.72733 60.97017)
			(xy 136.72733 60.95644) (xy 136.74106 60.95644) (xy 136.74106 60.94271) (xy 136.7548 60.94271) (xy 136.7548 60.92897)
			(xy 136.76853 60.92897) (xy 136.76853 60.91524) (xy 136.78226 60.91524) (xy 136.78226 60.90151) (xy 136.79599 60.90151)
			(xy 136.79599 60.88778) (xy 136.82345 60.88778) (xy 136.82345 60.87405) (xy 136.83719 60.87405) (xy 136.83719 60.86032)
			(xy 136.85092 60.86032) (xy 136.85092 60.84658) (xy 136.86465 60.84658) (xy 136.86465 60.83285) (xy 136.89211 60.83285)
			(xy 136.89211 60.81912) (xy 136.90584 60.81912) (xy 136.90584 60.80539) (xy 136.93331 60.80539) (xy 136.93331 60.79166)
			(xy 136.94704 60.79166) (xy 136.94704 60.77792) (xy 136.9745 60.77792) (xy 136.9745 60.76419) (xy 137.00197 60.76419)
			(xy 137.00197 60.75046) (xy 137.02943 60.75046) (xy 137.02943 60.73673) (xy 137.05689 60.73673) (xy 137.05689 60.723)
			(xy 137.09809 60.723) (xy 137.09809 60.70926) (xy 137.13928 60.70926) (xy 137.13928 60.69553) (xy 137.18048 60.69553)
			(xy 137.18048 60.6818) (xy 137.23541 60.6818) (xy 137.23541 60.66807) (xy 137.33153 60.66807) (xy 137.33153 60.65434)
			(xy 137.34526 60.65434) (xy 137.34526 60.66807) (xy 137.35899 60.66807) (xy 137.35899 60.65434) (xy 148.22081 60.65434)
			(xy 148.22081 60.64061) (xy 148.28947 60.64061) (xy 148.28947 60.62687) (xy 148.34439 60.62687) (xy 148.34439 60.61314)
			(xy 148.38559 60.61314) (xy 148.38559 60.59941) (xy 148.42678 60.59941) (xy 148.42678 60.58568) (xy 148.45425 60.58568)
			(xy 148.45425 60.57195) (xy 148.48171 60.57195) (xy 148.48171 60.55822) (xy 148.50917 60.55822) (xy 148.50917 60.54448)
			(xy 148.53664 60.54448) (xy 148.53664 60.53075) (xy 148.5641 60.53075) (xy 148.5641 60.51702) (xy 148.57783 60.51702)
			(xy 148.57783 60.50329) (xy 148.6053 60.50329) (xy 148.6053 60.48956) (xy 148.61903 60.48956) (xy 148.61903 60.47583)
			(xy 148.64649 60.47583) (xy 148.64649 60.46209) (xy 148.66022 60.46209) (xy 148.66022 60.44836) (xy 148.67395 60.44836)
			(xy 148.67395 60.43463) (xy 148.68769 60.43463) (xy 148.68769 60.4209) (xy 148.70142 60.4209) (xy 148.70142 60.40717)
			(xy 148.71515 60.40717) (xy 148.71515 60.39344) (xy 148.72888 60.39344) (xy 148.72888 60.3797) (xy 148.74261 60.3797)
			(xy 148.74261 60.36597) (xy 148.75634 60.36597) (xy 148.75634 60.35224) (xy 148.77008 60.35224) (xy 148.77008 60.33851)
			(xy 148.78381 60.33851) (xy 148.78381 60.32478) (xy 148.79754 60.32478) (xy 148.79754 60.31105) (xy 148.81127 60.31105)
			(xy 148.81127 60.29731) (xy 148.81127 60.28358) (xy 148.825 60.28358) (xy 148.825 60.26985) (xy 148.83874 60.26985)
			(xy 148.83874 60.25612) (xy 148.83874 60.24239) (xy 148.85247 60.24239) (xy 148.85247 60.22865) (xy 148.8662 60.22865)
			(xy 148.8662 60.21492) (xy 148.8662 60.20119) (xy 148.87993 60.20119) (xy 148.87993 60.18746) (xy 148.87993 60.17373)
			(xy 148.89366 60.17373) (xy 148.89366 60.15999) (xy 148.89366 60.14626) (xy 148.9074 60.14626) (xy 148.9074 60.13253)
			(xy 148.9074 60.1188) (xy 148.92113 60.1188) (xy 148.92113 60.10507) (xy 148.92113 60.09134) (xy 148.93486 60.09134)
			(xy 148.93486 60.0776) (xy 148.93486 60.06387) (xy 148.93486 60.05014) (xy 148.94859 60.05014) (xy 148.94859 60.03641)
			(xy 148.94859 60.02268) (xy 148.94859 60.00895) (xy 148.96232 60.00895) (xy 148.96232 59.99521) (xy 148.96232 59.98148)
			(xy 148.96232 59.96775) (xy 148.96232 59.95402) (xy 148.97605 59.95402) (xy 148.97605 59.94029) (xy 148.97605 59.92656)
			(xy 148.97605 59.91282) (xy 148.97605 59.89909) (xy 148.97605 59.88536) (xy 148.97605 59.87163) (xy 148.98979 59.87163)
			(xy 148.98979 59.8579) (xy 148.98979 59.84417) (xy 148.98979 59.83043) (xy 148.98979 59.8167) (xy 148.98979 59.80297)
			(xy 148.98979 59.78924) (xy 148.98979 59.77551) (xy 148.98979 59.76177) (xy 148.98979 59.74804) (xy 148.98979 59.73431)
			(xy 148.98979 59.72058) (xy 148.98979 59.70685) (xy 148.98979 59.69311) (xy 148.98979 59.67938) (xy 148.98979 59.66565)
			(xy 148.98979 59.65192) (xy 148.97605 59.65192) (xy 148.97605 59.63819) (xy 148.97605 59.62446) (xy 148.97605 59.61072)
			(xy 148.97605 59.59699) (xy 148.97605 59.58326) (xy 148.97605 59.56953) (xy 148.96232 59.56953) (xy 148.96232 59.5558)
			(xy 148.96232 59.54207) (xy 148.96232 59.52833) (xy 148.96232 59.5146) (xy 148.94859 59.5146) (xy 148.94859 59.50087)
			(xy 148.94859 59.48714) (xy 148.94859 59.47341) (xy 148.93486 59.47341) (xy 148.93486 59.45968) (xy 148.93486 59.44594)
			(xy 148.92113 59.44594) (xy 148.92113 59.43221) (xy 148.92113 59.41848) (xy 148.92113 59.40475) (xy 148.9074 59.40475)
			(xy 148.9074 59.39102) (xy 148.9074 59.37729) (xy 148.89366 59.37729) (xy 148.89366 59.36355) (xy 148.89366 59.34982)
			(xy 148.87993 59.34982) (xy 148.87993 59.33609) (xy 148.87993 59.32236) (xy 148.8662 59.32236) (xy 148.8662 59.30863)
			(xy 148.85247 59.30863) (xy 148.85247 59.2949) (xy 148.85247 59.28116) (xy 148.83874 59.28116) (xy 148.83874 59.26743)
			(xy 148.825 59.26743) (xy 148.825 59.2537) (xy 148.825 59.23997) (xy 148.81127 59.23997) (xy 148.81127 59.22624)
			(xy 148.79754 59.22624) (xy 148.79754 59.2125) (xy 148.78381 59.2125) (xy 148.78381 59.19877) (xy 148.78381 59.18504)
			(xy 148.77008 59.18504) (xy 148.77008 59.17131) (xy 148.75634 59.17131) (xy 148.75634 59.15758) (xy 148.74261 59.15758)
			(xy 148.74261 59.14384) (xy 148.72888 59.14384) (xy 148.72888 59.13011) (xy 148.71515 59.13011) (xy 148.71515 59.11638)
			(xy 148.70142 59.11638) (xy 148.70142 59.10265) (xy 148.68769 59.10265) (xy 148.68769 59.08892) (xy 148.66022 59.08892)
			(xy 148.66022 59.07519) (xy 148.64649 59.07519) (xy 148.64649 59.06145) (xy 148.63276 59.06145) (xy 148.63276 59.04772)
			(xy 148.61903 59.04772) (xy 148.61903 59.03399) (xy 148.59156 59.03399) (xy 148.59156 59.02026) (xy 148.5641 59.02026)
			(xy 148.5641 59.00653) (xy 148.55037 59.00653) (xy 148.55037 58.9928) (xy 148.52291 58.9928) (xy 148.52291 58.97906)
			(xy 148.49544 58.97906) (xy 148.49544 58.96533) (xy 148.46798 58.96533) (xy 148.46798 58.9516) (xy 148.44052 58.9516)
			(xy 148.44052 58.93787) (xy 148.39932 58.93787) (xy 148.39932 58.92414) (xy 148.37186 58.92414) (xy 148.37186 58.91041)
			(xy 148.31693 58.91041) (xy 148.31693 58.89667) (xy 148.262 58.89667) (xy 148.262 58.88294) (xy 148.15215 58.88294)
			(xy 148.15215 58.86921) (xy 146.07865 58.86921) (xy 146.07865 58.85548) (xy 145.99626 58.85548) (xy 145.99626 58.84175)
			(xy 145.95507 58.84175) (xy 145.95507 58.82802) (xy 145.90014 58.82802) (xy 145.90014 58.81428) (xy 145.87268 58.81428)
			(xy 145.87268 58.80055) (xy 145.83148 58.80055) (xy 145.83148 58.78682) (xy 145.80402 58.78682) (xy 145.80402 58.77309)
			(xy 145.77656 58.77309) (xy 145.77656 58.75936) (xy 145.74909 58.75936) (xy 145.74909 58.74563) (xy 145.73536 58.74563)
			(xy 145.73536 58.73189) (xy 145.7079 58.73189) (xy 145.7079 58.71816) (xy 145.69417 58.71816) (xy 145.69417 58.70443)
			(xy 145.6667 58.70443) (xy 145.6667 58.6907) (xy 145.65297 58.6907) (xy 145.65297 58.67697) (xy 145.63924 58.67697)
			(xy 145.63924 58.66323) (xy 145.61177 58.66323) (xy 145.61177 58.6495) (xy 145.59804 58.6495) (xy 145.59804 58.63577)
			(xy 145.58431 58.63577) (xy 145.58431 58.62204) (xy 145.57058 58.62204) (xy 145.57058 58.60831) (xy 145.55685 58.60831)
			(xy 145.55685 58.59457) (xy 145.54311 58.59457) (xy 145.54311 58.58084) (xy 145.52938 58.58084) (xy 145.52938 58.56711)
			(xy 145.51565 58.56711) (xy 145.51565 58.55338) (xy 145.50192 58.55338) (xy 145.50192 58.53965) (xy 145.50192 58.52592)
			(xy 145.48819 58.52592) (xy 145.48819 58.51218) (xy 145.47446 58.51218) (xy 145.47446 58.49845) (xy 145.46072 58.49845)
			(xy 145.46072 58.48472) (xy 145.46072 58.47099) (xy 145.44699 58.47099) (xy 145.44699 58.45726) (xy 145.43326 58.45726)
			(xy 145.43326 58.44353) (xy 145.43326 58.42979) (xy 145.41953 58.42979) (xy 145.41953 58.41606) (xy 145.4058 58.41606)
			(xy 145.4058 58.40233) (xy 145.4058 58.3886) (xy 145.39207 58.3886) (xy 145.39207 58.37487) (xy 145.39207 58.36114)
			(xy 145.37834 58.36114) (xy 145.37834 58.3474) (xy 145.37834 58.33367) (xy 145.3646 58.33367) (xy 145.3646 58.31994)
			(xy 145.3646 58.30621) (xy 145.3646 58.29248) (xy 145.35087 58.29248) (xy 145.35087 58.27875) (xy 145.35087 58.26501)
			(xy 145.35087 58.25128) (xy 145.33714 58.25128) (xy 145.33714 58.23755) (xy 145.33714 58.22382) (xy 145.33714 58.21009)
			(xy 145.32341 58.21009) (xy 145.32341 58.19636) (xy 145.32341 58.18262) (xy 145.32341 58.16889) (xy 145.32341 58.15516)
			(xy 145.30968 58.15516) (xy 145.30968 58.14143) (xy 145.30968 58.1277) (xy 145.30968 58.11396) (xy 145.30968 58.10023)
			(xy 145.30968 58.0865) (xy 145.30968 58.07277) (xy 145.30968 58.05904) (xy 145.29595 58.05904) (xy 145.29595 58.0453)
			(xy 145.30968 58.0453) (xy 145.30968 58.03157) (xy 145.29595 58.03157) (xy 145.29595 58.01784) (xy 145.29595 58.00411)
			(xy 145.29595 57.99038) (xy 145.29595 57.97665) (xy 145.29595 57.96291) (xy 145.29595 57.94918) (xy 145.29595 57.93545)
			(xy 145.29595 57.92172) (xy 145.29595 57.90799) (xy 145.29595 57.89426) (xy 145.29595 57.88052) (xy 145.30968 57.88052)
			(xy 145.30968 57.86679) (xy 145.30968 57.85306) (xy 145.30968 57.83933) (xy 145.30968 57.8256) (xy 145.30968 57.81187)
			(xy 145.30968 57.79813) (xy 145.32341 57.79813) (xy 145.32341 57.7844) (xy 145.32341 57.77067) (xy 145.32341 57.75694)
			(xy 145.32341 57.74321) (xy 145.33714 57.74321) (xy 145.33714 57.72948) (xy 145.33714 57.71574) (xy 145.33714 57.70201)
			(xy 145.35087 57.70201) (xy 145.35087 57.68828) (xy 145.35087 57.67455) (xy 145.35087 57.66082) (xy 145.3646 57.66082)
			(xy 145.3646 57.64708) (xy 145.3646 57.63335) (xy 145.3646 57.61962) (xy 145.37834 57.61962) (xy 145.37834 57.60589)
			(xy 145.37834 57.59216) (xy 145.39207 57.59216) (xy 145.39207 57.57842) (xy 145.39207 57.56469) (xy 145.4058 57.56469)
			(xy 145.4058 57.55096) (xy 145.4058 57.53723) (xy 145.41953 57.53723) (xy 145.41953 57.5235) (xy 145.43326 57.5235)
			(xy 145.43326 57.50977) (xy 145.43326 57.49603) (xy 145.44699 57.49603) (xy 145.44699 57.4823) (xy 145.44699 57.46857)
			(xy 145.46072 57.46857) (xy 145.46072 57.45484) (xy 145.47446 57.45484) (xy 145.47446 57.44111) (xy 145.48819 57.44111)
			(xy 145.48819 57.42738) (xy 145.48819 57.41364) (xy 145.50192 57.41364) (xy 145.50192 57.39991) (xy 145.51565 57.39991)
			(xy 145.51565 57.38618) (xy 145.52938 57.38618) (xy 145.52938 57.37245) (xy 145.54311 57.37245) (xy 145.54311 57.35872)
			(xy 145.55685 57.35872) (xy 145.55685 57.34499) (xy 145.57058 57.34499) (xy 145.57058 57.33125) (xy 145.58431 57.33125)
			(xy 145.58431 57.31752) (xy 145.59804 57.31752) (xy 145.59804 57.30379) (xy 145.61177 57.30379) (xy 145.61177 57.29006)
			(xy 145.62551 57.29006) (xy 145.62551 57.27633) (xy 145.65297 57.27633) (xy 145.65297 57.2626) (xy 145.6667 57.2626)
			(xy 145.6667 57.24886) (xy 145.68043 57.24886) (xy 145.68043 57.23513) (xy 145.7079 57.23513) (xy 145.7079 57.2214)
			(xy 145.72163 57.2214) (xy 145.72163 57.20767) (xy 145.74909 57.20767) (xy 145.74909 57.19394) (xy 145.77656 57.19394)
			(xy 145.77656 57.18021) (xy 145.80402 57.18021) (xy 145.80402 57.16647) (xy 145.83148 57.16647) (xy 145.83148 57.15274)
			(xy 145.85895 57.15274) (xy 145.85895 57.13901) (xy 145.90014 57.13901) (xy 145.90014 57.12528) (xy 145.94134 57.12528)
			(xy 145.94134 57.11155) (xy 145.99626 57.11155) (xy 145.99626 57.09781) (xy 146.05119 57.09781) (xy 146.05119 57.08408)
			(xy 146.20224 57.08408) (xy 146.20224 57.07035) (xy 163.53171 57.07035)
		)
		(stroke
			(width 0)
			(type default)
		)
		(fill yes)
		(layer "B.Cu")
	)
	(gr_rect
		(start 101.9761 154.6036)
		(end 103.8511 152.8786)
		(stroke
			(width 0)
			(type default)
		)
		(fill yes)
		(layer "B.Cu")
		(net "+12V_PCIE")
	)
	(gr_rect
		(start 109.05608 154.62058)
		(end 110.93108 152.89558)
		(stroke
			(width 0)
			(type default)
		)
		(fill yes)
		(layer "B.Cu")
		(net "+3.3V_PCIE")
	)
	(gr_line
		(start 55.8761 49.4286)
		(end 55.8761 156.0786)
		(stroke
			(width 0.05)
			(type solid)
		)
		(layer "Edge.Cuts")
	)
	(gr_line
		(start 55.8761 156.0786)
		(end 70.8761 156.0786)
		(stroke
			(width 0.05)
			(type solid)
		)
		(layer "Edge.Cuts")
	)
	(gr_line
		(start 70.8761 147.8286)
		(end 89.2261 147.8286)
		(stroke
			(width 0.05)
			(type solid)
		)
		(layer "Edge.Cuts")
	)
	(gr_line
		(start 70.8761 156.0786)
		(end 70.8761 147.8286)
		(stroke
			(width 0.05)
			(type solid)
		)
		(layer "Edge.Cuts")
	)
	(gr_line
		(start 89.2261 147.8286)
		(end 89.2261 156.0786)
		(stroke
			(width 0.05)
			(type solid)
		)
		(layer "Edge.Cuts")
	)
	(gr_line
		(start 89.2261 156.0786)
		(end 97.2261 156.0786)
		(stroke
			(width 0.05)
			(type solid)
		)
		(layer "Edge.Cuts")
	)
	(gr_arc
		(start 97.2261 149.6536)
		(mid 99.0511 147.8286)
		(end 100.8761 149.6536)
		(stroke
			(width 0.05)
			(type solid)
		)
		(layer "Edge.Cuts")
	)
	(gr_line
		(start 97.2261 156.0786)
		(end 97.2261 149.6536)
		(stroke
			(width 0.05)
			(type solid)
		)
		(layer "Edge.Cuts")
	)
	(gr_line
		(start 100.8761 149.6536)
		(end 100.8761 160.0786)
		(stroke
			(width 0.05)
			(type solid)
		)
		(layer "Edge.Cuts")
	)
	(gr_line
		(start 100.8761 160.0786)
		(end 101.3761 160.5786)
		(stroke
			(width 0.05)
			(type solid)
		)
		(layer "Edge.Cuts")
	)
	(gr_line
		(start 101.3761 160.5786)
		(end 111.5761 160.5786)
		(stroke
			(width 0.05)
			(type solid)
		)
		(layer "Edge.Cuts")
	)
	(gr_line
		(start 111.5761 160.5786)
		(end 112.0761 160.0786)
		(stroke
			(width 0.05)
			(type solid)
		)
		(layer "Edge.Cuts")
	)
	(gr_arc
		(start 112.0761 153.1286)
		(mid 113.0261 152.1786)
		(end 113.9761 153.1286)
		(stroke
			(width 0.05)
			(type solid)
		)
		(layer "Edge.Cuts")
	)
	(gr_line
		(start 112.0761 160.0786)
		(end 112.0761 153.1286)
		(stroke
			(width 0.05)
			(type solid)
		)
		(layer "Edge.Cuts")
	)
	(gr_line
		(start 113.9761 153.1286)
		(end 113.9761 160.0786)
		(stroke
			(width 0.05)
			(type solid)
		)
		(layer "Edge.Cuts")
	)
	(gr_line
		(start 113.9761 160.0786)
		(end 114.4761 160.5786)
		(stroke
			(width 0.05)
			(type solid)
		)
		(layer "Edge.Cuts")
	)
	(gr_line
		(start 114.4761 160.5786)
		(end 134.6761 160.5786)
		(stroke
			(width 0.05)
			(type solid)
		)
		(layer "Edge.Cuts")
	)
	(gr_line
		(start 134.6761 160.5786)
		(end 135.1761 160.0786)
		(stroke
			(width 0.05)
			(type solid)
		)
		(layer "Edge.Cuts")
	)
	(gr_line
		(start 135.1761 147.8286)
		(end 241.1261 147.8286)
		(stroke
			(width 0.05)
			(type solid)
		)
		(layer "Edge.Cuts")
	)
	(gr_line
		(start 135.1761 160.0786)
		(end 135.1761 147.8286)
		(stroke
			(width 0.05)
			(type solid)
		)
		(layer "Edge.Cuts")
	)
	(gr_line
		(start 241.12609 49.4286)
		(end 55.8761 49.4286)
		(stroke
			(width 0.05)
			(type solid)
		)
		(layer "Edge.Cuts")
	)
	(gr_line
		(start 241.1261 147.8286)
		(end 241.12609 49.4286)
		(stroke
			(width 0.05)
			(type solid)
		)
		(layer "Edge.Cuts")
	)
	(via
		(at 141.88361 53.23361)
		(size 5.08)
		(drill 3.0988)
		(layers "F.Cu" "B.Cu")
		(net "")
	)
	(via
		(at 168.11859 53.27359)
		(size 5.08)
		(drill 3.0988)
		(layers "F.Cu" "B.Cu")
		(net "")
	)
	(via
		(at 228.6186 53.27359)
		(size 5.08)
		(drill 3.0988)
		(layers "F.Cu" "B.Cu")
		(net "")
	)
	(via
		(at 141.88361 79.23361)
		(size 5.08)
		(drill 3.0988)
		(layers "F.Cu" "B.Cu")
		(net "")
	)
	(via
		(at 81.3836 79.23361)
		(size 5.08)
		(drill 3.0988)
		(layers "F.Cu" "B.Cu")
		(net "")
	)
	(via
		(at 186.6261 141.6162)
		(size 6.35)
		(drill 3.18)
		(layers "F.Cu" "B.Cu")
		(net "")
	)
	(via
		(at 237.1261 141.6162)
		(size 6.35)
		(drill 3.18)
		(layers "F.Cu" "B.Cu")
		(net "")
	)
	(via
		(at 228.6186 79.27359)
		(size 5.08)
		(drill 3.0988)
		(layers "F.Cu" "B.Cu")
		(net "")
	)
	(via
		(at 168.11859 79.27359)
		(size 5.08)
		(drill 3.0988)
		(layers "F.Cu" "B.Cu")
		(net "")
	)
	(via
		(at 81.3836 53.23361)
		(size 5.08)
		(drill 3.0988)
		(layers "F.Cu" "B.Cu")
		(net "")
	)
	(via
		(at 237.12611 55.1162)
		(size 6.35)
		(drill 3.18)
		(layers "F.Cu" "B.Cu")
		(net "")
	)
	(via
		(at 229.4261 108.0162)
		(size 0.4064)
		(drill 0.2032)
		(layers "F.Cu" "B.Cu")
		(tenting
			(front yes)
			(back yes)
		)
		(net "NetD12_2")
	)
	(via
		(at 229.9261 108.0162)
		(size 0.4064)
		(drill 0.2032)
		(layers "F.Cu" "B.Cu")
		(tenting
			(front yes)
			(back yes)
		)
		(net "NetD12_2")
	)
	(via
		(at 230.4261 108.8162)
		(size 0.4064)
		(drill 0.2032)
		(layers "F.Cu" "B.Cu")
		(tenting
			(front yes)
			(back yes)
		)
		(net "NetD12_2")
	)
	(via
		(at 230.4261 108.0162)
		(size 0.4064)
		(drill 0.2032)
		(layers "F.Cu" "B.Cu")
		(tenting
			(front yes)
			(back yes)
		)
		(net "NetD12_2")
	)
	(via
		(at 229.4261 108.8162)
		(size 0.4064)
		(drill 0.2032)
		(layers "F.Cu" "B.Cu")
		(tenting
			(front yes)
			(back yes)
		)
		(net "NetD12_2")
	)
	(via
		(at 229.9261 108.8162)
		(size 0.4064)
		(drill 0.2032)
		(layers "F.Cu" "B.Cu")
		(tenting
			(front yes)
			(back yes)
		)
		(net "NetD12_2")
	)
	(via
		(at 152.7261 84.8162)
		(size 0.4064)
		(drill 0.2032)
		(layers "F.Cu" "B.Cu")
		(tenting
			(front yes)
			(back yes)
		)
		(net "MAC_VCC")
	)
	(via
		(at 153.2261 84.0162)
		(size 0.4064)
		(drill 0.2032)
		(layers "F.Cu" "B.Cu")
		(tenting
			(front yes)
			(back yes)
		)
		(net "MAC_VCC")
	)
	(via
		(at 152.2261 84.0162)
		(size 0.4064)
		(drill 0.2032)
		(layers "F.Cu" "B.Cu")
		(tenting
			(front yes)
			(back yes)
		)
		(net "MAC_VCC")
	)
	(via
		(at 152.2261 84.8162)
		(size 0.4064)
		(drill 0.2032)
		(layers "F.Cu" "B.Cu")
		(tenting
			(front yes)
			(back yes)
		)
		(net "MAC_VCC")
	)
	(via
		(at 153.2261 84.8162)
		(size 0.4064)
		(drill 0.2032)
		(layers "F.Cu" "B.Cu")
		(tenting
			(front yes)
			(back yes)
		)
		(net "MAC_VCC")
	)
	(via
		(at 152.7261 84.0162)
		(size 0.4064)
		(drill 0.2032)
		(layers "F.Cu" "B.Cu")
		(tenting
			(front yes)
			(back yes)
		)
		(net "MAC_VCC")
	)
	(segment
		(start 123.46498 88.77732)
		(end 123.88327 88.35903)
		(width 0.2032)
		(layer "F.Cu")
		(net "MAC_PPS_OUT")
	)
	(segment
		(start 123.88327 88.35903)
		(end 125.93807 88.35903)
		(width 0.2032)
		(layer "F.Cu")
		(net "MAC_PPS_OUT")
	)
	(segment
		(start 125.93807 88.35903)
		(end 126.1261 88.171)
		(width 0.2032)
		(layer "F.Cu")
		(net "MAC_PPS_OUT")
	)
	(segment
		(start 123.46498 88.97732)
		(end 123.46498 88.77732)
		(width 0.2032)
		(layer "F.Cu")
		(net "MAC_PPS_OUT")
	)
	(segment
		(start 126.1261 88.171)
		(end 126.1261 87.4162)
		(width 0.2032)
		(layer "F.Cu")
		(net "MAC_PPS_OUT")
	)
	(segment
		(start 123.4261 89.0162)
		(end 123.46498 88.97732)
		(width 0.2032)
		(layer "F.Cu")
		(net "MAC_PPS_OUT")
	)
	(via
		(at 123.4261 89.0162)
		(size 0.4064)
		(drill 0.2032)
		(layers "F.Cu" "B.Cu")
		(tenting
			(front yes)
			(back yes)
		)
		(net "MAC_PPS_OUT")
	)
	(segment
		(start 123.4261 135.9122)
		(end 125.7301 138.2162)
		(width 0.2032)
		(layer "B.Cu")
		(net "MAC_PPS_OUT")
	)
	(segment
		(start 123.4261 135.9122)
		(end 123.4261 89.0162)
		(width 0.2032)
		(layer "B.Cu")
		(net "MAC_PPS_OUT")
	)
	(segment
		(start 124.66891 88.71463)
		(end 128.47888 88.71463)
		(width 0.254)
		(layer "F.Cu")
		(net "MAC_PPS_IN")
	)
	(segment
		(start 124.3261 89.0162)
		(end 124.36734 89.0162)
		(width 0.254)
		(layer "F.Cu")
		(net "MAC_PPS_IN")
	)
	(segment
		(start 124.36734 89.0162)
		(end 124.66891 88.71463)
		(width 0.254)
		(layer "F.Cu")
		(net "MAC_PPS_IN")
	)
	(via
		(at 124.3261 89.0162)
		(size 0.4064)
		(drill 0.2032)
		(layers "F.Cu" "B.Cu")
		(tenting
			(front yes)
			(back yes)
		)
		(net "MAC_PPS_IN")
	)
	(segment
		(start 124.3261 133.7642)
		(end 128.7781 138.2162)
		(width 0.254)
		(layer "B.Cu")
		(net "MAC_PPS_IN")
	)
	(segment
		(start 124.3261 133.7642)
		(end 124.3261 89.0162)
		(width 0.254)
		(layer "B.Cu")
		(net "MAC_PPS_IN")
	)
	(segment
		(start 69.8761 54.9412)
		(end 69.8761 52.8662)
		(width 0.2032)
		(layer "F.Cu")
		(net "NetD3_1")
	)
	(segment
		(start 84.1261 89.6162)
		(end 84.8761 88.8662)
		(width 0.254)
		(layer "F.Cu")
		(net "NetR41_2")
	)
	(segment
		(start 85.8761 87.6162)
		(end 87.0511 87.6162)
		(width 0.254)
		(layer "F.Cu")
		(net "NetR41_2")
	)
	(segment
		(start 84.8761 88.6162)
		(end 85.8761 87.6162)
		(width 0.254)
		(layer "F.Cu")
		(net "NetR41_2")
	)
	(segment
		(start 84.8761 88.8662)
		(end 84.8761 88.6162)
		(width 0.254)
		(layer "F.Cu")
		(net "NetR41_2")
	)
	(segment
		(start 84.8761 88.6162)
		(end 84.8761 88.6162)
		(width 0.254)
		(layer "F.Cu")
		(net "NetR41_2")
	)
	(segment
		(start 79.6261 135.6162)
		(end 79.8761 135.3662)
		(width 0.2032)
		(layer "F.Cu")
		(net "NetR34_1")
	)
	(segment
		(start 78.2761 135.6162)
		(end 79.6261 135.6162)
		(width 0.2032)
		(layer "F.Cu")
		(net "NetR34_1")
	)
	(segment
		(start 79.6261 135.6162)
		(end 79.8761 135.8662)
		(width 0.2032)
		(layer "F.Cu")
		(net "NetR34_1")
	)
	(segment
		(start 79.8761 135.3662)
		(end 80.5511 135.3662)
		(width 0.2032)
		(layer "F.Cu")
		(net "NetR34_1")
	)
	(segment
		(start 79.8761 135.8662)
		(end 80.5511 135.8662)
		(width 0.2032)
		(layer "F.Cu")
		(net "NetR34_1")
	)
	(segment
		(start 79.8761 108.6162)
		(end 80.1261 108.8662)
		(width 0.2032)
		(layer "F.Cu")
		(net "NetR33_1")
	)
	(segment
		(start 79.8761 108.6162)
		(end 80.1261 108.3662)
		(width 0.2032)
		(layer "F.Cu")
		(net "NetR33_1")
	)
	(segment
		(start 80.1261 108.3662)
		(end 80.8011 108.3662)
		(width 0.2032)
		(layer "F.Cu")
		(net "NetR33_1")
	)
	(segment
		(start 78.5761 108.6162)
		(end 79.8761 108.6162)
		(width 0.2032)
		(layer "F.Cu")
		(net "NetR33_1")
	)
	(segment
		(start 80.1261 108.8662)
		(end 80.8011 108.8662)
		(width 0.2032)
		(layer "F.Cu")
		(net "NetR33_1")
	)
	(segment
		(start 79.8213 121.8662)
		(end 80.0713 121.6162)
		(width 0.2032)
		(layer "F.Cu")
		(net "NetR28_1")
	)
	(segment
		(start 78.5761 121.8662)
		(end 79.8213 121.8662)
		(width 0.2032)
		(layer "F.Cu")
		(net "NetR28_1")
	)
	(segment
		(start 80.0713 121.6162)
		(end 80.8011 121.6162)
		(width 0.2032)
		(layer "F.Cu")
		(net "NetR28_1")
	)
	(segment
		(start 80.0713 122.1162)
		(end 80.8011 122.1162)
		(width 0.2032)
		(layer "F.Cu")
		(net "NetR28_1")
	)
	(segment
		(start 79.8213 121.8662)
		(end 80.0713 122.1162)
		(width 0.2032)
		(layer "F.Cu")
		(net "NetR28_1")
	)
	(segment
		(start 58.4261 140.3912)
		(end 58.4511 140.4162)
		(width 0.2032)
		(layer "F.Cu")
		(net "NetD18_4")
	)
	(segment
		(start 88.8521 83.6162)
		(end 88.8641 83.6282)
		(width 0.2032)
		(layer "F.Cu")
		(net "NetD18_4")
	)
	(segment
		(start 57.1261 140.3662)
		(end 57.1511 140.3912)
		(width 0.2032)
		(layer "F.Cu")
		(net "NetD18_4")
	)
	(segment
		(start 88.8641 84.7792)
		(end 88.8761 84.7912)
		(width 0.2032)
		(layer "F.Cu")
		(net "NetD18_4")
	)
	(segment
		(start 88.8641 84.7792)
		(end 88.8641 83.6282)
		(width 0.2032)
		(layer "F.Cu")
		(net "NetD18_4")
	)
	(segment
		(start 57.1511 140.3912)
		(end 58.4261 140.3912)
		(width 0.2032)
		(layer "F.Cu")
		(net "NetD18_4")
	)
	(via
		(at 57.1261 140.3662)
		(size 0.4064)
		(drill 0.2032)
		(layers "F.Cu" "B.Cu")
		(tenting
			(front yes)
			(back yes)
		)
		(net "NetD18_4")
	)
	(via
		(at 88.8521 83.6162)
		(size 0.4064)
		(drill 0.2032)
		(layers "F.Cu" "B.Cu")
		(tenting
			(front yes)
			(back yes)
		)
		(net "NetD18_4")
	)
	(segment
		(start 96.4657 90.59266)
		(end 96.4657 86.38974)
		(width 0.2032)
		(layer "B.Cu")
		(net "NetD18_4")
	)
	(segment
		(start 66.6261 140.3662)
		(end 70.7157 136.2766)
		(width 0.2032)
		(layer "B.Cu")
		(net "NetD18_4")
	)
	(segment
		(start 88.8521 83.6162)
		(end 88.8681 83.6002)
		(width 0.2032)
		(layer "B.Cu")
		(net "NetD18_4")
	)
	(segment
		(start 88.8681 82.84117)
		(end 89.68267 82.0266)
		(width 0.2032)
		(layer "B.Cu")
		(net "NetD18_4")
	)
	(segment
		(start 70.7157 136.2766)
		(end 70.7157 107.47934)
		(width 0.2032)
		(layer "B.Cu")
		(net "NetD18_4")
	)
	(segment
		(start 81.98924 96.2058)
		(end 90.85256 96.2058)
		(width 0.2032)
		(layer "B.Cu")
		(net "NetD18_4")
	)
	(segment
		(start 90.85256 96.2058)
		(end 96.4657 90.59266)
		(width 0.2032)
		(layer "B.Cu")
		(net "NetD18_4")
	)
	(segment
		(start 92.10256 82.0266)
		(end 96.4657 86.38974)
		(width 0.2032)
		(layer "B.Cu")
		(net "NetD18_4")
	)
	(segment
		(start 57.1261 140.3662)
		(end 66.6261 140.3662)
		(width 0.2032)
		(layer "B.Cu")
		(net "NetD18_4")
	)
	(segment
		(start 89.68267 82.0266)
		(end 92.10256 82.0266)
		(width 0.2032)
		(layer "B.Cu")
		(net "NetD18_4")
	)
	(segment
		(start 70.7157 107.47934)
		(end 81.98924 96.2058)
		(width 0.2032)
		(layer "B.Cu")
		(net "NetD18_4")
	)
	(segment
		(start 88.8681 83.6002)
		(end 88.8681 82.84117)
		(width 0.2032)
		(layer "B.Cu")
		(net "NetD18_4")
	)
	(segment
		(start 88.3441 83.82662)
		(end 88.3441 83.1322)
		(width 0.2032)
		(layer "F.Cu")
		(net "NetD18_3")
	)
	(segment
		(start 88.3441 83.82662)
		(end 88.3761 83.85862)
		(width 0.2032)
		(layer "F.Cu")
		(net "NetD18_3")
	)
	(segment
		(start 88.3441 83.1322)
		(end 88.3601 83.1162)
		(width 0.2032)
		(layer "F.Cu")
		(net "NetD18_3")
	)
	(segment
		(start 57.1261 141.3662)
		(end 58.1261 141.3662)
		(width 0.2032)
		(layer "F.Cu")
		(net "NetD18_3")
	)
	(segment
		(start 88.3761 84.7912)
		(end 88.3761 83.85862)
		(width 0.2032)
		(layer "F.Cu")
		(net "NetD18_3")
	)
	(via
		(at 88.3601 83.1162)
		(size 0.4064)
		(drill 0.2032)
		(layers "F.Cu" "B.Cu")
		(tenting
			(front yes)
			(back yes)
		)
		(net "NetD18_3")
	)
	(via
		(at 57.1261 141.3662)
		(size 0.4064)
		(drill 0.2032)
		(layers "F.Cu" "B.Cu")
		(tenting
			(front yes)
			(back yes)
		)
		(net "NetD18_3")
	)
	(segment
		(start 66.09307 141.3662)
		(end 71.0459 136.41337)
		(width 0.2032)
		(layer "B.Cu")
		(net "NetD18_3")
	)
	(segment
		(start 71.0459 136.41337)
		(end 71.0459 107.61611)
		(width 0.2032)
		(layer "B.Cu")
		(net "NetD18_3")
	)
	(segment
		(start 88.3601 83.1162)
		(end 88.39898 83.07732)
		(width 0.2032)
		(layer "B.Cu")
		(net "NetD18_3")
	)
	(segment
		(start 90.98933 96.536)
		(end 96.7959 90.72943)
		(width 0.2032)
		(layer "B.Cu")
		(net "NetD18_3")
	)
	(segment
		(start 82.12601 96.536)
		(end 90.98933 96.536)
		(width 0.2032)
		(layer "B.Cu")
		(net "NetD18_3")
	)
	(segment
		(start 96.7959 90.72943)
		(end 96.7959 86.25297)
		(width 0.2032)
		(layer "B.Cu")
		(net "NetD18_3")
	)
	(segment
		(start 71.0459 107.61611)
		(end 82.12601 96.536)
		(width 0.2032)
		(layer "B.Cu")
		(net "NetD18_3")
	)
	(segment
		(start 57.1261 141.3662)
		(end 66.09307 141.3662)
		(width 0.2032)
		(layer "B.Cu")
		(net "NetD18_3")
	)
	(segment
		(start 92.23933 81.6964)
		(end 96.7959 86.25297)
		(width 0.2032)
		(layer "B.Cu")
		(net "NetD18_3")
	)
	(segment
		(start 88.39898 82.84332)
		(end 89.5459 81.6964)
		(width 0.2032)
		(layer "B.Cu")
		(net "NetD18_3")
	)
	(segment
		(start 89.5459 81.6964)
		(end 92.23933 81.6964)
		(width 0.2032)
		(layer "B.Cu")
		(net "NetD18_3")
	)
	(segment
		(start 88.39898 83.07732)
		(end 88.39898 82.84332)
		(width 0.2032)
		(layer "B.Cu")
		(net "NetD18_3")
	)
	(segment
		(start 58.01498 142.15508)
		(end 58.1261 142.2662)
		(width 0.2032)
		(layer "F.Cu")
		(net "NetD18_2")
	)
	(segment
		(start 57.16498 142.15508)
		(end 58.01498 142.15508)
		(width 0.2032)
		(layer "F.Cu")
		(net "NetD18_2")
	)
	(segment
		(start 87.8361 83.6162)
		(end 87.8561 83.6362)
		(width 0.2032)
		(layer "F.Cu")
		(net "NetD18_2")
	)
	(segment
		(start 87.8561 84.7712)
		(end 87.8761 84.7912)
		(width 0.2032)
		(layer "F.Cu")
		(net "NetD18_2")
	)
	(segment
		(start 87.8561 84.7712)
		(end 87.8561 83.6362)
		(width 0.2032)
		(layer "F.Cu")
		(net "NetD18_2")
	)
	(segment
		(start 57.1261 142.1162)
		(end 57.16498 142.15508)
		(width 0.2032)
		(layer "F.Cu")
		(net "NetD18_2")
	)
	(via
		(at 87.8361 83.6162)
		(size 0.4064)
		(drill 0.2032)
		(layers "F.Cu" "B.Cu")
		(tenting
			(front yes)
			(back yes)
		)
		(net "NetD18_2")
	)
	(via
		(at 57.1261 142.1162)
		(size 0.4064)
		(drill 0.2032)
		(layers "F.Cu" "B.Cu")
		(tenting
			(front yes)
			(back yes)
		)
		(net "NetD18_2")
	)
	(segment
		(start 65.81004 142.1162)
		(end 71.3761 136.55014)
		(width 0.2032)
		(layer "B.Cu")
		(net "NetD18_2")
	)
	(segment
		(start 91.1261 96.8662)
		(end 97.1261 90.8662)
		(width 0.2032)
		(layer "B.Cu")
		(net "NetD18_2")
	)
	(segment
		(start 92.3761 81.3662)
		(end 97.1261 86.1162)
		(width 0.2032)
		(layer "B.Cu")
		(net "NetD18_2")
	)
	(segment
		(start 71.3761 136.55014)
		(end 71.3761 107.75289)
		(width 0.2032)
		(layer "B.Cu")
		(net "NetD18_2")
	)
	(segment
		(start 89.3761 81.3662)
		(end 92.3761 81.3662)
		(width 0.2032)
		(layer "B.Cu")
		(net "NetD18_2")
	)
	(segment
		(start 97.1261 90.8662)
		(end 97.1261 86.1162)
		(width 0.2032)
		(layer "B.Cu")
		(net "NetD18_2")
	)
	(segment
		(start 87.8361 83.6162)
		(end 87.8361 82.9062)
		(width 0.2032)
		(layer "B.Cu")
		(net "NetD18_2")
	)
	(segment
		(start 87.8361 82.9062)
		(end 89.3761 81.3662)
		(width 0.2032)
		(layer "B.Cu")
		(net "NetD18_2")
	)
	(segment
		(start 57.1261 142.1162)
		(end 65.81004 142.1162)
		(width 0.2032)
		(layer "B.Cu")
		(net "NetD18_2")
	)
	(segment
		(start 82.26278 96.8662)
		(end 91.1261 96.8662)
		(width 0.2032)
		(layer "B.Cu")
		(net "NetD18_2")
	)
	(segment
		(start 71.3761 107.75289)
		(end 82.26278 96.8662)
		(width 0.2032)
		(layer "B.Cu")
		(net "NetD18_2")
	)
	(segment
		(start 58.33998 126.90508)
		(end 58.4511 127.0162)
		(width 0.2032)
		(layer "F.Cu")
		(net "NetD17_4")
	)
	(segment
		(start 90.8961 84.7712)
		(end 90.8961 83.6442)
		(width 0.2032)
		(layer "F.Cu")
		(net "NetD17_4")
	)
	(segment
		(start 90.8961 83.6442)
		(end 90.9161 83.6242)
		(width 0.2032)
		(layer "F.Cu")
		(net "NetD17_4")
	)
	(segment
		(start 57.16498 126.90508)
		(end 58.33998 126.90508)
		(width 0.2032)
		(layer "F.Cu")
		(net "NetD17_4")
	)
	(segment
		(start 90.8761 84.7912)
		(end 90.8961 84.7712)
		(width 0.2032)
		(layer "F.Cu")
		(net "NetD17_4")
	)
	(segment
		(start 57.1261 126.8662)
		(end 57.16498 126.90508)
		(width 0.2032)
		(layer "F.Cu")
		(net "NetD17_4")
	)
	(via
		(at 57.1261 126.8662)
		(size 0.4064)
		(drill 0.2032)
		(layers "F.Cu" "B.Cu")
		(tenting
			(front yes)
			(back yes)
		)
		(net "NetD17_4")
	)
	(via
		(at 90.9161 83.6242)
		(size 0.4064)
		(drill 0.2032)
		(layers "F.Cu" "B.Cu")
		(tenting
			(front yes)
			(back yes)
		)
		(net "NetD17_4")
	)
	(segment
		(start 90.44224 95.2152)
		(end 95.4751 90.18234)
		(width 0.2032)
		(layer "B.Cu")
		(net "NetD17_4")
	)
	(segment
		(start 92.29125 83.6162)
		(end 95.4751 86.80005)
		(width 0.2032)
		(layer "B.Cu")
		(net "NetD17_4")
	)
	(segment
		(start 69.7251 107.06903)
		(end 81.57893 95.2152)
		(width 0.2032)
		(layer "B.Cu")
		(net "NetD17_4")
	)
	(segment
		(start 95.4751 90.18234)
		(end 95.4751 86.80005)
		(width 0.2032)
		(layer "B.Cu")
		(net "NetD17_4")
	)
	(segment
		(start 81.57893 95.2152)
		(end 90.44224 95.2152)
		(width 0.2032)
		(layer "B.Cu")
		(net "NetD17_4")
	)
	(segment
		(start 69.7251 124.5172)
		(end 69.7251 107.06903)
		(width 0.2032)
		(layer "B.Cu")
		(net "NetD17_4")
	)
	(segment
		(start 90.9161 83.6242)
		(end 90.9241 83.6162)
		(width 0.2032)
		(layer "B.Cu")
		(net "NetD17_4")
	)
	(segment
		(start 57.1261 126.8662)
		(end 67.3761 126.8662)
		(width 0.2032)
		(layer "B.Cu")
		(net "NetD17_4")
	)
	(segment
		(start 67.3761 126.8662)
		(end 69.7251 124.5172)
		(width 0.2032)
		(layer "B.Cu")
		(net "NetD17_4")
	)
	(segment
		(start 90.9241 83.6162)
		(end 92.29125 83.6162)
		(width 0.2032)
		(layer "B.Cu")
		(net "NetD17_4")
	)
	(segment
		(start 58.06498 127.90508)
		(end 58.1261 127.9662)
		(width 0.2032)
		(layer "F.Cu")
		(net "NetD17_3")
	)
	(segment
		(start 90.3761 84.7912)
		(end 90.3921 84.7752)
		(width 0.2032)
		(layer "F.Cu")
		(net "NetD17_3")
	)
	(segment
		(start 57.16498 127.90508)
		(end 58.06498 127.90508)
		(width 0.2032)
		(layer "F.Cu")
		(net "NetD17_3")
	)
	(segment
		(start 57.1261 127.8662)
		(end 57.16498 127.90508)
		(width 0.2032)
		(layer "F.Cu")
		(net "NetD17_3")
	)
	(segment
		(start 90.3921 84.7752)
		(end 90.3921 83.1162)
		(width 0.2032)
		(layer "F.Cu")
		(net "NetD17_3")
	)
	(via
		(at 57.1261 127.8662)
		(size 0.4064)
		(drill 0.2032)
		(layers "F.Cu" "B.Cu")
		(tenting
			(front yes)
			(back yes)
		)
		(net "NetD17_3")
	)
	(via
		(at 90.3921 83.1162)
		(size 0.4064)
		(drill 0.2032)
		(layers "F.Cu" "B.Cu")
		(tenting
			(front yes)
			(back yes)
		)
		(net "NetD17_3")
	)
	(segment
		(start 57.1261 127.8662)
		(end 66.84307 127.8662)
		(width 0.2032)
		(layer "B.Cu")
		(net "NetD17_3")
	)
	(segment
		(start 92.25822 83.1162)
		(end 95.8053 86.66328)
		(width 0.2032)
		(layer "B.Cu")
		(net "NetD17_3")
	)
	(segment
		(start 90.3921 83.1162)
		(end 92.25822 83.1162)
		(width 0.2032)
		(layer "B.Cu")
		(net "NetD17_3")
	)
	(segment
		(start 81.7157 95.5454)
		(end 90.57901 95.5454)
		(width 0.2032)
		(layer "B.Cu")
		(net "NetD17_3")
	)
	(segment
		(start 70.0553 124.65397)
		(end 70.0553 107.2058)
		(width 0.2032)
		(layer "B.Cu")
		(net "NetD17_3")
	)
	(segment
		(start 70.0553 107.2058)
		(end 81.7157 95.5454)
		(width 0.2032)
		(layer "B.Cu")
		(net "NetD17_3")
	)
	(segment
		(start 95.8053 90.31911)
		(end 95.8053 86.66328)
		(width 0.2032)
		(layer "B.Cu")
		(net "NetD17_3")
	)
	(segment
		(start 90.57901 95.5454)
		(end 95.8053 90.31911)
		(width 0.2032)
		(layer "B.Cu")
		(net "NetD17_3")
	)
	(segment
		(start 66.84307 127.8662)
		(end 70.0553 124.65397)
		(width 0.2032)
		(layer "B.Cu")
		(net "NetD17_3")
	)
	(segment
		(start 57.1261 128.8662)
		(end 58.1261 128.8662)
		(width 0.2032)
		(layer "F.Cu")
		(net "NetD17_2")
	)
	(segment
		(start 89.8761 84.7912)
		(end 89.8801 84.7872)
		(width 0.2032)
		(layer "F.Cu")
		(net "NetD17_2")
	)
	(segment
		(start 89.8801 84.7872)
		(end 89.8801 83.6202)
		(width 0.2032)
		(layer "F.Cu")
		(net "NetD17_2")
	)
	(segment
		(start 89.8801 83.6202)
		(end 89.8841 83.6162)
		(width 0.2032)
		(layer "F.Cu")
		(net "NetD17_2")
	)
	(via
		(at 89.8841 83.6162)
		(size 0.4064)
		(drill 0.2032)
		(layers "F.Cu" "B.Cu")
		(tenting
			(front yes)
			(back yes)
		)
		(net "NetD17_2")
	)
	(via
		(at 57.1261 128.8662)
		(size 0.4064)
		(drill 0.2032)
		(layers "F.Cu" "B.Cu")
		(tenting
			(front yes)
			(back yes)
		)
		(net "NetD17_2")
	)
	(segment
		(start 66.31004 128.8662)
		(end 70.3855 124.79074)
		(width 0.2032)
		(layer "B.Cu")
		(net "NetD17_2")
	)
	(segment
		(start 57.1261 128.8662)
		(end 66.31004 128.8662)
		(width 0.2032)
		(layer "B.Cu")
		(net "NetD17_2")
	)
	(segment
		(start 89.8841 82.8582)
		(end 90.3761 82.3662)
		(width 0.2032)
		(layer "B.Cu")
		(net "NetD17_2")
	)
	(segment
		(start 70.3855 107.34257)
		(end 81.85247 95.8756)
		(width 0.2032)
		(layer "B.Cu")
		(net "NetD17_2")
	)
	(segment
		(start 81.85247 95.8756)
		(end 90.71578 95.8756)
		(width 0.2032)
		(layer "B.Cu")
		(net "NetD17_2")
	)
	(segment
		(start 90.3761 82.3662)
		(end 91.97519 82.3662)
		(width 0.2032)
		(layer "B.Cu")
		(net "NetD17_2")
	)
	(segment
		(start 89.8841 83.6162)
		(end 89.8841 82.8582)
		(width 0.2032)
		(layer "B.Cu")
		(net "NetD17_2")
	)
	(segment
		(start 90.71578 95.8756)
		(end 96.1355 90.45588)
		(width 0.2032)
		(layer "B.Cu")
		(net "NetD17_2")
	)
	(segment
		(start 70.3855 124.79074)
		(end 70.3855 107.34257)
		(width 0.2032)
		(layer "B.Cu")
		(net "NetD17_2")
	)
	(segment
		(start 96.1355 90.45588)
		(end 96.1355 86.52651)
		(width 0.2032)
		(layer "B.Cu")
		(net "NetD17_2")
	)
	(segment
		(start 91.97519 82.3662)
		(end 96.1355 86.52651)
		(width 0.2032)
		(layer "B.Cu")
		(net "NetD17_2")
	)
	(segment
		(start 91.7011 86.6162)
		(end 91.70503 86.62012)
		(width 0.2032)
		(layer "F.Cu")
		(net "NetD16_4")
	)
	(segment
		(start 91.70503 86.62012)
		(end 92.87218 86.62012)
		(width 0.2032)
		(layer "F.Cu")
		(net "NetD16_4")
	)
	(segment
		(start 58.4261 113.3912)
		(end 58.4511 113.4162)
		(width 0.2032)
		(layer "F.Cu")
		(net "NetD16_4")
	)
	(segment
		(start 57.1261 113.3662)
		(end 57.1511 113.3912)
		(width 0.2032)
		(layer "F.Cu")
		(net "NetD16_4")
	)
	(segment
		(start 57.1511 113.3912)
		(end 58.4261 113.3912)
		(width 0.2032)
		(layer "F.Cu")
		(net "NetD16_4")
	)
	(segment
		(start 92.87218 86.62012)
		(end 92.8761 86.62405)
		(width 0.2032)
		(layer "F.Cu")
		(net "NetD16_4")
	)
	(via
		(at 57.1261 113.3662)
		(size 0.4064)
		(drill 0.2032)
		(layers "F.Cu" "B.Cu")
		(tenting
			(front yes)
			(back yes)
		)
		(net "NetD16_4")
	)
	(via
		(at 92.8761 86.62405)
		(size 0.4064)
		(drill 0.2032)
		(layers "F.Cu" "B.Cu")
		(tenting
			(front yes)
			(back yes)
		)
		(net "NetD16_4")
	)
	(segment
		(start 90.03193 94.2246)
		(end 94.4845 89.77203)
		(width 0.2032)
		(layer "B.Cu")
		(net "NetD16_4")
	)
	(segment
		(start 81.16861 94.2246)
		(end 90.03193 94.2246)
		(width 0.2032)
		(layer "B.Cu")
		(net "NetD16_4")
	)
	(segment
		(start 66.94216 113.3662)
		(end 68.7345 111.57386)
		(width 0.2032)
		(layer "B.Cu")
		(net "NetD16_4")
	)
	(segment
		(start 68.7345 106.65872)
		(end 81.16861 94.2246)
		(width 0.2032)
		(layer "B.Cu")
		(net "NetD16_4")
	)
	(segment
		(start 57.1261 113.3662)
		(end 66.94216 113.3662)
		(width 0.2032)
		(layer "B.Cu")
		(net "NetD16_4")
	)
	(segment
		(start 68.7345 111.57386)
		(end 68.7345 106.65872)
		(width 0.2032)
		(layer "B.Cu")
		(net "NetD16_4")
	)
	(segment
		(start 94.4845 89.77203)
		(end 94.4845 87.2246)
		(width 0.2032)
		(layer "B.Cu")
		(net "NetD16_4")
	)
	(segment
		(start 93.88395 86.62405)
		(end 94.4845 87.2246)
		(width 0.2032)
		(layer "B.Cu")
		(net "NetD16_4")
	)
	(segment
		(start 92.8761 86.62405)
		(end 93.88395 86.62405)
		(width 0.2032)
		(layer "B.Cu")
		(net "NetD16_4")
	)
	(segment
		(start 91.7011 86.1162)
		(end 91.70126 86.11605)
		(width 0.2032)
		(layer "F.Cu")
		(net "NetD16_3")
	)
	(segment
		(start 91.70126 86.11605)
		(end 93.3761 86.11605)
		(width 0.2032)
		(layer "F.Cu")
		(net "NetD16_3")
	)
	(segment
		(start 57.1261 114.3662)
		(end 58.1261 114.3662)
		(width 0.2032)
		(layer "F.Cu")
		(net "NetD16_3")
	)
	(via
		(at 93.3761 86.11605)
		(size 0.4064)
		(drill 0.2032)
		(layers "F.Cu" "B.Cu")
		(tenting
			(front yes)
			(back yes)
		)
		(net "NetD16_3")
	)
	(via
		(at 57.1261 114.3662)
		(size 0.4064)
		(drill 0.2032)
		(layers "F.Cu" "B.Cu")
		(tenting
			(front yes)
			(back yes)
		)
		(net "NetD16_3")
	)
	(segment
		(start 69.0647 106.79549)
		(end 81.30538 94.5548)
		(width 0.2032)
		(layer "B.Cu")
		(net "NetD16_3")
	)
	(segment
		(start 94.8147 89.9088)
		(end 94.8147 87.0736)
		(width 0.2032)
		(layer "B.Cu")
		(net "NetD16_3")
	)
	(segment
		(start 57.1261 114.3662)
		(end 66.40913 114.3662)
		(width 0.2032)
		(layer "B.Cu")
		(net "NetD16_3")
	)
	(segment
		(start 93.40305 86.143)
		(end 93.8841 86.143)
		(width 0.2032)
		(layer "B.Cu")
		(net "NetD16_3")
	)
	(segment
		(start 66.40913 114.3662)
		(end 69.0647 111.71063)
		(width 0.2032)
		(layer "B.Cu")
		(net "NetD16_3")
	)
	(segment
		(start 93.3761 86.11605)
		(end 93.40305 86.143)
		(width 0.2032)
		(layer "B.Cu")
		(net "NetD16_3")
	)
	(segment
		(start 93.8841 86.143)
		(end 94.8147 87.0736)
		(width 0.2032)
		(layer "B.Cu")
		(net "NetD16_3")
	)
	(segment
		(start 90.1687 94.5548)
		(end 94.8147 89.9088)
		(width 0.2032)
		(layer "B.Cu")
		(net "NetD16_3")
	)
	(segment
		(start 69.0647 111.71063)
		(end 69.0647 106.79549)
		(width 0.2032)
		(layer "B.Cu")
		(net "NetD16_3")
	)
	(segment
		(start 81.30538 94.5548)
		(end 90.1687 94.5548)
		(width 0.2032)
		(layer "B.Cu")
		(net "NetD16_3")
	)
	(segment
		(start 92.8561 85.5962)
		(end 92.8761 85.5762)
		(width 0.2032)
		(layer "F.Cu")
		(net "NetD16_2")
	)
	(segment
		(start 91.7011 85.6162)
		(end 91.7211 85.5962)
		(width 0.2032)
		(layer "F.Cu")
		(net "NetD16_2")
	)
	(segment
		(start 57.16498 115.32732)
		(end 58.06498 115.32732)
		(width 0.2032)
		(layer "F.Cu")
		(net "NetD16_2")
	)
	(segment
		(start 91.7211 85.5962)
		(end 92.8561 85.5962)
		(width 0.2032)
		(layer "F.Cu")
		(net "NetD16_2")
	)
	(segment
		(start 58.06498 115.32732)
		(end 58.1261 115.2662)
		(width 0.2032)
		(layer "F.Cu")
		(net "NetD16_2")
	)
	(segment
		(start 57.1261 115.3662)
		(end 57.16498 115.32732)
		(width 0.2032)
		(layer "F.Cu")
		(net "NetD16_2")
	)
	(via
		(at 92.8761 85.5762)
		(size 0.4064)
		(drill 0.2032)
		(layers "F.Cu" "B.Cu")
		(tenting
			(front yes)
			(back yes)
		)
		(net "NetD16_2")
	)
	(via
		(at 57.1261 115.3662)
		(size 0.4064)
		(drill 0.2032)
		(layers "F.Cu" "B.Cu")
		(tenting
			(front yes)
			(back yes)
		)
		(net "NetD16_2")
	)
	(segment
		(start 69.3949 111.8474)
		(end 69.3949 106.93226)
		(width 0.2032)
		(layer "B.Cu")
		(net "NetD16_2")
	)
	(segment
		(start 81.44216 94.885)
		(end 90.30547 94.885)
		(width 0.2032)
		(layer "B.Cu")
		(net "NetD16_2")
	)
	(segment
		(start 90.30547 94.885)
		(end 95.1449 90.04557)
		(width 0.2032)
		(layer "B.Cu")
		(net "NetD16_2")
	)
	(segment
		(start 69.3949 106.93226)
		(end 81.44216 94.885)
		(width 0.2032)
		(layer "B.Cu")
		(net "NetD16_2")
	)
	(segment
		(start 57.1261 115.3662)
		(end 65.8761 115.3662)
		(width 0.2032)
		(layer "B.Cu")
		(net "NetD16_2")
	)
	(segment
		(start 92.8761 85.5762)
		(end 93.78428 85.5762)
		(width 0.2032)
		(layer "B.Cu")
		(net "NetD16_2")
	)
	(segment
		(start 93.78428 85.5762)
		(end 95.1449 86.93682)
		(width 0.2032)
		(layer "B.Cu")
		(net "NetD16_2")
	)
	(segment
		(start 95.1449 90.04557)
		(end 95.1449 86.93682)
		(width 0.2032)
		(layer "B.Cu")
		(net "NetD16_2")
	)
	(segment
		(start 65.8761 115.3662)
		(end 69.3949 111.8474)
		(width 0.2032)
		(layer "B.Cu")
		(net "NetD16_2")
	)
	(segment
		(start 91.7211 88.6362)
		(end 92.8561 88.6362)
		(width 0.2032)
		(layer "F.Cu")
		(net "NetD15_4")
	)
	(segment
		(start 57.1261 100.1162)
		(end 57.16498 100.07732)
		(width 0.2032)
		(layer "F.Cu")
		(net "NetD15_4")
	)
	(segment
		(start 58.38998 100.07732)
		(end 58.4511 100.0162)
		(width 0.2032)
		(layer "F.Cu")
		(net "NetD15_4")
	)
	(segment
		(start 92.8561 88.6362)
		(end 92.8761 88.6562)
		(width 0.2032)
		(layer "F.Cu")
		(net "NetD15_4")
	)
	(segment
		(start 91.7011 88.6162)
		(end 91.7211 88.6362)
		(width 0.2032)
		(layer "F.Cu")
		(net "NetD15_4")
	)
	(segment
		(start 57.16498 100.07732)
		(end 58.38998 100.07732)
		(width 0.2032)
		(layer "F.Cu")
		(net "NetD15_4")
	)
	(via
		(at 57.1261 100.1162)
		(size 0.4064)
		(drill 0.2032)
		(layers "F.Cu" "B.Cu")
		(tenting
			(front yes)
			(back yes)
		)
		(net "NetD15_4")
	)
	(via
		(at 92.8761 88.6562)
		(size 0.4064)
		(drill 0.2032)
		(layers "F.Cu" "B.Cu")
		(tenting
			(front yes)
			(back yes)
		)
		(net "NetD15_4")
	)
	(segment
		(start 89.62161 93.234)
		(end 92.8761 89.97952)
		(width 0.2032)
		(layer "B.Cu")
		(net "NetD15_4")
	)
	(segment
		(start 92.8761 89.97952)
		(end 92.8761 88.6562)
		(width 0.2032)
		(layer "B.Cu")
		(net "NetD15_4")
	)
	(segment
		(start 80.7583 93.234)
		(end 89.62161 93.234)
		(width 0.2032)
		(layer "B.Cu")
		(net "NetD15_4")
	)
	(segment
		(start 73.8761 100.1162)
		(end 80.7583 93.234)
		(width 0.2032)
		(layer "B.Cu")
		(net "NetD15_4")
	)
	(segment
		(start 57.1261 100.1162)
		(end 73.8761 100.1162)
		(width 0.2032)
		(layer "B.Cu")
		(net "NetD15_4")
	)
	(segment
		(start 58.01498 101.07732)
		(end 58.1261 100.9662)
		(width 0.2032)
		(layer "F.Cu")
		(net "NetD15_3")
	)
	(segment
		(start 57.1261 101.1162)
		(end 57.16498 101.07732)
		(width 0.2032)
		(layer "F.Cu")
		(net "NetD15_3")
	)
	(segment
		(start 91.7011 88.1162)
		(end 92.63383 88.1162)
		(width 0.2032)
		(layer "F.Cu")
		(net "NetD15_3")
	)
	(segment
		(start 92.66568 88.14805)
		(end 93.3761 88.14805)
		(width 0.2032)
		(layer "F.Cu")
		(net "NetD15_3")
	)
	(segment
		(start 57.16498 101.07732)
		(end 58.01498 101.07732)
		(width 0.2032)
		(layer "F.Cu")
		(net "NetD15_3")
	)
	(segment
		(start 92.63383 88.1162)
		(end 92.66568 88.14805)
		(width 0.2032)
		(layer "F.Cu")
		(net "NetD15_3")
	)
	(via
		(at 93.3761 88.14805)
		(size 0.4064)
		(drill 0.2032)
		(layers "F.Cu" "B.Cu")
		(tenting
			(front yes)
			(back yes)
		)
		(net "NetD15_3")
	)
	(via
		(at 57.1261 101.1162)
		(size 0.4064)
		(drill 0.2032)
		(layers "F.Cu" "B.Cu")
		(tenting
			(front yes)
			(back yes)
		)
		(net "NetD15_3")
	)
	(segment
		(start 57.1261 101.1162)
		(end 73.34307 101.1162)
		(width 0.2032)
		(layer "B.Cu")
		(net "NetD15_3")
	)
	(segment
		(start 93.8241 89.49849)
		(end 93.8241 88.59605)
		(width 0.2032)
		(layer "B.Cu")
		(net "NetD15_3")
	)
	(segment
		(start 73.34307 101.1162)
		(end 80.89507 93.5642)
		(width 0.2032)
		(layer "B.Cu")
		(net "NetD15_3")
	)
	(segment
		(start 80.89507 93.5642)
		(end 89.75839 93.5642)
		(width 0.2032)
		(layer "B.Cu")
		(net "NetD15_3")
	)
	(segment
		(start 89.75839 93.5642)
		(end 93.8241 89.49849)
		(width 0.2032)
		(layer "B.Cu")
		(net "NetD15_3")
	)
	(segment
		(start 93.3761 88.14805)
		(end 93.8241 88.59605)
		(width 0.2032)
		(layer "B.Cu")
		(net "NetD15_3")
	)
	(segment
		(start 91.71303 87.62812)
		(end 92.86418 87.62812)
		(width 0.2032)
		(layer "F.Cu")
		(net "NetD15_2")
	)
	(segment
		(start 57.1261 101.8662)
		(end 58.1261 101.8662)
		(width 0.2032)
		(layer "F.Cu")
		(net "NetD15_2")
	)
	(segment
		(start 91.7011 87.6162)
		(end 91.71303 87.62812)
		(width 0.2032)
		(layer "F.Cu")
		(net "NetD15_2")
	)
	(segment
		(start 92.86418 87.62812)
		(end 92.8761 87.64005)
		(width 0.2032)
		(layer "F.Cu")
		(net "NetD15_2")
	)
	(via
		(at 92.8761 87.64005)
		(size 0.4064)
		(drill 0.2032)
		(layers "F.Cu" "B.Cu")
		(tenting
			(front yes)
			(back yes)
		)
		(net "NetD15_2")
	)
	(via
		(at 57.1261 101.8662)
		(size 0.4064)
		(drill 0.2032)
		(layers "F.Cu" "B.Cu")
		(tenting
			(front yes)
			(back yes)
		)
		(net "NetD15_2")
	)
	(segment
		(start 81.03184 93.8944)
		(end 89.89516 93.8944)
		(width 0.2032)
		(layer "B.Cu")
		(net "NetD15_2")
	)
	(segment
		(start 89.89516 93.8944)
		(end 94.1543 89.63526)
		(width 0.2032)
		(layer "B.Cu")
		(net "NetD15_2")
	)
	(segment
		(start 94.1543 89.63526)
		(end 94.1543 88.1444)
		(width 0.2032)
		(layer "B.Cu")
		(net "NetD15_2")
	)
	(segment
		(start 73.06004 101.8662)
		(end 81.03184 93.8944)
		(width 0.2032)
		(layer "B.Cu")
		(net "NetD15_2")
	)
	(segment
		(start 92.8761 87.64005)
		(end 93.64995 87.64005)
		(width 0.2032)
		(layer "B.Cu")
		(net "NetD15_2")
	)
	(segment
		(start 93.64995 87.64005)
		(end 94.1543 88.1444)
		(width 0.2032)
		(layer "B.Cu")
		(net "NetD15_2")
	)
	(segment
		(start 57.1261 101.8662)
		(end 73.06004 101.8662)
		(width 0.2032)
		(layer "B.Cu")
		(net "NetD15_2")
	)
	(segment
		(start 89.8881 90.6924)
		(end 89.8881 89.4532)
		(width 0.2032)
		(layer "F.Cu")
		(net "NetD14_4")
	)
	(segment
		(start 57.16498 81.15508)
		(end 58.33998 81.15508)
		(width 0.2032)
		(layer "F.Cu")
		(net "NetD14_4")
	)
	(segment
		(start 57.1261 81.1162)
		(end 57.16498 81.15508)
		(width 0.2032)
		(layer "F.Cu")
		(net "NetD14_4")
	)
	(segment
		(start 58.33998 81.15508)
		(end 58.4511 81.2662)
		(width 0.2032)
		(layer "F.Cu")
		(net "NetD14_4")
	)
	(segment
		(start 89.8761 89.4412)
		(end 89.8881 89.4532)
		(width 0.2032)
		(layer "F.Cu")
		(net "NetD14_4")
	)
	(segment
		(start 89.8881 90.6924)
		(end 89.9001 90.7044)
		(width 0.2032)
		(layer "F.Cu")
		(net "NetD14_4")
	)
	(via
		(at 89.9001 90.7044)
		(size 0.4064)
		(drill 0.2032)
		(layers "F.Cu" "B.Cu")
		(tenting
			(front yes)
			(back yes)
		)
		(net "NetD14_4")
	)
	(via
		(at 57.1261 81.1162)
		(size 0.4064)
		(drill 0.2032)
		(layers "F.Cu" "B.Cu")
		(tenting
			(front yes)
			(back yes)
		)
		(net "NetD14_4")
	)
	(segment
		(start 89.2113 92.2434)
		(end 89.9001 91.5546)
		(width 0.2032)
		(layer "B.Cu")
		(net "NetD14_4")
	)
	(segment
		(start 72.06004 81.1162)
		(end 83.18725 92.2434)
		(width 0.2032)
		(layer "B.Cu")
		(net "NetD14_4")
	)
	(segment
		(start 83.18725 92.2434)
		(end 89.2113 92.2434)
		(width 0.2032)
		(layer "B.Cu")
		(net "NetD14_4")
	)
	(segment
		(start 89.9001 91.5546)
		(end 89.9001 90.7044)
		(width 0.2032)
		(layer "B.Cu")
		(net "NetD14_4")
	)
	(segment
		(start 57.1261 81.1162)
		(end 72.06004 81.1162)
		(width 0.2032)
		(layer "B.Cu")
		(net "NetD14_4")
	)
	(segment
		(start 57.16498 82.15508)
		(end 58.06498 82.15508)
		(width 0.2032)
		(layer "F.Cu")
		(net "NetD14_3")
	)
	(segment
		(start 57.1261 82.1162)
		(end 57.16498 82.15508)
		(width 0.2032)
		(layer "F.Cu")
		(net "NetD14_3")
	)
	(segment
		(start 90.3761 90.37378)
		(end 90.3761 89.4412)
		(width 0.2032)
		(layer "F.Cu")
		(net "NetD14_3")
	)
	(segment
		(start 90.4081 91.1162)
		(end 90.4081 90.40578)
		(width 0.2032)
		(layer "F.Cu")
		(net "NetD14_3")
	)
	(segment
		(start 58.06498 82.15508)
		(end 58.1261 82.2162)
		(width 0.2032)
		(layer "F.Cu")
		(net "NetD14_3")
	)
	(segment
		(start 90.3761 90.37378)
		(end 90.4081 90.40578)
		(width 0.2032)
		(layer "F.Cu")
		(net "NetD14_3")
	)
	(via
		(at 57.1261 82.1162)
		(size 0.4064)
		(drill 0.2032)
		(layers "F.Cu" "B.Cu")
		(tenting
			(front yes)
			(back yes)
		)
		(net "NetD14_3")
	)
	(via
		(at 90.4081 91.1162)
		(size 0.4064)
		(drill 0.2032)
		(layers "F.Cu" "B.Cu")
		(tenting
			(front yes)
			(back yes)
		)
		(net "NetD14_3")
	)
	(segment
		(start 89.34807 92.5736)
		(end 90.36922 91.55245)
		(width 0.2032)
		(layer "B.Cu")
		(net "NetD14_3")
	)
	(segment
		(start 72.59307 82.1162)
		(end 83.05047 92.5736)
		(width 0.2032)
		(layer "B.Cu")
		(net "NetD14_3")
	)
	(segment
		(start 57.1261 82.1162)
		(end 72.59307 82.1162)
		(width 0.2032)
		(layer "B.Cu")
		(net "NetD14_3")
	)
	(segment
		(start 90.36922 91.55245)
		(end 90.36922 91.15508)
		(width 0.2032)
		(layer "B.Cu")
		(net "NetD14_3")
	)
	(segment
		(start 83.05047 92.5736)
		(end 89.34807 92.5736)
		(width 0.2032)
		(layer "B.Cu")
		(net "NetD14_3")
	)
	(segment
		(start 90.36922 91.15508)
		(end 90.4081 91.1162)
		(width 0.2032)
		(layer "B.Cu")
		(net "NetD14_3")
	)
	(segment
		(start 57.1261 83.1162)
		(end 58.1261 83.1162)
		(width 0.2032)
		(layer "F.Cu")
		(net "NetD14_2")
	)
	(segment
		(start 90.8761 89.4412)
		(end 90.8961 89.4612)
		(width 0.2032)
		(layer "F.Cu")
		(net "NetD14_2")
	)
	(segment
		(start 90.8961 90.6844)
		(end 90.8961 89.4612)
		(width 0.2032)
		(layer "F.Cu")
		(net "NetD14_2")
	)
	(segment
		(start 90.8961 90.6844)
		(end 90.9161 90.7044)
		(width 0.2032)
		(layer "F.Cu")
		(net "NetD14_2")
	)
	(via
		(at 57.1261 83.1162)
		(size 0.4064)
		(drill 0.2032)
		(layers "F.Cu" "B.Cu")
		(tenting
			(front yes)
			(back yes)
		)
		(net "NetD14_2")
	)
	(via
		(at 90.9161 90.7044)
		(size 0.4064)
		(drill 0.2032)
		(layers "F.Cu" "B.Cu")
		(tenting
			(front yes)
			(back yes)
		)
		(net "NetD14_2")
	)
	(segment
		(start 57.1261 83.1162)
		(end 73.1261 83.1162)
		(width 0.2032)
		(layer "B.Cu")
		(net "NetD14_2")
	)
	(segment
		(start 73.1261 83.1162)
		(end 82.9137 92.9038)
		(width 0.2032)
		(layer "B.Cu")
		(net "NetD14_2")
	)
	(segment
		(start 82.9137 92.9038)
		(end 89.48484 92.9038)
		(width 0.2032)
		(layer "B.Cu")
		(net "NetD14_2")
	)
	(segment
		(start 90.9161 91.47254)
		(end 90.9161 90.7044)
		(width 0.2032)
		(layer "B.Cu")
		(net "NetD14_2")
	)
	(segment
		(start 89.48484 92.9038)
		(end 90.9161 91.47254)
		(width 0.2032)
		(layer "B.Cu")
		(net "NetD14_2")
	)
	(segment
		(start 87.8681 90.7044)
		(end 87.8721 90.7004)
		(width 0.2032)
		(layer "F.Cu")
		(net "NetD13_4")
	)
	(segment
		(start 57.1261 70.3662)
		(end 57.16498 70.32732)
		(width 0.2032)
		(layer "F.Cu")
		(net "NetD13_4")
	)
	(segment
		(start 87.8721 90.7004)
		(end 87.8721 89.4452)
		(width 0.2032)
		(layer "F.Cu")
		(net "NetD13_4")
	)
	(segment
		(start 57.16498 70.32732)
		(end 58.38998 70.32732)
		(width 0.2032)
		(layer "F.Cu")
		(net "NetD13_4")
	)
	(segment
		(start 87.8721 89.4452)
		(end 87.8761 89.4412)
		(width 0.2032)
		(layer "F.Cu")
		(net "NetD13_4")
	)
	(segment
		(start 58.38998 70.32732)
		(end 58.4511 70.2662)
		(width 0.2032)
		(layer "F.Cu")
		(net "NetD13_4")
	)
	(via
		(at 57.1261 70.3662)
		(size 0.4064)
		(drill 0.2032)
		(layers "F.Cu" "B.Cu")
		(tenting
			(front yes)
			(back yes)
		)
		(net "NetD13_4")
	)
	(via
		(at 87.8681 90.7044)
		(size 0.4064)
		(drill 0.2032)
		(layers "F.Cu" "B.Cu")
		(tenting
			(front yes)
			(back yes)
		)
		(net "NetD13_4")
	)
	(segment
		(start 62.71096 70.3662)
		(end 83.59756 91.2528)
		(width 0.2032)
		(layer "B.Cu")
		(net "NetD13_4")
	)
	(segment
		(start 83.59756 91.2528)
		(end 87.3197 91.2528)
		(width 0.2032)
		(layer "B.Cu")
		(net "NetD13_4")
	)
	(segment
		(start 87.3197 91.2528)
		(end 87.8681 90.7044)
		(width 0.2032)
		(layer "B.Cu")
		(net "NetD13_4")
	)
	(segment
		(start 57.1261 70.3662)
		(end 62.71096 70.3662)
		(width 0.2032)
		(layer "B.Cu")
		(net "NetD13_4")
	)
	(segment
		(start 57.1261 71.1162)
		(end 57.16498 71.15508)
		(width 0.2032)
		(layer "F.Cu")
		(net "NetD13_3")
	)
	(segment
		(start 57.16498 71.15508)
		(end 58.06498 71.15508)
		(width 0.2032)
		(layer "F.Cu")
		(net "NetD13_3")
	)
	(segment
		(start 88.3761 91.1162)
		(end 88.3761 89.4412)
		(width 0.2032)
		(layer "F.Cu")
		(net "NetD13_3")
	)
	(segment
		(start 58.06498 71.15508)
		(end 58.1261 71.2162)
		(width 0.2032)
		(layer "F.Cu")
		(net "NetD13_3")
	)
	(via
		(at 88.3761 91.1162)
		(size 0.4064)
		(drill 0.2032)
		(layers "F.Cu" "B.Cu")
		(tenting
			(front yes)
			(back yes)
		)
		(net "NetD13_3")
	)
	(via
		(at 57.1261 71.1162)
		(size 0.4064)
		(drill 0.2032)
		(layers "F.Cu" "B.Cu")
		(tenting
			(front yes)
			(back yes)
		)
		(net "NetD13_3")
	)
	(segment
		(start 62.99399 71.1162)
		(end 83.46079 91.583)
		(width 0.2032)
		(layer "B.Cu")
		(net "NetD13_3")
	)
	(segment
		(start 87.9093 91.583)
		(end 88.3761 91.1162)
		(width 0.2032)
		(layer "B.Cu")
		(net "NetD13_3")
	)
	(segment
		(start 83.46079 91.583)
		(end 87.9093 91.583)
		(width 0.2032)
		(layer "B.Cu")
		(net "NetD13_3")
	)
	(segment
		(start 57.1261 71.1162)
		(end 62.99399 71.1162)
		(width 0.2032)
		(layer "B.Cu")
		(net "NetD13_3")
	)
	(segment
		(start 88.8801 90.7004)
		(end 88.8841 90.7044)
		(width 0.2032)
		(layer "F.Cu")
		(net "NetD13_2")
	)
	(segment
		(start 88.8801 90.7004)
		(end 88.8801 89.4452)
		(width 0.2032)
		(layer "F.Cu")
		(net "NetD13_2")
	)
	(segment
		(start 57.1261 72.1162)
		(end 58.1261 72.1162)
		(width 0.2032)
		(layer "F.Cu")
		(net "NetD13_2")
	)
	(segment
		(start 88.8761 89.4412)
		(end 88.8801 89.4452)
		(width 0.2032)
		(layer "F.Cu")
		(net "NetD13_2")
	)
	(via
		(at 88.8841 90.7044)
		(size 0.4064)
		(drill 0.2032)
		(layers "F.Cu" "B.Cu")
		(tenting
			(front yes)
			(back yes)
		)
		(net "NetD13_2")
	)
	(via
		(at 57.1261 72.1162)
		(size 0.4064)
		(drill 0.2032)
		(layers "F.Cu" "B.Cu")
		(tenting
			(front yes)
			(back yes)
		)
		(net "NetD13_2")
	)
	(segment
		(start 88.8841 91.32662)
		(end 88.8841 90.7044)
		(width 0.2032)
		(layer "B.Cu")
		(net "NetD13_2")
	)
	(segment
		(start 88.29752 91.9132)
		(end 88.8841 91.32662)
		(width 0.2032)
		(layer "B.Cu")
		(net "NetD13_2")
	)
	(segment
		(start 57.1261 72.1162)
		(end 63.52702 72.1162)
		(width 0.2032)
		(layer "B.Cu")
		(net "NetD13_2")
	)
	(segment
		(start 63.52702 72.1162)
		(end 83.32402 91.9132)
		(width 0.2032)
		(layer "B.Cu")
		(net "NetD13_2")
	)
	(segment
		(start 83.32402 91.9132)
		(end 88.29752 91.9132)
		(width 0.2032)
		(layer "B.Cu")
		(net "NetD13_2")
	)
	(segment
		(start 85.8761 85.6162)
		(end 87.0511 85.6162)
		(width 0.254)
		(layer "F.Cu")
		(net "NetC39_2")
	)
	(segment
		(start 84.2761 84.8662)
		(end 85.1261 84.8662)
		(width 0.254)
		(layer "F.Cu")
		(net "NetC39_2")
	)
	(segment
		(start 82.4006 84.7162)
		(end 84.1261 84.7162)
		(width 0.254)
		(layer "F.Cu")
		(net "NetC39_2")
	)
	(segment
		(start 84.1261 84.7162)
		(end 84.2761 84.8662)
		(width 0.254)
		(layer "F.Cu")
		(net "NetC39_2")
	)
	(segment
		(start 82.39059 84.7062)
		(end 82.4006 84.7162)
		(width 0.254)
		(layer "F.Cu")
		(net "NetC39_2")
	)
	(segment
		(start 85.1261 84.8662)
		(end 85.8761 85.6162)
		(width 0.254)
		(layer "F.Cu")
		(net "NetC39_2")
	)
	(segment
		(start 146.22856 115.3662)
		(end 146.28233 115.31242)
		(width 0.2032)
		(layer "F.Cu")
		(net "EXT_GPIO_10")
	)
	(segment
		(start 146.28233 115.31242)
		(end 147.69091 115.31242)
		(width 0.2032)
		(layer "F.Cu")
		(net "EXT_GPIO_10")
	)
	(segment
		(start 145.3841 115.3662)
		(end 146.22856 115.3662)
		(width 0.2032)
		(layer "F.Cu")
		(net "EXT_GPIO_10")
	)
	(via
		(at 145.3841 115.3662)
		(size 0.4064)
		(drill 0.2032)
		(layers "F.Cu" "B.Cu")
		(tenting
			(front yes)
			(back yes)
		)
		(net "EXT_GPIO_10")
	)
	(segment
		(start 205.3667 112.50772)
		(end 205.3667 58.88982)
		(width 0.2032)
		(layer "B.Cu")
		(net "EXT_GPIO_10")
	)
	(segment
		(start 148.94682 117.536)
		(end 200.33842 117.536)
		(width 0.2032)
		(layer "B.Cu")
		(net "EXT_GPIO_10")
	)
	(segment
		(start 205.1261 58.64923)
		(end 205.3667 58.88982)
		(width 0.2032)
		(layer "B.Cu")
		(net "EXT_GPIO_10")
	)
	(segment
		(start 145.3841 115.3662)
		(end 146.77702 115.3662)
		(width 0.2032)
		(layer "B.Cu")
		(net "EXT_GPIO_10")
	)
	(segment
		(start 146.77702 115.3662)
		(end 148.94682 117.536)
		(width 0.2032)
		(layer "B.Cu")
		(net "EXT_GPIO_10")
	)
	(segment
		(start 200.33842 117.536)
		(end 205.3667 112.50772)
		(width 0.2032)
		(layer "B.Cu")
		(net "EXT_GPIO_10")
	)
	(segment
		(start 205.1261 58.64923)
		(end 205.1261 53.59766)
		(width 0.2032)
		(layer "B.Cu")
		(net "EXT_GPIO_10")
	)
	(segment
		(start 146.53639 115.8123)
		(end 147.69091 115.8123)
		(width 0.2032)
		(layer "F.Cu")
		(net "EXT_GPIO_9")
	)
	(segment
		(start 145.8761 115.8742)
		(end 146.47449 115.8742)
		(width 0.2032)
		(layer "F.Cu")
		(net "EXT_GPIO_9")
	)
	(segment
		(start 146.47449 115.8742)
		(end 146.53639 115.8123)
		(width 0.2032)
		(layer "F.Cu")
		(net "EXT_GPIO_9")
	)
	(via
		(at 145.8761 115.8742)
		(size 0.4064)
		(drill 0.2032)
		(layers "F.Cu" "B.Cu")
		(tenting
			(front yes)
			(back yes)
		)
		(net "EXT_GPIO_9")
	)
	(segment
		(start 205.6969 59.5454)
		(end 207.6661 57.5762)
		(width 0.2032)
		(layer "B.Cu")
		(net "EXT_GPIO_9")
	)
	(segment
		(start 200.47519 117.8662)
		(end 205.6969 112.64449)
		(width 0.2032)
		(layer "B.Cu")
		(net "EXT_GPIO_9")
	)
	(segment
		(start 145.8761 115.8742)
		(end 146.81805 115.8742)
		(width 0.2032)
		(layer "B.Cu")
		(net "EXT_GPIO_9")
	)
	(segment
		(start 146.81805 115.8742)
		(end 148.81005 117.8662)
		(width 0.2032)
		(layer "B.Cu")
		(net "EXT_GPIO_9")
	)
	(segment
		(start 205.6969 112.64449)
		(end 205.6969 59.5454)
		(width 0.2032)
		(layer "B.Cu")
		(net "EXT_GPIO_9")
	)
	(segment
		(start 207.6661 57.5762)
		(end 207.6661 54.1162)
		(width 0.2032)
		(layer "B.Cu")
		(net "EXT_GPIO_9")
	)
	(segment
		(start 148.81005 117.8662)
		(end 200.47519 117.8662)
		(width 0.2032)
		(layer "B.Cu")
		(net "EXT_GPIO_9")
	)
	(segment
		(start 146.29033 116.31242)
		(end 147.69091 116.31242)
		(width 0.2032)
		(layer "F.Cu")
		(net "EXT_GPIO_8")
	)
	(segment
		(start 145.3841 116.3742)
		(end 145.3921 116.3822)
		(width 0.2032)
		(layer "F.Cu")
		(net "EXT_GPIO_8")
	)
	(segment
		(start 145.3921 116.3822)
		(end 146.22056 116.3822)
		(width 0.2032)
		(layer "F.Cu")
		(net "EXT_GPIO_8")
	)
	(segment
		(start 146.22056 116.3822)
		(end 146.29033 116.31242)
		(width 0.2032)
		(layer "F.Cu")
		(net "EXT_GPIO_8")
	)
	(via
		(at 145.3841 116.3742)
		(size 0.4064)
		(drill 0.2032)
		(layers "F.Cu" "B.Cu")
		(tenting
			(front yes)
			(back yes)
		)
		(net "EXT_GPIO_8")
	)
	(segment
		(start 200.61196 118.1964)
		(end 206.0271 112.78126)
		(width 0.2032)
		(layer "B.Cu")
		(net "EXT_GPIO_8")
	)
	(segment
		(start 146.85907 116.3822)
		(end 148.67327 118.1964)
		(width 0.2032)
		(layer "B.Cu")
		(net "EXT_GPIO_8")
	)
	(segment
		(start 206.0271 112.78126)
		(end 206.0271 59.68217)
		(width 0.2032)
		(layer "B.Cu")
		(net "EXT_GPIO_8")
	)
	(segment
		(start 206.0271 59.68217)
		(end 210.2061 55.50317)
		(width 0.2032)
		(layer "B.Cu")
		(net "EXT_GPIO_8")
	)
	(segment
		(start 210.2061 55.50317)
		(end 210.2061 54.1162)
		(width 0.2032)
		(layer "B.Cu")
		(net "EXT_GPIO_8")
	)
	(segment
		(start 148.67327 118.1964)
		(end 200.61196 118.1964)
		(width 0.2032)
		(layer "B.Cu")
		(net "EXT_GPIO_8")
	)
	(segment
		(start 145.3841 116.3742)
		(end 145.3921 116.3822)
		(width 0.2032)
		(layer "B.Cu")
		(net "EXT_GPIO_8")
	)
	(segment
		(start 145.3921 116.3822)
		(end 146.85907 116.3822)
		(width 0.2032)
		(layer "B.Cu")
		(net "EXT_GPIO_8")
	)
	(segment
		(start 145.93108 116.8902)
		(end 146.00899 116.81229)
		(width 0.2032)
		(layer "F.Cu")
		(net "EXT_GPIO_7")
	)
	(segment
		(start 146.00899 116.81229)
		(end 147.69091 116.81229)
		(width 0.2032)
		(layer "F.Cu")
		(net "EXT_GPIO_7")
	)
	(segment
		(start 145.8761 116.8902)
		(end 145.93108 116.8902)
		(width 0.2032)
		(layer "F.Cu")
		(net "EXT_GPIO_7")
	)
	(via
		(at 145.8761 116.8902)
		(size 0.4064)
		(drill 0.2032)
		(layers "F.Cu" "B.Cu")
		(tenting
			(front yes)
			(back yes)
		)
		(net "EXT_GPIO_7")
	)
	(segment
		(start 206.3573 113.885)
		(end 206.3573 60.505)
		(width 0.2032)
		(layer "B.Cu")
		(net "EXT_GPIO_7")
	)
	(segment
		(start 201.7157 118.5266)
		(end 206.3573 113.885)
		(width 0.2032)
		(layer "B.Cu")
		(net "EXT_GPIO_7")
	)
	(segment
		(start 146.9001 116.8902)
		(end 148.5365 118.5266)
		(width 0.2032)
		(layer "B.Cu")
		(net "EXT_GPIO_7")
	)
	(segment
		(start 148.5365 118.5266)
		(end 201.7157 118.5266)
		(width 0.2032)
		(layer "B.Cu")
		(net "EXT_GPIO_7")
	)
	(segment
		(start 206.3573 60.505)
		(end 212.7461 54.1162)
		(width 0.2032)
		(layer "B.Cu")
		(net "EXT_GPIO_7")
	)
	(segment
		(start 145.8761 116.8902)
		(end 146.9001 116.8902)
		(width 0.2032)
		(layer "B.Cu")
		(net "EXT_GPIO_7")
	)
	(segment
		(start 145.3761 112.8662)
		(end 146.2285 112.8662)
		(width 0.2032)
		(layer "F.Cu")
		(net "EXT_GPIO_4")
	)
	(segment
		(start 146.2285 112.8662)
		(end 146.28239 112.8123)
		(width 0.2032)
		(layer "F.Cu")
		(net "EXT_GPIO_4")
	)
	(segment
		(start 146.28239 112.8123)
		(end 147.69091 112.8123)
		(width 0.2032)
		(layer "F.Cu")
		(net "EXT_GPIO_4")
	)
	(via
		(at 145.3761 112.8662)
		(size 0.4064)
		(drill 0.2032)
		(layers "F.Cu" "B.Cu")
		(tenting
			(front yes)
			(back yes)
		)
		(net "EXT_GPIO_4")
	)
	(segment
		(start 168.3949 112.8662)
		(end 171.0835 115.5548)
		(width 0.2032)
		(layer "B.Cu")
		(net "EXT_GPIO_4")
	)
	(segment
		(start 201.3761 53.6162)
		(end 202.1261 52.8662)
		(width 0.2032)
		(layer "B.Cu")
		(net "EXT_GPIO_4")
	)
	(segment
		(start 200.9187 115.5548)
		(end 203.4261 113.0474)
		(width 0.2032)
		(layer "B.Cu")
		(net "EXT_GPIO_4")
	)
	(segment
		(start 202.1261 52.8662)
		(end 203.8361 52.8662)
		(width 0.2032)
		(layer "B.Cu")
		(net "EXT_GPIO_4")
	)
	(segment
		(start 201.3761 56.3662)
		(end 201.3761 53.6162)
		(width 0.2032)
		(layer "B.Cu")
		(net "EXT_GPIO_4")
	)
	(segment
		(start 203.4261 113.0474)
		(end 203.4261 58.4162)
		(width 0.2032)
		(layer "B.Cu")
		(net "EXT_GPIO_4")
	)
	(segment
		(start 145.3761 112.8662)
		(end 168.3949 112.8662)
		(width 0.2032)
		(layer "B.Cu")
		(net "EXT_GPIO_4")
	)
	(segment
		(start 201.3761 56.3662)
		(end 203.4261 58.4162)
		(width 0.2032)
		(layer "B.Cu")
		(net "EXT_GPIO_4")
	)
	(segment
		(start 203.8361 52.8662)
		(end 205.1261 51.5762)
		(width 0.2032)
		(layer "B.Cu")
		(net "EXT_GPIO_4")
	)
	(segment
		(start 171.0835 115.5548)
		(end 200.9187 115.5548)
		(width 0.2032)
		(layer "B.Cu")
		(net "EXT_GPIO_4")
	)
	(segment
		(start 146.53633 113.31243)
		(end 147.69091 113.31243)
		(width 0.2032)
		(layer "F.Cu")
		(net "EXT_GPIO_3")
	)
	(segment
		(start 146.47456 113.3742)
		(end 146.53633 113.31243)
		(width 0.2032)
		(layer "F.Cu")
		(net "EXT_GPIO_3")
	)
	(segment
		(start 145.8761 113.3742)
		(end 146.47456 113.3742)
		(width 0.2032)
		(layer "F.Cu")
		(net "EXT_GPIO_3")
	)
	(via
		(at 145.8761 113.3742)
		(size 0.4064)
		(drill 0.2032)
		(layers "F.Cu" "B.Cu")
		(tenting
			(front yes)
			(back yes)
		)
		(net "EXT_GPIO_3")
	)
	(segment
		(start 203.6409 53.54683)
		(end 204.45653 52.7312)
		(width 0.2032)
		(layer "B.Cu")
		(net "EXT_GPIO_3")
	)
	(segment
		(start 203.6409 58.131)
		(end 203.6409 53.54683)
		(width 0.2032)
		(layer "B.Cu")
		(net "EXT_GPIO_3")
	)
	(segment
		(start 203.6409 58.131)
		(end 204.7063 59.1964)
		(width 0.2032)
		(layer "B.Cu")
		(net "EXT_GPIO_3")
	)
	(segment
		(start 201.05547 115.885)
		(end 204.7063 112.23417)
		(width 0.2032)
		(layer "B.Cu")
		(net "EXT_GPIO_3")
	)
	(segment
		(start 206.8761 52.7312)
		(end 207.1306 52.4767)
		(width 0.2032)
		(layer "B.Cu")
		(net "EXT_GPIO_3")
	)
	(segment
		(start 207.1306 52.46261)
		(end 207.6661 51.92711)
		(width 0.2032)
		(layer "B.Cu")
		(net "EXT_GPIO_3")
	)
	(segment
		(start 207.1306 52.4767)
		(end 207.1306 52.46261)
		(width 0.2032)
		(layer "B.Cu")
		(net "EXT_GPIO_3")
	)
	(segment
		(start 204.45653 52.7312)
		(end 206.8761 52.7312)
		(width 0.2032)
		(layer "B.Cu")
		(net "EXT_GPIO_3")
	)
	(segment
		(start 170.94673 115.885)
		(end 201.05547 115.885)
		(width 0.2032)
		(layer "B.Cu")
		(net "EXT_GPIO_3")
	)
	(segment
		(start 168.43593 113.3742)
		(end 170.94673 115.885)
		(width 0.2032)
		(layer "B.Cu")
		(net "EXT_GPIO_3")
	)
	(segment
		(start 204.7063 112.23417)
		(end 204.7063 59.1964)
		(width 0.2032)
		(layer "B.Cu")
		(net "EXT_GPIO_3")
	)
	(segment
		(start 145.8761 113.3742)
		(end 168.43593 113.3742)
		(width 0.2032)
		(layer "B.Cu")
		(net "EXT_GPIO_3")
	)
	(segment
		(start 207.6661 51.92711)
		(end 207.6661 51.5762)
		(width 0.2032)
		(layer "B.Cu")
		(net "EXT_GPIO_3")
	)
	(segment
		(start 146.22049 113.8822)
		(end 146.29039 113.8123)
		(width 0.2032)
		(layer "F.Cu")
		(net "EXT_GPIO_2")
	)
	(segment
		(start 145.3761 113.8662)
		(end 145.3921 113.8822)
		(width 0.2032)
		(layer "F.Cu")
		(net "EXT_GPIO_2")
	)
	(segment
		(start 145.3921 113.8822)
		(end 146.22049 113.8822)
		(width 0.2032)
		(layer "F.Cu")
		(net "EXT_GPIO_2")
	)
	(segment
		(start 146.29039 113.8123)
		(end 147.69091 113.8123)
		(width 0.2032)
		(layer "F.Cu")
		(net "EXT_GPIO_2")
	)
	(via
		(at 145.3761 113.8662)
		(size 0.4064)
		(drill 0.2032)
		(layers "F.Cu" "B.Cu")
		(tenting
			(front yes)
			(back yes)
		)
		(net "EXT_GPIO_2")
	)
	(segment
		(start 205.0365 112.37094)
		(end 205.0365 59.0266)
		(width 0.2032)
		(layer "B.Cu")
		(net "EXT_GPIO_2")
	)
	(segment
		(start 203.9761 53.6786)
		(end 204.5933 53.0614)
		(width 0.2032)
		(layer "B.Cu")
		(net "EXT_GPIO_2")
	)
	(segment
		(start 210.0017 52.631)
		(end 210.0017 51.7806)
		(width 0.2032)
		(layer "B.Cu")
		(net "EXT_GPIO_2")
	)
	(segment
		(start 170.80996 116.2152)
		(end 201.19224 116.2152)
		(width 0.2032)
		(layer "B.Cu")
		(net "EXT_GPIO_2")
	)
	(segment
		(start 145.3761 113.8662)
		(end 145.3921 113.8822)
		(width 0.2032)
		(layer "B.Cu")
		(net "EXT_GPIO_2")
	)
	(segment
		(start 203.9761 57.9662)
		(end 205.0365 59.0266)
		(width 0.2032)
		(layer "B.Cu")
		(net "EXT_GPIO_2")
	)
	(segment
		(start 203.9761 57.9662)
		(end 203.9761 53.6786)
		(width 0.2032)
		(layer "B.Cu")
		(net "EXT_GPIO_2")
	)
	(segment
		(start 201.19224 116.2152)
		(end 205.0365 112.37094)
		(width 0.2032)
		(layer "B.Cu")
		(net "EXT_GPIO_2")
	)
	(segment
		(start 145.3921 113.8822)
		(end 168.47696 113.8822)
		(width 0.2032)
		(layer "B.Cu")
		(net "EXT_GPIO_2")
	)
	(segment
		(start 168.47696 113.8822)
		(end 170.80996 116.2152)
		(width 0.2032)
		(layer "B.Cu")
		(net "EXT_GPIO_2")
	)
	(segment
		(start 210.0017 51.7806)
		(end 210.2061 51.5762)
		(width 0.2032)
		(layer "B.Cu")
		(net "EXT_GPIO_2")
	)
	(segment
		(start 209.5713 53.0614)
		(end 210.0017 52.631)
		(width 0.2032)
		(layer "B.Cu")
		(net "EXT_GPIO_2")
	)
	(segment
		(start 204.5933 53.0614)
		(end 209.5713 53.0614)
		(width 0.2032)
		(layer "B.Cu")
		(net "EXT_GPIO_2")
	)
	(segment
		(start 146.00886 114.31243)
		(end 147.69091 114.31243)
		(width 0.2032)
		(layer "F.Cu")
		(net "EXT_GPIO_1")
	)
	(segment
		(start 145.8761 114.3902)
		(end 145.93108 114.3902)
		(width 0.2032)
		(layer "F.Cu")
		(net "EXT_GPIO_1")
	)
	(segment
		(start 145.93108 114.3902)
		(end 146.00886 114.31243)
		(width 0.2032)
		(layer "F.Cu")
		(net "EXT_GPIO_1")
	)
	(via
		(at 145.8761 114.3902)
		(size 0.4064)
		(drill 0.2032)
		(layers "F.Cu" "B.Cu")
		(tenting
			(front yes)
			(back yes)
		)
		(net "EXT_GPIO_1")
	)
	(segment
		(start 144.8761 117.1162)
		(end 144.8761 114.8662)
		(width 0.2032)
		(layer "B.Cu")
		(net "EXT_GPIO_1")
	)
	(segment
		(start 213.8009 54.55311)
		(end 213.8009 52.631)
		(width 0.2032)
		(layer "B.Cu")
		(net "EXT_GPIO_1")
	)
	(segment
		(start 146.6261 118.8662)
		(end 202.0761 118.8662)
		(width 0.2032)
		(layer "B.Cu")
		(net "EXT_GPIO_1")
	)
	(segment
		(start 206.6875 86.5162)
		(end 206.6875 61.66651)
		(width 0.2032)
		(layer "B.Cu")
		(net "EXT_GPIO_1")
	)
	(segment
		(start 212.7461 51.5762)
		(end 213.8009 52.631)
		(width 0.2032)
		(layer "B.Cu")
		(net "EXT_GPIO_1")
	)
	(segment
		(start 206.6875 61.66651)
		(end 213.8009 54.55311)
		(width 0.2032)
		(layer "B.Cu")
		(net "EXT_GPIO_1")
	)
	(segment
		(start 144.8761 117.1162)
		(end 146.6261 118.8662)
		(width 0.2032)
		(layer "B.Cu")
		(net "EXT_GPIO_1")
	)
	(segment
		(start 145.3521 114.3902)
		(end 145.8761 114.3902)
		(width 0.2032)
		(layer "B.Cu")
		(net "EXT_GPIO_1")
	)
	(segment
		(start 206.6875 86.5162)
		(end 207.9261 87.7548)
		(width 0.2032)
		(layer "B.Cu")
		(net "EXT_GPIO_1")
	)
	(segment
		(start 144.8761 114.8662)
		(end 145.3521 114.3902)
		(width 0.2032)
		(layer "B.Cu")
		(net "EXT_GPIO_1")
	)
	(segment
		(start 202.0761 118.8662)
		(end 206.6875 114.2548)
		(width 0.2032)
		(layer "B.Cu")
		(net "EXT_GPIO_1")
	)
	(segment
		(start 206.6875 91.7162)
		(end 207.9261 90.4776)
		(width 0.2032)
		(layer "B.Cu")
		(net "EXT_GPIO_1")
	)
	(segment
		(start 206.6875 114.2548)
		(end 206.6875 91.7162)
		(width 0.2032)
		(layer "B.Cu")
		(net "EXT_GPIO_1")
	)
	(segment
		(start 207.9261 90.4776)
		(end 207.9261 87.7548)
		(width 0.2032)
		(layer "B.Cu")
		(net "EXT_GPIO_1")
	)
	(segment
		(start 169.32587 98.98917)
		(end 169.87256 99.53586)
		(width 0.2032)
		(layer "F.Cu")
		(net "ANT4_OUT")
	)
	(segment
		(start 169.87256 99.53586)
		(end 170.17266 99.53586)
		(width 0.2032)
		(layer "F.Cu")
		(net "ANT4_OUT")
	)
	(segment
		(start 84.82111 136.4758)
		(end 84.8761 136.4758)
		(width 0.2032)
		(layer "F.Cu")
		(net "ANT4_OUT")
	)
	(segment
		(start 170.17266 99.53586)
		(end 170.21154 99.57474)
		(width 0.2032)
		(layer "F.Cu")
		(net "ANT4_OUT")
	)
	(segment
		(start 83.7011 136.3662)
		(end 84.71151 136.3662)
		(width 0.2032)
		(layer "F.Cu")
		(net "ANT4_OUT")
	)
	(segment
		(start 169.32587 98.98917)
		(end 169.32587 97.91825)
		(width 0.2032)
		(layer "F.Cu")
		(net "ANT4_OUT")
	)
	(segment
		(start 84.71151 136.3662)
		(end 84.82111 136.4758)
		(width 0.2032)
		(layer "F.Cu")
		(net "ANT4_OUT")
	)
	(via
		(at 170.21154 99.57474)
		(size 0.4064)
		(drill 0.2032)
		(layers "F.Cu" "B.Cu")
		(tenting
			(front yes)
			(back yes)
		)
		(net "ANT4_OUT")
	)
	(via
		(at 84.8761 136.4758)
		(size 0.4064)
		(drill 0.2032)
		(layers "F.Cu" "B.Cu")
		(tenting
			(front yes)
			(back yes)
		)
		(net "ANT4_OUT")
	)
	(segment
		(start 86.8761 134.4758)
		(end 86.8761 107.64923)
		(width 0.2032)
		(layer "In3.Cu")
		(net "ANT4_OUT")
	)
	(segment
		(start 170.21154 100.39864)
		(end 170.21154 99.57474)
		(width 0.2032)
		(layer "In3.Cu")
		(net "ANT4_OUT")
	)
	(segment
		(start 166.62768 103.9825)
		(end 170.21154 100.39864)
		(width 0.2032)
		(layer "In3.Cu")
		(net "ANT4_OUT")
	)
	(segment
		(start 86.8761 107.64923)
		(end 90.54283 103.9825)
		(width 0.2032)
		(layer "In3.Cu")
		(net "ANT4_OUT")
	)
	(segment
		(start 84.8761 136.4758)
		(end 86.8761 134.4758)
		(width 0.2032)
		(layer "In3.Cu")
		(net "ANT4_OUT")
	)
	(segment
		(start 90.54283 103.9825)
		(end 166.62768 103.9825)
		(width 0.2032)
		(layer "In3.Cu")
		(net "ANT4_OUT")
	)
	(segment
		(start 83.0777 136.9146)
		(end 83.6527 136.9146)
		(width 0.2032)
		(layer "F.Cu")
		(net "ANT4_IO_OUT")
	)
	(segment
		(start 82.8761 137.8662)
		(end 82.8761 137.1162)
		(width 0.2032)
		(layer "F.Cu")
		(net "ANT4_IO_OUT")
	)
	(segment
		(start 83.6527 136.9146)
		(end 83.7011 136.8662)
		(width 0.2032)
		(layer "F.Cu")
		(net "ANT4_IO_OUT")
	)
	(segment
		(start 153.65794 112.36778)
		(end 153.69682 112.3289)
		(width 0.2032)
		(layer "F.Cu")
		(net "ANT4_IO_OUT")
	)
	(segment
		(start 84.1261 138.8662)
		(end 85.3761 138.8662)
		(width 0.254)
		(layer "F.Cu")
		(net "ANT4_IO_OUT")
	)
	(segment
		(start 153.20324 113.28906)
		(end 153.65794 112.83436)
		(width 0.2032)
		(layer "F.Cu")
		(net "ANT4_IO_OUT")
	)
	(segment
		(start 82.8761 137.8662)
		(end 83.51377 138.50387)
		(width 0.2032)
		(layer "F.Cu")
		(net "ANT4_IO_OUT")
	)
	(segment
		(start 83.7527 138.50387)
		(end 83.84442 138.59559)
		(width 0.2032)
		(layer "F.Cu")
		(net "ANT4_IO_OUT")
	)
	(segment
		(start 82.8761 137.1162)
		(end 83.0777 136.9146)
		(width 0.2032)
		(layer "F.Cu")
		(net "ANT4_IO_OUT")
	)
	(segment
		(start 83.84442 138.83452)
		(end 83.84442 138.59559)
		(width 0.2032)
		(layer "F.Cu")
		(net "ANT4_IO_OUT")
	)
	(segment
		(start 151.76406 113.28906)
		(end 153.20324 113.28906)
		(width 0.2032)
		(layer "F.Cu")
		(net "ANT4_IO_OUT")
	)
	(segment
		(start 83.51377 138.50387)
		(end 83.7527 138.50387)
		(width 0.2032)
		(layer "F.Cu")
		(net "ANT4_IO_OUT")
	)
	(segment
		(start 153.65794 112.83436)
		(end 153.65794 112.36778)
		(width 0.2032)
		(layer "F.Cu")
		(net "ANT4_IO_OUT")
	)
	(segment
		(start 151.74069 113.31243)
		(end 151.76406 113.28906)
		(width 0.2032)
		(layer "F.Cu")
		(net "ANT4_IO_OUT")
	)
	(via
		(at 153.69682 112.3289)
		(size 0.4064)
		(drill 0.2032)
		(layers "F.Cu" "B.Cu")
		(tenting
			(front yes)
			(back yes)
		)
		(net "ANT4_IO_OUT")
	)
	(via
		(at 85.3761 138.8662)
		(size 0.4064)
		(drill 0.2032)
		(layers "F.Cu" "B.Cu")
		(tenting
			(front yes)
			(back yes)
		)
		(net "ANT4_IO_OUT")
	)
	(segment
		(start 153.69682 112.3289)
		(end 153.71298 112.31274)
		(width 0.254)
		(layer "In3.Cu")
		(net "ANT4_IO_OUT")
	)
	(segment
		(start 92.3761 112.6162)
		(end 94.3761 110.6162)
		(width 0.254)
		(layer "In3.Cu")
		(net "ANT4_IO_OUT")
	)
	(segment
		(start 94.3761 110.6162)
		(end 152.63044 110.6162)
		(width 0.254)
		(layer "In3.Cu")
		(net "ANT4_IO_OUT")
	)
	(segment
		(start 152.63044 110.6162)
		(end 153.71298 111.69874)
		(width 0.254)
		(layer "In3.Cu")
		(net "ANT4_IO_OUT")
	)
	(segment
		(start 92.3761 135.3662)
		(end 92.3761 112.6162)
		(width 0.254)
		(layer "In3.Cu")
		(net "ANT4_IO_OUT")
	)
	(segment
		(start 85.3761 138.8662)
		(end 88.8761 138.8662)
		(width 0.254)
		(layer "In3.Cu")
		(net "ANT4_IO_OUT")
	)
	(segment
		(start 88.8761 138.8662)
		(end 92.3761 135.3662)
		(width 0.254)
		(layer "In3.Cu")
		(net "ANT4_IO_OUT")
	)
	(segment
		(start 153.71298 112.31274)
		(end 153.71298 111.69874)
		(width 0.254)
		(layer "In3.Cu")
		(net "ANT4_IO_OUT")
	)
	(segment
		(start 82.1261 138.8662)
		(end 83.00707 138.8662)
		(width 0.2032)
		(layer "F.Cu")
		(net "ANT4_IO_IN")
	)
	(segment
		(start 151.74069 112.8123)
		(end 152.93 112.8123)
		(width 0.2032)
		(layer "F.Cu")
		(net "ANT4_IO_IN")
	)
	(segment
		(start 152.93 112.8123)
		(end 153.08722 112.65508)
		(width 0.2032)
		(layer "F.Cu")
		(net "ANT4_IO_IN")
	)
	(segment
		(start 151.74069 112.8123)
		(end 151.74069 112.8123)
		(width 0.2032)
		(layer "F.Cu")
		(net "ANT4_IO_IN")
	)
	(segment
		(start 80.5511 136.3662)
		(end 81.8761 136.3662)
		(width 0.2032)
		(layer "F.Cu")
		(net "ANT4_IO_IN")
	)
	(segment
		(start 81.8761 136.3662)
		(end 82.1261 136.6162)
		(width 0.2032)
		(layer "F.Cu")
		(net "ANT4_IO_IN")
	)
	(segment
		(start 153.17958 112.43693)
		(end 153.17958 111.91968)
		(width 0.2032)
		(layer "F.Cu")
		(net "ANT4_IO_IN")
	)
	(segment
		(start 153.08722 112.65508)
		(end 153.08722 112.52929)
		(width 0.2032)
		(layer "F.Cu")
		(net "ANT4_IO_IN")
	)
	(segment
		(start 83.1261 141.6162)
		(end 83.1261 138.98523)
		(width 0.2032)
		(layer "F.Cu")
		(net "ANT4_IO_IN")
	)
	(segment
		(start 83.00707 138.8662)
		(end 83.1261 138.98523)
		(width 0.2032)
		(layer "F.Cu")
		(net "ANT4_IO_IN")
	)
	(segment
		(start 82.1261 138.8662)
		(end 82.1261 136.6162)
		(width 0.2032)
		(layer "F.Cu")
		(net "ANT4_IO_IN")
	)
	(segment
		(start 153.08722 112.52929)
		(end 153.17958 112.43693)
		(width 0.2032)
		(layer "F.Cu")
		(net "ANT4_IO_IN")
	)
	(via
		(at 83.1261 141.6162)
		(size 0.4064)
		(drill 0.2032)
		(layers "F.Cu" "B.Cu")
		(tenting
			(front yes)
			(back yes)
		)
		(net "ANT4_IO_IN")
	)
	(via
		(at 153.17958 111.91968)
		(size 0.4064)
		(drill 0.2032)
		(layers "F.Cu" "B.Cu")
		(tenting
			(front yes)
			(back yes)
		)
		(net "ANT4_IO_IN")
	)
	(segment
		(start 152.3761 111.1162)
		(end 153.17958 111.91968)
		(width 0.2032)
		(layer "In3.Cu")
		(net "ANT4_IO_IN")
	)
	(segment
		(start 87.6261 141.6162)
		(end 93.1261 136.1162)
		(width 0.2032)
		(layer "In3.Cu")
		(net "ANT4_IO_IN")
	)
	(segment
		(start 83.1261 141.6162)
		(end 87.6261 141.6162)
		(width 0.2032)
		(layer "In3.Cu")
		(net "ANT4_IO_IN")
	)
	(segment
		(start 93.1261 136.1162)
		(end 93.1261 112.8662)
		(width 0.2032)
		(layer "In3.Cu")
		(net "ANT4_IO_IN")
	)
	(segment
		(start 153.17958 111.91968)
		(end 153.17958 111.91968)
		(width 0.2032)
		(layer "In3.Cu")
		(net "ANT4_IO_IN")
	)
	(segment
		(start 94.8761 111.1162)
		(end 152.3761 111.1162)
		(width 0.2032)
		(layer "In3.Cu")
		(net "ANT4_IO_IN")
	)
	(segment
		(start 93.1261 112.8662)
		(end 94.8761 111.1162)
		(width 0.2032)
		(layer "In3.Cu")
		(net "ANT4_IO_IN")
	)
	(segment
		(start 166.8921 95.54521)
		(end 166.8921 94.97854)
		(width 0.2032)
		(layer "F.Cu")
		(net "ANT4_IN")
	)
	(segment
		(start 166.6261 95.81121)
		(end 166.8921 95.54521)
		(width 0.2032)
		(layer "F.Cu")
		(net "ANT4_IN")
	)
	(segment
		(start 83.7011 135.8662)
		(end 83.72831 135.83899)
		(width 0.2032)
		(layer "F.Cu")
		(net "ANT4_IN")
	)
	(segment
		(start 166.82575 94.91219)
		(end 166.8921 94.97854)
		(width 0.2032)
		(layer "F.Cu")
		(net "ANT4_IN")
	)
	(segment
		(start 84.79449 135.83899)
		(end 84.82169 135.81179)
		(width 0.2032)
		(layer "F.Cu")
		(net "ANT4_IN")
	)
	(segment
		(start 166.6261 95.8662)
		(end 166.6261 95.81121)
		(width 0.2032)
		(layer "F.Cu")
		(net "ANT4_IN")
	)
	(segment
		(start 83.72831 135.83899)
		(end 84.79449 135.83899)
		(width 0.2032)
		(layer "F.Cu")
		(net "ANT4_IN")
	)
	(segment
		(start 166.82575 94.91219)
		(end 166.82575 93.86847)
		(width 0.2032)
		(layer "F.Cu")
		(net "ANT4_IN")
	)
	(via
		(at 84.82169 135.81179)
		(size 0.4064)
		(drill 0.2032)
		(layers "F.Cu" "B.Cu")
		(tenting
			(front yes)
			(back yes)
		)
		(net "ANT4_IN")
	)
	(via
		(at 166.6261 95.8662)
		(size 0.4064)
		(drill 0.2032)
		(layers "F.Cu" "B.Cu")
		(tenting
			(front yes)
			(back yes)
		)
		(net "ANT4_IN")
	)
	(segment
		(start 168.7063 97.9464)
		(end 168.7063 94.97943)
		(width 0.2032)
		(layer "In3.Cu")
		(net "ANT4_IN")
	)
	(segment
		(start 84.82169 135.81179)
		(end 86.5459 134.08758)
		(width 0.2032)
		(layer "In3.Cu")
		(net "ANT4_IN")
	)
	(segment
		(start 86.5459 134.08758)
		(end 86.5459 107.51245)
		(width 0.2032)
		(layer "In3.Cu")
		(net "ANT4_IN")
	)
	(segment
		(start 86.5459 107.51245)
		(end 90.40605 103.6523)
		(width 0.2032)
		(layer "In3.Cu")
		(net "ANT4_IN")
	)
	(segment
		(start 165.8761 95.39938)
		(end 166.03208 95.55536)
		(width 0.2032)
		(layer "In3.Cu")
		(net "ANT4_IN")
	)
	(segment
		(start 166.03208 95.55536)
		(end 166.03223 95.55536)
		(width 0.2032)
		(layer "In3.Cu")
		(net "ANT4_IN")
	)
	(segment
		(start 166.4563 94.286)
		(end 168.01287 94.286)
		(width 0.2032)
		(layer "In3.Cu")
		(net "ANT4_IN")
	)
	(segment
		(start 166.49091 103.6523)
		(end 169.70354 100.43967)
		(width 0.2032)
		(layer "In3.Cu")
		(net "ANT4_IN")
	)
	(segment
		(start 168.01287 94.286)
		(end 168.7063 94.97943)
		(width 0.2032)
		(layer "In3.Cu")
		(net "ANT4_IN")
	)
	(segment
		(start 169.70354 100.43967)
		(end 169.70354 98.94364)
		(width 0.2032)
		(layer "In3.Cu")
		(net "ANT4_IN")
	)
	(segment
		(start 166.03223 95.55536)
		(end 166.30419 95.82732)
		(width 0.2032)
		(layer "In3.Cu")
		(net "ANT4_IN")
	)
	(segment
		(start 165.8761 94.8662)
		(end 166.4563 94.286)
		(width 0.2032)
		(layer "In3.Cu")
		(net "ANT4_IN")
	)
	(segment
		(start 166.30419 95.82732)
		(end 166.58722 95.82732)
		(width 0.2032)
		(layer "In3.Cu")
		(net "ANT4_IN")
	)
	(segment
		(start 165.8761 95.39938)
		(end 165.8761 94.8662)
		(width 0.2032)
		(layer "In3.Cu")
		(net "ANT4_IN")
	)
	(segment
		(start 166.58722 95.82732)
		(end 166.6261 95.8662)
		(width 0.2032)
		(layer "In3.Cu")
		(net "ANT4_IN")
	)
	(segment
		(start 168.7063 97.9464)
		(end 169.70354 98.94364)
		(width 0.2032)
		(layer "In3.Cu")
		(net "ANT4_IN")
	)
	(segment
		(start 90.40605 103.6523)
		(end 166.49091 103.6523)
		(width 0.2032)
		(layer "In3.Cu")
		(net "ANT4_IN")
	)
	(segment
		(start 84.82111 122.7258)
		(end 84.8761 122.7258)
		(width 0.2032)
		(layer "F.Cu")
		(net "ANT3_OUT")
	)
	(segment
		(start 168.82575 97.91825)
		(end 168.8261 97.91861)
		(width 0.2032)
		(layer "F.Cu")
		(net "ANT3_OUT")
	)
	(segment
		(start 84.71151 122.6162)
		(end 84.82111 122.7258)
		(width 0.2032)
		(layer "F.Cu")
		(net "ANT3_OUT")
	)
	(segment
		(start 168.8261 99.24676)
		(end 169.19554 99.6162)
		(width 0.2032)
		(layer "F.Cu")
		(net "ANT3_OUT")
	)
	(segment
		(start 83.9511 122.6162)
		(end 84.71151 122.6162)
		(width 0.2032)
		(layer "F.Cu")
		(net "ANT3_OUT")
	)
	(segment
		(start 168.8261 99.24676)
		(end 168.8261 97.91861)
		(width 0.2032)
		(layer "F.Cu")
		(net "ANT3_OUT")
	)
	(via
		(at 169.19554 99.6162)
		(size 0.4064)
		(drill 0.2032)
		(layers "F.Cu" "B.Cu")
		(tenting
			(front yes)
			(back yes)
		)
		(net "ANT3_OUT")
	)
	(via
		(at 84.8761 122.7258)
		(size 0.4064)
		(drill 0.2032)
		(layers "F.Cu" "B.Cu")
		(tenting
			(front yes)
			(back yes)
		)
		(net "ANT3_OUT")
	)
	(segment
		(start 85.08652 122.6242)
		(end 86.2157 121.49502)
		(width 0.2032)
		(layer "In3.Cu")
		(net "ANT3_OUT")
	)
	(segment
		(start 85.03268 122.6242)
		(end 85.08652 122.6242)
		(width 0.2032)
		(layer "In3.Cu")
		(net "ANT3_OUT")
	)
	(segment
		(start 84.8761 122.7258)
		(end 84.93108 122.7258)
		(width 0.2032)
		(layer "In3.Cu")
		(net "ANT3_OUT")
	)
	(segment
		(start 84.93108 122.7258)
		(end 85.03268 122.6242)
		(width 0.2032)
		(layer "In3.Cu")
		(net "ANT3_OUT")
	)
	(segment
		(start 86.2157 121.49502)
		(end 86.2157 107.37568)
		(width 0.2032)
		(layer "In3.Cu")
		(net "ANT3_OUT")
	)
	(segment
		(start 166.35414 103.3221)
		(end 169.19554 100.4807)
		(width 0.2032)
		(layer "In3.Cu")
		(net "ANT3_OUT")
	)
	(segment
		(start 86.2157 107.37568)
		(end 90.26928 103.3221)
		(width 0.2032)
		(layer "In3.Cu")
		(net "ANT3_OUT")
	)
	(segment
		(start 90.26928 103.3221)
		(end 166.35414 103.3221)
		(width 0.2032)
		(layer "In3.Cu")
		(net "ANT3_OUT")
	)
	(segment
		(start 169.19554 100.4807)
		(end 169.19554 99.6162)
		(width 0.2032)
		(layer "In3.Cu")
		(net "ANT3_OUT")
	)
	(segment
		(start 83.1261 124.1162)
		(end 83.1261 123.3662)
		(width 0.2032)
		(layer "F.Cu")
		(net "ANT3_IO_OUT")
	)
	(segment
		(start 151.74069 114.31243)
		(end 153.11382 114.31243)
		(width 0.2032)
		(layer "F.Cu")
		(net "ANT3_IO_OUT")
	)
	(segment
		(start 83.3277 123.1646)
		(end 83.9027 123.1646)
		(width 0.2032)
		(layer "F.Cu")
		(net "ANT3_IO_OUT")
	)
	(segment
		(start 83.1261 123.3662)
		(end 83.3277 123.1646)
		(width 0.2032)
		(layer "F.Cu")
		(net "ANT3_IO_OUT")
	)
	(segment
		(start 84.3761 125.1162)
		(end 85.3761 125.1162)
		(width 0.2032)
		(layer "F.Cu")
		(net "ANT3_IO_OUT")
	)
	(segment
		(start 83.1261 124.1162)
		(end 84.1261 125.1162)
		(width 0.2032)
		(layer "F.Cu")
		(net "ANT3_IO_OUT")
	)
	(segment
		(start 154.9549 112.47134)
		(end 154.9549 111.8662)
		(width 0.2032)
		(layer "F.Cu")
		(net "ANT3_IO_OUT")
	)
	(segment
		(start 83.9027 123.1646)
		(end 83.9511 123.1162)
		(width 0.2032)
		(layer "F.Cu")
		(net "ANT3_IO_OUT")
	)
	(segment
		(start 153.11382 114.31243)
		(end 154.9549 112.47134)
		(width 0.2032)
		(layer "F.Cu")
		(net "ANT3_IO_OUT")
	)
	(via
		(at 85.3761 125.1162)
		(size 0.4064)
		(drill 0.2032)
		(layers "F.Cu" "B.Cu")
		(tenting
			(front yes)
			(back yes)
		)
		(net "ANT3_IO_OUT")
	)
	(via
		(at 154.9549 111.8662)
		(size 0.4064)
		(drill 0.2032)
		(layers "F.Cu" "B.Cu")
		(tenting
			(front yes)
			(back yes)
		)
		(net "ANT3_IO_OUT")
	)
	(segment
		(start 84.25372 132.17739)
		(end 84.6261 131.80501)
		(width 0.2032)
		(layer "In3.Cu")
		(net "ANT3_IO_OUT")
	)
	(segment
		(start 154.9549 111.8662)
		(end 154.9549 110.945)
		(width 0.2032)
		(layer "In3.Cu")
		(net "ANT3_IO_OUT")
	)
	(segment
		(start 91.3761 111.1162)
		(end 93.79193 108.70037)
		(width 0.2032)
		(layer "In3.Cu")
		(net "ANT3_IO_OUT")
	)
	(segment
		(start 91.3761 134.1162)
		(end 91.3761 111.1162)
		(width 0.2032)
		(layer "In3.Cu")
		(net "ANT3_IO_OUT")
	)
	(segment
		(start 84.6261 137.6162)
		(end 87.8761 137.6162)
		(width 0.2032)
		(layer "In3.Cu")
		(net "ANT3_IO_OUT")
	)
	(segment
		(start 84.6261 131.80501)
		(end 84.6261 125.8662)
		(width 0.2032)
		(layer "In3.Cu")
		(net "ANT3_IO_OUT")
	)
	(segment
		(start 152.71027 108.70037)
		(end 154.9549 110.945)
		(width 0.2032)
		(layer "In3.Cu")
		(net "ANT3_IO_OUT")
	)
	(segment
		(start 84.25372 137.24382)
		(end 84.25372 132.17739)
		(width 0.2032)
		(layer "In3.Cu")
		(net "ANT3_IO_OUT")
	)
	(segment
		(start 93.79193 108.70037)
		(end 152.71027 108.70037)
		(width 0.2032)
		(layer "In3.Cu")
		(net "ANT3_IO_OUT")
	)
	(segment
		(start 84.25372 137.24382)
		(end 84.6261 137.6162)
		(width 0.2032)
		(layer "In3.Cu")
		(net "ANT3_IO_OUT")
	)
	(segment
		(start 84.6261 125.8662)
		(end 85.3761 125.1162)
		(width 0.2032)
		(layer "In3.Cu")
		(net "ANT3_IO_OUT")
	)
	(segment
		(start 87.8761 137.6162)
		(end 91.3761 134.1162)
		(width 0.2032)
		(layer "In3.Cu")
		(net "ANT3_IO_OUT")
	)
	(segment
		(start 83.3761 127.6162)
		(end 83.3761 125.3662)
		(width 0.2032)
		(layer "F.Cu")
		(net "ANT3_IO_IN")
	)
	(segment
		(start 80.8011 122.6162)
		(end 82.1261 122.6162)
		(width 0.2032)
		(layer "F.Cu")
		(net "ANT3_IO_IN")
	)
	(segment
		(start 151.74069 113.8123)
		(end 153.14697 113.8123)
		(width 0.2032)
		(layer "F.Cu")
		(net "ANT3_IO_IN")
	)
	(segment
		(start 82.3761 125.1162)
		(end 82.3761 122.8662)
		(width 0.2032)
		(layer "F.Cu")
		(net "ANT3_IO_IN")
	)
	(segment
		(start 82.3761 125.1162)
		(end 83.1261 125.1162)
		(width 0.2032)
		(layer "F.Cu")
		(net "ANT3_IO_IN")
	)
	(segment
		(start 153.14697 113.8123)
		(end 154.3453 112.61397)
		(width 0.2032)
		(layer "F.Cu")
		(net "ANT3_IO_IN")
	)
	(segment
		(start 82.1261 122.6162)
		(end 82.3761 122.8662)
		(width 0.2032)
		(layer "F.Cu")
		(net "ANT3_IO_IN")
	)
	(segment
		(start 154.3453 112.61397)
		(end 154.3453 111.8662)
		(width 0.2032)
		(layer "F.Cu")
		(net "ANT3_IO_IN")
	)
	(segment
		(start 83.3761 127.6162)
		(end 83.8761 128.1162)
		(width 0.2032)
		(layer "F.Cu")
		(net "ANT3_IO_IN")
	)
	(segment
		(start 83.1261 125.1162)
		(end 83.3761 125.3662)
		(width 0.2032)
		(layer "F.Cu")
		(net "ANT3_IO_IN")
	)
	(via
		(at 154.3453 111.8662)
		(size 0.4064)
		(drill 0.2032)
		(layers "F.Cu" "B.Cu")
		(tenting
			(front yes)
			(back yes)
		)
		(net "ANT3_IO_IN")
	)
	(via
		(at 83.92352 128.16213)
		(size 0.4064)
		(drill 0.2032)
		(layers "F.Cu" "B.Cu")
		(tenting
			(front yes)
			(back yes)
		)
		(net "ANT3_IO_IN")
	)
	(segment
		(start 152.3761 109.1162)
		(end 154.3453 111.0854)
		(width 0.2032)
		(layer "In3.Cu")
		(net "ANT3_IO_IN")
	)
	(segment
		(start 83.92352 137.66361)
		(end 83.92352 128.16213)
		(width 0.2032)
		(layer "In3.Cu")
		(net "ANT3_IO_IN")
	)
	(segment
		(start 84.3761 138.1162)
		(end 88.6261 138.1162)
		(width 0.2032)
		(layer "In3.Cu")
		(net "ANT3_IO_IN")
	)
	(segment
		(start 154.3453 111.8662)
		(end 154.3453 111.0854)
		(width 0.2032)
		(layer "In3.Cu")
		(net "ANT3_IO_IN")
	)
	(segment
		(start 91.8761 134.8662)
		(end 91.8761 112.1162)
		(width 0.2032)
		(layer "In3.Cu")
		(net "ANT3_IO_IN")
	)
	(segment
		(start 91.71027 111.95037)
		(end 91.8761 112.1162)
		(width 0.2032)
		(layer "In3.Cu")
		(net "ANT3_IO_IN")
	)
	(segment
		(start 91.71027 111.95037)
		(end 91.71027 111.78203)
		(width 0.2032)
		(layer "In3.Cu")
		(net "ANT3_IO_IN")
	)
	(segment
		(start 83.92352 137.66361)
		(end 84.3761 138.1162)
		(width 0.2032)
		(layer "In3.Cu")
		(net "ANT3_IO_IN")
	)
	(segment
		(start 88.6261 138.1162)
		(end 91.8761 134.8662)
		(width 0.2032)
		(layer "In3.Cu")
		(net "ANT3_IO_IN")
	)
	(segment
		(start 91.71027 111.78203)
		(end 94.3761 109.1162)
		(width 0.2032)
		(layer "In3.Cu")
		(net "ANT3_IO_IN")
	)
	(segment
		(start 94.3761 109.1162)
		(end 152.3761 109.1162)
		(width 0.2032)
		(layer "In3.Cu")
		(net "ANT3_IO_IN")
	)
	(segment
		(start 83.9511 122.1162)
		(end 84.8761 122.1162)
		(width 0.2032)
		(layer "F.Cu")
		(net "ANT3_IN")
	)
	(segment
		(start 166.32588 95.07575)
		(end 166.32588 93.86847)
		(width 0.2032)
		(layer "F.Cu")
		(net "ANT3_IN")
	)
	(segment
		(start 166.32588 95.07575)
		(end 166.3841 95.13397)
		(width 0.2032)
		(layer "F.Cu")
		(net "ANT3_IN")
	)
	(segment
		(start 166.3841 95.18896)
		(end 166.3841 95.13397)
		(width 0.2032)
		(layer "F.Cu")
		(net "ANT3_IN")
	)
	(via
		(at 84.8761 122.1162)
		(size 0.4064)
		(drill 0.2032)
		(layers "F.Cu" "B.Cu")
		(tenting
			(front yes)
			(back yes)
		)
		(net "ANT3_IN")
	)
	(via
		(at 166.3841 95.18896)
		(size 0.4064)
		(drill 0.2032)
		(layers "F.Cu" "B.Cu")
		(tenting
			(front yes)
			(back yes)
		)
		(net "ANT3_IN")
	)
	(segment
		(start 167.8761 94.6162)
		(end 168.3761 95.1162)
		(width 0.2032)
		(layer "In3.Cu")
		(net "ANT3_IN")
	)
	(segment
		(start 166.3841 95.18896)
		(end 166.95686 94.6162)
		(width 0.2032)
		(layer "In3.Cu")
		(net "ANT3_IN")
	)
	(segment
		(start 84.8761 122.1162)
		(end 85.8855 121.1068)
		(width 0.2032)
		(layer "In3.Cu")
		(net "ANT3_IN")
	)
	(segment
		(start 166.21737 102.9919)
		(end 168.68754 100.52172)
		(width 0.2032)
		(layer "In3.Cu")
		(net "ANT3_IN")
	)
	(segment
		(start 168.3761 98.1162)
		(end 168.3761 95.1162)
		(width 0.2032)
		(layer "In3.Cu")
		(net "ANT3_IN")
	)
	(segment
		(start 166.95686 94.6162)
		(end 167.8761 94.6162)
		(width 0.2032)
		(layer "In3.Cu")
		(net "ANT3_IN")
	)
	(segment
		(start 85.8855 107.23891)
		(end 90.13251 102.9919)
		(width 0.2032)
		(layer "In3.Cu")
		(net "ANT3_IN")
	)
	(segment
		(start 90.13251 102.9919)
		(end 166.21737 102.9919)
		(width 0.2032)
		(layer "In3.Cu")
		(net "ANT3_IN")
	)
	(segment
		(start 168.3761 98.1162)
		(end 168.68754 98.42764)
		(width 0.2032)
		(layer "In3.Cu")
		(net "ANT3_IN")
	)
	(segment
		(start 85.8855 121.1068)
		(end 85.8855 107.23891)
		(width 0.2032)
		(layer "In3.Cu")
		(net "ANT3_IN")
	)
	(segment
		(start 168.68754 100.52172)
		(end 168.68754 98.42764)
		(width 0.2032)
		(layer "In3.Cu")
		(net "ANT3_IN")
	)
	(segment
		(start 166.6261 96.63884)
		(end 166.82575 96.8385)
		(width 0.2032)
		(layer "F.Cu")
		(net "ANT2_OUT")
	)
	(segment
		(start 166.82575 97.91825)
		(end 166.82575 96.8385)
		(width 0.2032)
		(layer "F.Cu")
		(net "ANT2_OUT")
	)
	(segment
		(start 166.6261 96.63884)
		(end 166.6261 96.6162)
		(width 0.2032)
		(layer "F.Cu")
		(net "ANT2_OUT")
	)
	(segment
		(start 84.8761 109.3662)
		(end 84.8761 109.3662)
		(width 0.2032)
		(layer "F.Cu")
		(net "ANT2_OUT")
	)
	(segment
		(start 83.9511 109.3662)
		(end 84.8761 109.3662)
		(width 0.2032)
		(layer "F.Cu")
		(net "ANT2_OUT")
	)
	(via
		(at 166.6261 96.6162)
		(size 0.4064)
		(drill 0.2032)
		(layers "F.Cu" "B.Cu")
		(tenting
			(front yes)
			(back yes)
		)
		(net "ANT2_OUT")
	)
	(via
		(at 84.8761 109.3662)
		(size 0.4064)
		(drill 0.2032)
		(layers "F.Cu" "B.Cu")
		(tenting
			(front yes)
			(back yes)
		)
		(net "ANT2_OUT")
	)
	(segment
		(start 139.1261 92.7162)
		(end 150.85724 92.7162)
		(width 0.2032)
		(layer "In3.Cu")
		(net "ANT2_OUT")
	)
	(segment
		(start 84.60491 109.14557)
		(end 84.60491 97.3192)
		(width 0.2032)
		(layer "In3.Cu")
		(net "ANT2_OUT")
	)
	(segment
		(start 84.60491 109.14557)
		(end 84.82554 109.3662)
		(width 0.2032)
		(layer "In3.Cu")
		(net "ANT2_OUT")
	)
	(segment
		(start 163.4037 95.88556)
		(end 165.89545 95.88556)
		(width 0.2032)
		(layer "In3.Cu")
		(net "ANT2_OUT")
	)
	(segment
		(start 110.58933 94.186)
		(end 137.6563 94.186)
		(width 0.2032)
		(layer "In3.Cu")
		(net "ANT2_OUT")
	)
	(segment
		(start 162.8042 96.48506)
		(end 163.4037 95.88556)
		(width 0.2032)
		(layer "In3.Cu")
		(net "ANT2_OUT")
	)
	(segment
		(start 154.6261 96.48506)
		(end 162.8042 96.48506)
		(width 0.2032)
		(layer "In3.Cu")
		(net "ANT2_OUT")
	)
	(segment
		(start 85.78821 96.1359)
		(end 108.63943 96.1359)
		(width 0.2032)
		(layer "In3.Cu")
		(net "ANT2_OUT")
	)
	(segment
		(start 108.63943 96.1359)
		(end 110.58933 94.186)
		(width 0.2032)
		(layer "In3.Cu")
		(net "ANT2_OUT")
	)
	(segment
		(start 137.6563 94.186)
		(end 139.1261 92.7162)
		(width 0.2032)
		(layer "In3.Cu")
		(net "ANT2_OUT")
	)
	(segment
		(start 84.60491 97.3192)
		(end 85.78821 96.1359)
		(width 0.2032)
		(layer "In3.Cu")
		(net "ANT2_OUT")
	)
	(segment
		(start 150.85724 92.7162)
		(end 154.6261 96.48506)
		(width 0.2032)
		(layer "In3.Cu")
		(net "ANT2_OUT")
	)
	(segment
		(start 84.82554 109.3662)
		(end 84.8761 109.3662)
		(width 0.2032)
		(layer "In3.Cu")
		(net "ANT2_OUT")
	)
	(segment
		(start 165.89545 95.88556)
		(end 166.6261 96.6162)
		(width 0.2032)
		(layer "In3.Cu")
		(net "ANT2_OUT")
	)
	(segment
		(start 153.7665 115.4758)
		(end 153.7665 114.8662)
		(width 0.2032)
		(layer "F.Cu")
		(net "ANT2_IO_OUT")
	)
	(segment
		(start 153.43 115.8123)
		(end 153.7665 115.4758)
		(width 0.2032)
		(layer "F.Cu")
		(net "ANT2_IO_OUT")
	)
	(segment
		(start 83.1261 110.6162)
		(end 83.8761 111.3662)
		(width 0.2032)
		(layer "F.Cu")
		(net "ANT2_IO_OUT")
	)
	(segment
		(start 151.74069 115.8123)
		(end 153.43 115.8123)
		(width 0.2032)
		(layer "F.Cu")
		(net "ANT2_IO_OUT")
	)
	(segment
		(start 84.1261 111.3662)
		(end 85.1261 111.3662)
		(width 0.2032)
		(layer "F.Cu")
		(net "ANT2_IO_OUT")
	)
	(segment
		(start 83.1261 110.6162)
		(end 83.1261 109.98523)
		(width 0.2032)
		(layer "F.Cu")
		(net "ANT2_IO_OUT")
	)
	(segment
		(start 83.1261 109.98523)
		(end 83.24513 109.8662)
		(width 0.2032)
		(layer "F.Cu")
		(net "ANT2_IO_OUT")
	)
	(segment
		(start 83.24513 109.8662)
		(end 83.9511 109.8662)
		(width 0.2032)
		(layer "F.Cu")
		(net "ANT2_IO_OUT")
	)
	(via
		(at 153.7665 114.8662)
		(size 0.4064)
		(drill 0.2032)
		(layers "F.Cu" "B.Cu")
		(tenting
			(front yes)
			(back yes)
		)
		(net "ANT2_IO_OUT")
	)
	(via
		(at 85.1261 111.3662)
		(size 0.4064)
		(drill 0.2032)
		(layers "F.Cu" "B.Cu")
		(tenting
			(front yes)
			(back yes)
		)
		(net "ANT2_IO_OUT")
	)
	(via
		(at 88.3761 110.1162)
		(size 0.4064)
		(drill 0.2032)
		(layers "F.Cu" "B.Cu")
		(tenting
			(front yes)
			(back yes)
		)
		(net "ANT2_IO_OUT")
	)
	(segment
		(start 86.3761 110.1162)
		(end 88.3761 110.1162)
		(width 0.2032)
		(layer "In2.Cu")
		(net "ANT2_IO_OUT")
	)
	(segment
		(start 85.1261 111.3662)
		(end 86.3761 110.1162)
		(width 0.2032)
		(layer "In2.Cu")
		(net "ANT2_IO_OUT")
	)
	(segment
		(start 151.93093 106.138)
		(end 156.1261 110.33317)
		(width 0.2032)
		(layer "In3.Cu")
		(net "ANT2_IO_OUT")
	)
	(segment
		(start 156.1261 114.90319)
		(end 156.1261 110.33317)
		(width 0.2032)
		(layer "In3.Cu")
		(net "ANT2_IO_OUT")
	)
	(segment
		(start 153.7665 114.92119)
		(end 153.8681 115.02279)
		(width 0.2032)
		(layer "In3.Cu")
		(net "ANT2_IO_OUT")
	)
	(segment
		(start 88.1261 109.8662)
		(end 88.3761 110.1162)
		(width 0.2032)
		(layer "In3.Cu")
		(net "ANT2_IO_OUT")
	)
	(segment
		(start 155.33289 115.6964)
		(end 156.1261 114.90319)
		(width 0.2032)
		(layer "In3.Cu")
		(net "ANT2_IO_OUT")
	)
	(segment
		(start 88.1261 109.8662)
		(end 88.1261 108.58317)
		(width 0.2032)
		(layer "In3.Cu")
		(net "ANT2_IO_OUT")
	)
	(segment
		(start 154.48788 115.6964)
		(end 155.33289 115.6964)
		(width 0.2032)
		(layer "In3.Cu")
		(net "ANT2_IO_OUT")
	)
	(segment
		(start 88.1261 108.58317)
		(end 90.57127 106.138)
		(width 0.2032)
		(layer "In3.Cu")
		(net "ANT2_IO_OUT")
	)
	(segment
		(start 153.8681 115.07662)
		(end 153.8681 115.02279)
		(width 0.2032)
		(layer "In3.Cu")
		(net "ANT2_IO_OUT")
	)
	(segment
		(start 90.57127 106.138)
		(end 151.93093 106.138)
		(width 0.2032)
		(layer "In3.Cu")
		(net "ANT2_IO_OUT")
	)
	(segment
		(start 153.8681 115.07662)
		(end 154.48788 115.6964)
		(width 0.2032)
		(layer "In3.Cu")
		(net "ANT2_IO_OUT")
	)
	(segment
		(start 153.7665 114.92119)
		(end 153.7665 114.8662)
		(width 0.2032)
		(layer "In3.Cu")
		(net "ANT2_IO_OUT")
	)
	(segment
		(start 83.1261 111.3662)
		(end 83.2511 111.4912)
		(width 0.2032)
		(layer "F.Cu")
		(net "ANT2_IO_IN")
	)
	(segment
		(start 81.8761 109.3662)
		(end 82.3761 109.8662)
		(width 0.2032)
		(layer "F.Cu")
		(net "ANT2_IO_IN")
	)
	(segment
		(start 151.74069 115.31242)
		(end 152.96819 115.31242)
		(width 0.2032)
		(layer "F.Cu")
		(net "ANT2_IO_IN")
	)
	(segment
		(start 152.96819 115.31242)
		(end 153.11802 115.16259)
		(width 0.2032)
		(layer "F.Cu")
		(net "ANT2_IO_IN")
	)
	(segment
		(start 80.8011 109.3662)
		(end 81.8761 109.3662)
		(width 0.2032)
		(layer "F.Cu")
		(net "ANT2_IO_IN")
	)
	(segment
		(start 83.6261 114.1162)
		(end 84.1261 114.1162)
		(width 0.2032)
		(layer "F.Cu")
		(net "ANT2_IO_IN")
	)
	(segment
		(start 82.3761 111.3662)
		(end 82.3761 109.8662)
		(width 0.2032)
		(layer "F.Cu")
		(net "ANT2_IO_IN")
	)
	(segment
		(start 82.3761 111.3662)
		(end 83.1261 111.3662)
		(width 0.2032)
		(layer "F.Cu")
		(net "ANT2_IO_IN")
	)
	(segment
		(start 80.8011 109.3662)
		(end 80.8011 109.3662)
		(width 0.2032)
		(layer "F.Cu")
		(net "ANT2_IO_IN")
	)
	(segment
		(start 153.11802 115.16259)
		(end 153.11802 114.90508)
		(width 0.2032)
		(layer "F.Cu")
		(net "ANT2_IO_IN")
	)
	(segment
		(start 83.2511 113.7412)
		(end 83.2511 111.4912)
		(width 0.2032)
		(layer "F.Cu")
		(net "ANT2_IO_IN")
	)
	(segment
		(start 83.2511 113.7412)
		(end 83.6261 114.1162)
		(width 0.2032)
		(layer "F.Cu")
		(net "ANT2_IO_IN")
	)
	(segment
		(start 153.11802 114.90508)
		(end 153.1569 114.8662)
		(width 0.2032)
		(layer "F.Cu")
		(net "ANT2_IO_IN")
	)
	(via
		(at 84.1261 114.1162)
		(size 0.4064)
		(drill 0.2032)
		(layers "F.Cu" "B.Cu")
		(tenting
			(front yes)
			(back yes)
		)
		(net "ANT2_IO_IN")
	)
	(via
		(at 87.7959 110.8662)
		(size 0.4064)
		(drill 0.2032)
		(layers "F.Cu" "B.Cu")
		(tenting
			(front yes)
			(back yes)
		)
		(net "ANT2_IO_IN")
	)
	(via
		(at 153.1569 114.8662)
		(size 0.4064)
		(drill 0.2032)
		(layers "F.Cu" "B.Cu")
		(tenting
			(front yes)
			(back yes)
		)
		(net "ANT2_IO_IN")
	)
	(segment
		(start 84.1261 114.1162)
		(end 84.1261 113.14778)
		(width 0.2032)
		(layer "In2.Cu")
		(net "ANT2_IO_IN")
	)
	(segment
		(start 84.1261 113.14778)
		(end 86.40768 110.8662)
		(width 0.2032)
		(layer "In2.Cu")
		(net "ANT2_IO_IN")
	)
	(segment
		(start 86.40768 110.8662)
		(end 87.7959 110.8662)
		(width 0.2032)
		(layer "In2.Cu")
		(net "ANT2_IO_IN")
	)
	(segment
		(start 156.4563 115.06903)
		(end 156.4563 110.1964)
		(width 0.2032)
		(layer "In3.Cu")
		(net "ANT2_IO_IN")
	)
	(segment
		(start 153.2585 115.07662)
		(end 154.20848 116.0266)
		(width 0.2032)
		(layer "In3.Cu")
		(net "ANT2_IO_IN")
	)
	(segment
		(start 153.1569 114.92119)
		(end 153.1569 114.8662)
		(width 0.2032)
		(layer "In3.Cu")
		(net "ANT2_IO_IN")
	)
	(segment
		(start 87.7959 110.8662)
		(end 87.7959 108.4464)
		(width 0.2032)
		(layer "In3.Cu")
		(net "ANT2_IO_IN")
	)
	(segment
		(start 87.7959 108.4464)
		(end 90.4345 105.8078)
		(width 0.2032)
		(layer "In3.Cu")
		(net "ANT2_IO_IN")
	)
	(segment
		(start 152.0677 105.8078)
		(end 156.4563 110.1964)
		(width 0.2032)
		(layer "In3.Cu")
		(net "ANT2_IO_IN")
	)
	(segment
		(start 155.49873 116.0266)
		(end 156.4563 115.06903)
		(width 0.2032)
		(layer "In3.Cu")
		(net "ANT2_IO_IN")
	)
	(segment
		(start 90.4345 105.8078)
		(end 152.0677 105.8078)
		(width 0.2032)
		(layer "In3.Cu")
		(net "ANT2_IO_IN")
	)
	(segment
		(start 153.2585 115.07662)
		(end 153.2585 115.02279)
		(width 0.2032)
		(layer "In3.Cu")
		(net "ANT2_IO_IN")
	)
	(segment
		(start 153.1569 114.92119)
		(end 153.2585 115.02279)
		(width 0.2032)
		(layer "In3.Cu")
		(net "ANT2_IO_IN")
	)
	(segment
		(start 154.20848 116.0266)
		(end 155.49873 116.0266)
		(width 0.2032)
		(layer "In3.Cu")
		(net "ANT2_IO_IN")
	)
	(segment
		(start 168.32587 99.28696)
		(end 168.32587 97.91825)
		(width 0.2032)
		(layer "F.Cu")
		(net "ANT2_IN")
	)
	(segment
		(start 85.07403 108.79548)
		(end 85.11291 108.7566)
		(width 0.2032)
		(layer "F.Cu")
		(net "ANT2_IN")
	)
	(segment
		(start 168.13973 99.4731)
		(end 168.32587 99.28696)
		(width 0.2032)
		(layer "F.Cu")
		(net "ANT2_IN")
	)
	(segment
		(start 84.75162 108.79548)
		(end 85.07403 108.79548)
		(width 0.2032)
		(layer "F.Cu")
		(net "ANT2_IN")
	)
	(segment
		(start 84.6809 108.8662)
		(end 84.75162 108.79548)
		(width 0.2032)
		(layer "F.Cu")
		(net "ANT2_IN")
	)
	(segment
		(start 83.9511 108.8662)
		(end 84.6809 108.8662)
		(width 0.2032)
		(layer "F.Cu")
		(net "ANT2_IN")
	)
	(segment
		(start 168.13973 99.52808)
		(end 168.13973 99.4731)
		(width 0.2032)
		(layer "F.Cu")
		(net "ANT2_IN")
	)
	(via
		(at 85.11291 108.7566)
		(size 0.4064)
		(drill 0.2032)
		(layers "F.Cu" "B.Cu")
		(tenting
			(front yes)
			(back yes)
		)
		(net "ANT2_IN")
	)
	(via
		(at 168.13973 99.52808)
		(size 0.4064)
		(drill 0.2032)
		(layers "F.Cu" "B.Cu")
		(tenting
			(front yes)
			(back yes)
		)
		(net "ANT2_IN")
	)
	(segment
		(start 85.11291 108.7566)
		(end 85.11291 107.54454)
		(width 0.2032)
		(layer "In3.Cu")
		(net "ANT2_IN")
	)
	(segment
		(start 166.2865 102.4558)
		(end 168.10085 100.64144)
		(width 0.2032)
		(layer "In3.Cu")
		(net "ANT2_IN")
	)
	(segment
		(start 168.10085 99.56696)
		(end 168.13973 99.52808)
		(width 0.2032)
		(layer "In3.Cu")
		(net "ANT2_IN")
	)
	(segment
		(start 90.20164 102.4558)
		(end 166.2865 102.4558)
		(width 0.2032)
		(layer "In3.Cu")
		(net "ANT2_IN")
	)
	(segment
		(start 168.10085 100.64144)
		(end 168.10085 99.56696)
		(width 0.2032)
		(layer "In3.Cu")
		(net "ANT2_IN")
	)
	(segment
		(start 85.11291 107.54454)
		(end 90.20164 102.4558)
		(width 0.2032)
		(layer "In3.Cu")
		(net "ANT2_IN")
	)
	(segment
		(start 84.6261 95.8662)
		(end 85.26658 96.50668)
		(width 0.2032)
		(layer "F.Cu")
		(net "ANT1_OUT")
	)
	(segment
		(start 165.8761 96.6162)
		(end 166.30251 97.04261)
		(width 0.2032)
		(layer "F.Cu")
		(net "ANT1_OUT")
	)
	(segment
		(start 83.7011 95.8662)
		(end 84.6261 95.8662)
		(width 0.2032)
		(layer "F.Cu")
		(net "ANT1_OUT")
	)
	(segment
		(start 166.30251 97.89488)
		(end 166.30251 97.04261)
		(width 0.2032)
		(layer "F.Cu")
		(net "ANT1_OUT")
	)
	(segment
		(start 166.30251 97.89488)
		(end 166.32588 97.91825)
		(width 0.2032)
		(layer "F.Cu")
		(net "ANT1_OUT")
	)
	(segment
		(start 85.26658 97.37595)
		(end 85.26658 96.50668)
		(width 0.2032)
		(layer "F.Cu")
		(net "ANT1_OUT")
	)
	(via
		(at 165.8761 96.6162)
		(size 0.4064)
		(drill 0.2032)
		(layers "F.Cu" "B.Cu")
		(tenting
			(front yes)
			(back yes)
		)
		(net "ANT1_OUT")
	)
	(via
		(at 85.26658 97.37595)
		(size 0.4064)
		(drill 0.2032)
		(layers "F.Cu" "B.Cu")
		(tenting
			(front yes)
			(back yes)
		)
		(net "ANT1_OUT")
	)
	(segment
		(start 138.1261 94.5162)
		(end 139.3261 93.3162)
		(width 0.2032)
		(layer "In3.Cu")
		(net "ANT1_OUT")
	)
	(segment
		(start 146.4261 97.1162)
		(end 165.3761 97.1162)
		(width 0.2032)
		(layer "In3.Cu")
		(net "ANT1_OUT")
	)
	(segment
		(start 139.3261 93.3162)
		(end 142.6261 93.3162)
		(width 0.2032)
		(layer "In3.Cu")
		(net "ANT1_OUT")
	)
	(segment
		(start 110.7261 94.5162)
		(end 138.1261 94.5162)
		(width 0.2032)
		(layer "In3.Cu")
		(net "ANT1_OUT")
	)
	(segment
		(start 85.26658 97.37595)
		(end 85.26658 97.32097)
		(width 0.2032)
		(layer "In3.Cu")
		(net "ANT1_OUT")
	)
	(segment
		(start 85.26658 97.32097)
		(end 85.36817 97.21937)
		(width 0.2032)
		(layer "In3.Cu")
		(net "ANT1_OUT")
	)
	(segment
		(start 108.6261 96.6162)
		(end 110.7261 94.5162)
		(width 0.2032)
		(layer "In3.Cu")
		(net "ANT1_OUT")
	)
	(segment
		(start 85.36817 97.21937)
		(end 85.36817 97.16378)
		(width 0.2032)
		(layer "In3.Cu")
		(net "ANT1_OUT")
	)
	(segment
		(start 85.91575 96.6162)
		(end 108.6261 96.6162)
		(width 0.2032)
		(layer "In3.Cu")
		(net "ANT1_OUT")
	)
	(segment
		(start 85.36817 97.16378)
		(end 85.91575 96.6162)
		(width 0.2032)
		(layer "In3.Cu")
		(net "ANT1_OUT")
	)
	(segment
		(start 142.6261 93.3162)
		(end 146.4261 97.1162)
		(width 0.2032)
		(layer "In3.Cu")
		(net "ANT1_OUT")
	)
	(segment
		(start 165.3761 97.1162)
		(end 165.8761 96.6162)
		(width 0.2032)
		(layer "In3.Cu")
		(net "ANT1_OUT")
	)
	(segment
		(start 151.74069 116.81229)
		(end 153.39842 116.81229)
		(width 0.2032)
		(layer "F.Cu")
		(net "ANT1_IO_OUT")
	)
	(segment
		(start 82.8761 97.3662)
		(end 82.8761 96.6162)
		(width 0.2032)
		(layer "F.Cu")
		(net "ANT1_IO_OUT")
	)
	(segment
		(start 85.1261 98.1162)
		(end 85.1261 98.1162)
		(width 0.2032)
		(layer "F.Cu")
		(net "ANT1_IO_OUT")
	)
	(segment
		(start 82.8761 96.6162)
		(end 83.11377 96.37853)
		(width 0.2032)
		(layer "F.Cu")
		(net "ANT1_IO_OUT")
	)
	(segment
		(start 83.11377 96.37853)
		(end 83.68877 96.37853)
		(width 0.2032)
		(layer "F.Cu")
		(net "ANT1_IO_OUT")
	)
	(segment
		(start 83.3761 97.8662)
		(end 84.1261 97.8662)
		(width 0.2032)
		(layer "F.Cu")
		(net "ANT1_IO_OUT")
	)
	(segment
		(start 83.68877 96.37853)
		(end 83.7011 96.3662)
		(width 0.2032)
		(layer "F.Cu")
		(net "ANT1_IO_OUT")
	)
	(segment
		(start 153.39842 116.81229)
		(end 154.94682 115.2639)
		(width 0.2032)
		(layer "F.Cu")
		(net "ANT1_IO_OUT")
	)
	(segment
		(start 154.94682 114.89708)
		(end 154.9857 114.8582)
		(width 0.2032)
		(layer "F.Cu")
		(net "ANT1_IO_OUT")
	)
	(segment
		(start 154.94682 115.2639)
		(end 154.94682 114.89708)
		(width 0.2032)
		(layer "F.Cu")
		(net "ANT1_IO_OUT")
	)
	(segment
		(start 82.8761 97.3662)
		(end 83.3761 97.8662)
		(width 0.2032)
		(layer "F.Cu")
		(net "ANT1_IO_OUT")
	)
	(segment
		(start 84.1261 98.1162)
		(end 85.1261 98.1162)
		(width 0.2032)
		(layer "F.Cu")
		(net "ANT1_IO_OUT")
	)
	(via
		(at 85.11291 98.10747)
		(size 0.4064)
		(drill 0.2032)
		(layers "F.Cu" "B.Cu")
		(tenting
			(front yes)
			(back yes)
		)
		(net "ANT1_IO_OUT")
	)
	(via
		(at 89.1681 108.8582)
		(size 0.4064)
		(drill 0.2032)
		(layers "F.Cu" "B.Cu")
		(tenting
			(front yes)
			(back yes)
		)
		(net "ANT1_IO_OUT")
	)
	(via
		(at 154.9857 114.8582)
		(size 0.4064)
		(drill 0.2032)
		(layers "F.Cu" "B.Cu")
		(tenting
			(front yes)
			(back yes)
		)
		(net "ANT1_IO_OUT")
	)
	(segment
		(start 85.11291 98.10747)
		(end 89.1341 102.12866)
		(width 0.2032)
		(layer "In2.Cu")
		(net "ANT1_IO_OUT")
	)
	(segment
		(start 89.1341 108.8242)
		(end 89.1341 102.12866)
		(width 0.2032)
		(layer "In2.Cu")
		(net "ANT1_IO_OUT")
	)
	(segment
		(start 89.1341 108.8242)
		(end 89.1681 108.8582)
		(width 0.2032)
		(layer "In2.Cu")
		(net "ANT1_IO_OUT")
	)
	(segment
		(start 151.65739 106.7984)
		(end 155.4629 110.60391)
		(width 0.2032)
		(layer "In3.Cu")
		(net "ANT1_IO_OUT")
	)
	(segment
		(start 90.9439 106.7984)
		(end 151.65739 106.7984)
		(width 0.2032)
		(layer "In3.Cu")
		(net "ANT1_IO_OUT")
	)
	(segment
		(start 154.9937 114.8582)
		(end 155.4629 114.389)
		(width 0.2032)
		(layer "In3.Cu")
		(net "ANT1_IO_OUT")
	)
	(segment
		(start 89.16511 108.57719)
		(end 90.9439 106.7984)
		(width 0.2032)
		(layer "In3.Cu")
		(net "ANT1_IO_OUT")
	)
	(segment
		(start 89.16511 108.85521)
		(end 89.16511 108.57719)
		(width 0.2032)
		(layer "In3.Cu")
		(net "ANT1_IO_OUT")
	)
	(segment
		(start 89.16511 108.85521)
		(end 89.1681 108.8582)
		(width 0.2032)
		(layer "In3.Cu")
		(net "ANT1_IO_OUT")
	)
	(segment
		(start 154.9857 114.8582)
		(end 154.9937 114.8582)
		(width 0.2032)
		(layer "In3.Cu")
		(net "ANT1_IO_OUT")
	)
	(segment
		(start 155.4629 114.389)
		(end 155.4629 110.60391)
		(width 0.2032)
		(layer "In3.Cu")
		(net "ANT1_IO_OUT")
	)
	(segment
		(start 151.74069 116.31242)
		(end 153.39685 116.31242)
		(width 0.2032)
		(layer "F.Cu")
		(net "ANT1_IO_IN")
	)
	(segment
		(start 83.1261 100.3662)
		(end 83.1261 98.3662)
		(width 0.2032)
		(layer "F.Cu")
		(net "ANT1_IO_IN")
	)
	(segment
		(start 83.1261 100.3662)
		(end 83.6261 100.8662)
		(width 0.2032)
		(layer "F.Cu")
		(net "ANT1_IO_IN")
	)
	(segment
		(start 153.39685 116.31242)
		(end 154.33722 115.37205)
		(width 0.2032)
		(layer "F.Cu")
		(net "ANT1_IO_IN")
	)
	(segment
		(start 154.33722 115.37205)
		(end 154.33722 114.90508)
		(width 0.2032)
		(layer "F.Cu")
		(net "ANT1_IO_IN")
	)
	(segment
		(start 82.1261 98.1662)
		(end 82.1761 98.1162)
		(width 0.2032)
		(layer "F.Cu")
		(net "ANT1_IO_IN")
	)
	(segment
		(start 154.33722 114.90508)
		(end 154.3761 114.8662)
		(width 0.2032)
		(layer "F.Cu")
		(net "ANT1_IO_IN")
	)
	(segment
		(start 82.1261 98.1162)
		(end 82.8761 98.1162)
		(width 0.2032)
		(layer "F.Cu")
		(net "ANT1_IO_IN")
	)
	(segment
		(start 80.5511 95.8662)
		(end 81.6261 95.8662)
		(width 0.2032)
		(layer "F.Cu")
		(net "ANT1_IO_IN")
	)
	(segment
		(start 82.1261 98.1162)
		(end 82.1261 96.3662)
		(width 0.2032)
		(layer "F.Cu")
		(net "ANT1_IO_IN")
	)
	(segment
		(start 82.8761 98.1162)
		(end 83.1261 98.3662)
		(width 0.2032)
		(layer "F.Cu")
		(net "ANT1_IO_IN")
	)
	(segment
		(start 81.6261 95.8662)
		(end 82.1261 96.3662)
		(width 0.2032)
		(layer "F.Cu")
		(net "ANT1_IO_IN")
	)
	(segment
		(start 82.1261 98.4162)
		(end 82.1261 98.4146)
		(width 0.2032)
		(layer "F.Cu")
		(net "ANT1_IO_IN")
	)
	(via
		(at 88.8761 109.6162)
		(size 0.4064)
		(drill 0.2032)
		(layers "F.Cu" "B.Cu")
		(tenting
			(front yes)
			(back yes)
		)
		(net "ANT1_IO_IN")
	)
	(via
		(at 154.3761 114.8662)
		(size 0.4064)
		(drill 0.2032)
		(layers "F.Cu" "B.Cu")
		(tenting
			(front yes)
			(back yes)
		)
		(net "ANT1_IO_IN")
	)
	(via
		(at 83.6261 100.8662)
		(size 0.4064)
		(drill 0.2032)
		(layers "F.Cu" "B.Cu")
		(tenting
			(front yes)
			(back yes)
		)
		(net "ANT1_IO_IN")
	)
	(segment
		(start 86.1261 100.8662)
		(end 87.3761 102.1162)
		(width 0.2032)
		(layer "In2.Cu")
		(net "ANT1_IO_IN")
	)
	(segment
		(start 87.3761 108.1162)
		(end 88.8761 109.6162)
		(width 0.2032)
		(layer "In2.Cu")
		(net "ANT1_IO_IN")
	)
	(segment
		(start 83.6261 100.8662)
		(end 86.1261 100.8662)
		(width 0.2032)
		(layer "In2.Cu")
		(net "ANT1_IO_IN")
	)
	(segment
		(start 87.3761 108.1162)
		(end 87.3761 102.1162)
		(width 0.2032)
		(layer "In2.Cu")
		(net "ANT1_IO_IN")
	)
	(segment
		(start 154.4777 115.06862)
		(end 154.4777 115.02279)
		(width 0.2032)
		(layer "In3.Cu")
		(net "ANT1_IO_IN")
	)
	(segment
		(start 151.79416 106.4682)
		(end 155.7959 110.46994)
		(width 0.2032)
		(layer "In3.Cu")
		(net "ANT1_IO_IN")
	)
	(segment
		(start 90.70804 106.4682)
		(end 151.79416 106.4682)
		(width 0.2032)
		(layer "In3.Cu")
		(net "ANT1_IO_IN")
	)
	(segment
		(start 88.6261 109.31121)
		(end 88.6261 108.55014)
		(width 0.2032)
		(layer "In3.Cu")
		(net "ANT1_IO_IN")
	)
	(segment
		(start 154.77528 115.3662)
		(end 155.19612 115.3662)
		(width 0.2032)
		(layer "In3.Cu")
		(net "ANT1_IO_IN")
	)
	(segment
		(start 154.3761 114.92119)
		(end 154.4777 115.02279)
		(width 0.2032)
		(layer "In3.Cu")
		(net "ANT1_IO_IN")
	)
	(segment
		(start 88.8761 109.6162)
		(end 88.8761 109.56121)
		(width 0.2032)
		(layer "In3.Cu")
		(net "ANT1_IO_IN")
	)
	(segment
		(start 155.19612 115.3662)
		(end 155.7959 114.76642)
		(width 0.2032)
		(layer "In3.Cu")
		(net "ANT1_IO_IN")
	)
	(segment
		(start 154.4777 115.06862)
		(end 154.77528 115.3662)
		(width 0.2032)
		(layer "In3.Cu")
		(net "ANT1_IO_IN")
	)
	(segment
		(start 154.3761 114.92119)
		(end 154.3761 114.8662)
		(width 0.2032)
		(layer "In3.Cu")
		(net "ANT1_IO_IN")
	)
	(segment
		(start 88.6261 109.31121)
		(end 88.8761 109.56121)
		(width 0.2032)
		(layer "In3.Cu")
		(net "ANT1_IO_IN")
	)
	(segment
		(start 88.6261 108.55014)
		(end 90.70804 106.4682)
		(width 0.2032)
		(layer "In3.Cu")
		(net "ANT1_IO_IN")
	)
	(segment
		(start 155.7959 114.76642)
		(end 155.7959 110.46994)
		(width 0.2032)
		(layer "In3.Cu")
		(net "ANT1_IO_IN")
	)
	(segment
		(start 85.87617 97.3742)
		(end 85.87617 96.11627)
		(width 0.2032)
		(layer "F.Cu")
		(net "ANT1_IN")
	)
	(segment
		(start 83.7011 95.3662)
		(end 85.1261 95.3662)
		(width 0.2032)
		(layer "F.Cu")
		(net "ANT1_IN")
	)
	(segment
		(start 167.53095 99.55961)
		(end 167.56983 99.52073)
		(width 0.2032)
		(layer "F.Cu")
		(net "ANT1_IN")
	)
	(segment
		(start 85.1261 95.3662)
		(end 85.87617 96.11627)
		(width 0.2032)
		(layer "F.Cu")
		(net "ANT1_IN")
	)
	(segment
		(start 167.82575 99.00659)
		(end 167.82575 97.91825)
		(width 0.2032)
		(layer "F.Cu")
		(net "ANT1_IN")
	)
	(segment
		(start 167.56983 99.26251)
		(end 167.82575 99.00659)
		(width 0.2032)
		(layer "F.Cu")
		(net "ANT1_IN")
	)
	(segment
		(start 167.56983 99.52073)
		(end 167.56983 99.26251)
		(width 0.2032)
		(layer "F.Cu")
		(net "ANT1_IN")
	)
	(via
		(at 85.87617 97.3742)
		(size 0.4064)
		(drill 0.2032)
		(layers "F.Cu" "B.Cu")
		(tenting
			(front yes)
			(back yes)
		)
		(net "ANT1_IN")
	)
	(via
		(at 167.53095 99.55961)
		(size 0.4064)
		(drill 0.2032)
		(layers "F.Cu" "B.Cu")
		(tenting
			(front yes)
			(back yes)
		)
		(net "ANT1_IN")
	)
	(segment
		(start 89.46357 100.9616)
		(end 166.15035 100.9616)
		(width 0.2032)
		(layer "In3.Cu")
		(net "ANT1_IN")
	)
	(segment
		(start 167.53095 99.581)
		(end 167.53095 99.55961)
		(width 0.2032)
		(layer "In3.Cu")
		(net "ANT1_IN")
	)
	(segment
		(start 85.87617 97.3742)
		(end 89.46357 100.9616)
		(width 0.2032)
		(layer "In3.Cu")
		(net "ANT1_IN")
	)
	(segment
		(start 166.15035 100.9616)
		(end 167.53095 99.581)
		(width 0.2032)
		(layer "In3.Cu")
		(net "ANT1_IN")
	)
	(segment
		(start 73.3761 54.9412)
		(end 73.3761 52.8662)
		(width 0.2032)
		(layer "F.Cu")
		(net "NetD10_1")
	)
	(segment
		(start 71.6261 54.9412)
		(end 71.6261 52.8662)
		(width 0.2032)
		(layer "F.Cu")
		(net "NetD9_1")
	)
	(segment
		(start 151.74878 124.3205)
		(end 154.618 124.3205)
		(width 0.2032)
		(layer "F.Cu")
		(net "GPS2_TX")
	)
	(segment
		(start 228.0711 60.6786)
		(end 230.3761 60.6786)
		(width 0.2032)
		(layer "F.Cu")
		(net "GPS2_TX")
	)
	(segment
		(start 151.74069 124.31241)
		(end 151.74878 124.3205)
		(width 0.2032)
		(layer "F.Cu")
		(net "GPS2_TX")
	)
	(segment
		(start 154.618 124.3205)
		(end 154.6261 124.3286)
		(width 0.2032)
		(layer "F.Cu")
		(net "GPS2_TX")
	)
	(via
		(at 230.3761 60.6786)
		(size 0.4064)
		(drill 0.2032)
		(layers "F.Cu" "B.Cu")
		(tenting
			(front yes)
			(back yes)
		)
		(net "GPS2_TX")
	)
	(via
		(at 154.6261 124.3286)
		(size 0.4064)
		(drill 0.2032)
		(layers "F.Cu" "B.Cu")
		(tenting
			(front yes)
			(back yes)
		)
		(net "GPS2_TX")
	)
	(segment
		(start 230.3761 60.6786)
		(end 231.6261 61.9286)
		(width 0.2032)
		(layer "In2.Cu")
		(net "GPS2_TX")
	)
	(segment
		(start 229.1261 68.0786)
		(end 231.6261 65.5786)
		(width 0.2032)
		(layer "In2.Cu")
		(net "GPS2_TX")
	)
	(segment
		(start 168.5459 111.1588)
		(end 177.7959 111.1588)
		(width 0.2032)
		(layer "In2.Cu")
		(net "GPS2_TX")
	)
	(segment
		(start 177.7959 111.1588)
		(end 220.8761 68.0786)
		(width 0.2032)
		(layer "In2.Cu")
		(net "GPS2_TX")
	)
	(segment
		(start 231.6261 65.5786)
		(end 231.6261 61.9286)
		(width 0.2032)
		(layer "In2.Cu")
		(net "GPS2_TX")
	)
	(segment
		(start 220.8761 68.0786)
		(end 229.1261 68.0786)
		(width 0.2032)
		(layer "In2.Cu")
		(net "GPS2_TX")
	)
	(segment
		(start 154.6261 124.3286)
		(end 155.3761 124.3286)
		(width 0.2032)
		(layer "In2.Cu")
		(net "GPS2_TX")
	)
	(segment
		(start 155.3761 124.3286)
		(end 168.5459 111.1588)
		(width 0.2032)
		(layer "In2.Cu")
		(net "GPS2_TX")
	)
	(segment
		(start 153.89242 122.81228)
		(end 154.0165 122.6882)
		(width 0.2032)
		(layer "F.Cu")
		(net "GPS2_TP2")
	)
	(segment
		(start 154.0165 122.6882)
		(end 154.18483 122.6882)
		(width 0.2032)
		(layer "F.Cu")
		(net "GPS2_TP2")
	)
	(segment
		(start 151.74069 122.81228)
		(end 153.89242 122.81228)
		(width 0.2032)
		(layer "F.Cu")
		(net "GPS2_TP2")
	)
	(segment
		(start 154.18514 122.68851)
		(end 154.58722 122.68851)
		(width 0.2032)
		(layer "F.Cu")
		(net "GPS2_TP2")
	)
	(segment
		(start 154.18483 122.6882)
		(end 154.18514 122.68851)
		(width 0.2032)
		(layer "F.Cu")
		(net "GPS2_TP2")
	)
	(segment
		(start 154.58722 122.68851)
		(end 154.6261 122.72739)
		(width 0.2032)
		(layer "F.Cu")
		(net "GPS2_TP2")
	)
	(segment
		(start 228.0711 64.6786)
		(end 230.3761 64.6786)
		(width 0.2032)
		(layer "F.Cu")
		(net "GPS2_TP2")
	)
	(via
		(at 230.3761 64.6786)
		(size 0.4064)
		(drill 0.2032)
		(layers "F.Cu" "B.Cu")
		(tenting
			(front yes)
			(back yes)
		)
		(net "GPS2_TP2")
	)
	(via
		(at 154.6261 122.72739)
		(size 0.4064)
		(drill 0.2032)
		(layers "F.Cu" "B.Cu")
		(tenting
			(front yes)
			(back yes)
		)
		(net "GPS2_TP2")
	)
	(segment
		(start 155.97731 122.72739)
		(end 168.3761 110.3286)
		(width 0.2032)
		(layer "In2.Cu")
		(net "GPS2_TP2")
	)
	(segment
		(start 154.6261 122.72739)
		(end 155.97731 122.72739)
		(width 0.2032)
		(layer "In2.Cu")
		(net "GPS2_TP2")
	)
	(segment
		(start 177.69216 110.3286)
		(end 223.34216 64.6786)
		(width 0.2032)
		(layer "In2.Cu")
		(net "GPS2_TP2")
	)
	(segment
		(start 223.34216 64.6786)
		(end 230.3761 64.6786)
		(width 0.2032)
		(layer "In2.Cu")
		(net "GPS2_TP2")
	)
	(segment
		(start 168.3761 110.3286)
		(end 177.69216 110.3286)
		(width 0.2032)
		(layer "In2.Cu")
		(net "GPS2_TP2")
	)
	(segment
		(start 154.60961 123.3205)
		(end 154.6261 123.33699)
		(width 0.2032)
		(layer "F.Cu")
		(net "GPS2_TP1")
	)
	(segment
		(start 151.74069 123.31241)
		(end 151.74878 123.3205)
		(width 0.2032)
		(layer "F.Cu")
		(net "GPS2_TP1")
	)
	(segment
		(start 221.8761 62.6786)
		(end 223.6261 62.6786)
		(width 0.2032)
		(layer "F.Cu")
		(net "GPS2_TP1")
	)
	(segment
		(start 151.74878 123.3205)
		(end 154.60961 123.3205)
		(width 0.2032)
		(layer "F.Cu")
		(net "GPS2_TP1")
	)
	(via
		(at 221.8761 62.6786)
		(size 0.4064)
		(drill 0.2032)
		(layers "F.Cu" "B.Cu")
		(tenting
			(front yes)
			(back yes)
		)
		(net "GPS2_TP1")
	)
	(via
		(at 154.6261 123.33699)
		(size 0.4064)
		(drill 0.2032)
		(layers "F.Cu" "B.Cu")
		(tenting
			(front yes)
			(back yes)
		)
		(net "GPS2_TP1")
	)
	(via
		(at 221.8761 67.3286)
		(size 0.4064)
		(drill 0.2032)
		(layers "F.Cu" "B.Cu")
		(tenting
			(front yes)
			(back yes)
		)
		(net "GPS2_TP1")
	)
	(segment
		(start 168.34307 110.8286)
		(end 177.65913 110.8286)
		(width 0.2032)
		(layer "In2.Cu")
		(net "GPS2_TP1")
	)
	(segment
		(start 154.6261 123.33699)
		(end 155.83468 123.33699)
		(width 0.2032)
		(layer "In2.Cu")
		(net "GPS2_TP1")
	)
	(segment
		(start 155.83468 123.33699)
		(end 168.34307 110.8286)
		(width 0.2032)
		(layer "In2.Cu")
		(net "GPS2_TP1")
	)
	(segment
		(start 177.65913 110.8286)
		(end 221.15913 67.3286)
		(width 0.2032)
		(layer "In2.Cu")
		(net "GPS2_TP1")
	)
	(segment
		(start 221.15913 67.3286)
		(end 221.8761 67.3286)
		(width 0.2032)
		(layer "In2.Cu")
		(net "GPS2_TP1")
	)
	(segment
		(start 221.8761 67.3286)
		(end 221.8761 62.6786)
		(width 0.2032)
		(layer "In3.Cu")
		(net "GPS2_TP1")
	)
	(segment
		(start 144.6261 124.3286)
		(end 144.6342 124.3205)
		(width 0.2032)
		(layer "F.Cu")
		(net "GPS2_RX")
	)
	(segment
		(start 144.6342 124.3205)
		(end 147.68282 124.3205)
		(width 0.2032)
		(layer "F.Cu")
		(net "GPS2_RX")
	)
	(segment
		(start 147.68282 124.3205)
		(end 147.69091 124.31241)
		(width 0.2032)
		(layer "F.Cu")
		(net "GPS2_RX")
	)
	(segment
		(start 228.0711 62.6786)
		(end 230.3761 62.6786)
		(width 0.2032)
		(layer "F.Cu")
		(net "GPS2_RX")
	)
	(via
		(at 144.6261 124.3286)
		(size 0.4064)
		(drill 0.2032)
		(layers "F.Cu" "B.Cu")
		(tenting
			(front yes)
			(back yes)
		)
		(net "GPS2_RX")
	)
	(via
		(at 230.3761 62.6786)
		(size 0.4064)
		(drill 0.2032)
		(layers "F.Cu" "B.Cu")
		(tenting
			(front yes)
			(back yes)
		)
		(net "GPS2_RX")
	)
	(segment
		(start 168.2959 109.9088)
		(end 177.64499 109.9088)
		(width 0.2032)
		(layer "In2.Cu")
		(net "GPS2_RX")
	)
	(segment
		(start 220.6261 62.8286)
		(end 221.6261 61.8286)
		(width 0.2032)
		(layer "In2.Cu")
		(net "GPS2_RX")
	)
	(segment
		(start 221.6261 61.8286)
		(end 229.5261 61.8286)
		(width 0.2032)
		(layer "In2.Cu")
		(net "GPS2_RX")
	)
	(segment
		(start 220.6261 66.92768)
		(end 220.6261 62.8286)
		(width 0.2032)
		(layer "In2.Cu")
		(net "GPS2_RX")
	)
	(segment
		(start 148.91612 124.3286)
		(end 151.02533 122.21939)
		(width 0.2032)
		(layer "In2.Cu")
		(net "GPS2_RX")
	)
	(segment
		(start 144.6261 124.3286)
		(end 148.91612 124.3286)
		(width 0.2032)
		(layer "In2.Cu")
		(net "GPS2_RX")
	)
	(segment
		(start 155.98531 122.21939)
		(end 168.2959 109.9088)
		(width 0.2032)
		(layer "In2.Cu")
		(net "GPS2_RX")
	)
	(segment
		(start 177.64499 109.9088)
		(end 220.6261 66.92768)
		(width 0.2032)
		(layer "In2.Cu")
		(net "GPS2_RX")
	)
	(segment
		(start 229.5261 61.8286)
		(end 230.3761 62.6786)
		(width 0.2032)
		(layer "In2.Cu")
		(net "GPS2_RX")
	)
	(segment
		(start 151.02533 122.21939)
		(end 155.98531 122.21939)
		(width 0.2032)
		(layer "In2.Cu")
		(net "GPS2_RX")
	)
	(segment
		(start 154.47022 121.81228)
		(end 154.57112 121.71139)
		(width 0.2032)
		(layer "F.Cu")
		(net "GPS2_RST")
	)
	(segment
		(start 154.57112 121.71139)
		(end 154.6261 121.71139)
		(width 0.2032)
		(layer "F.Cu")
		(net "GPS2_RST")
	)
	(segment
		(start 221.8761 60.6786)
		(end 223.6261 60.6786)
		(width 0.2032)
		(layer "F.Cu")
		(net "GPS2_RST")
	)
	(segment
		(start 151.74069 121.81228)
		(end 154.47022 121.81228)
		(width 0.2032)
		(layer "F.Cu")
		(net "GPS2_RST")
	)
	(via
		(at 221.8761 60.6786)
		(size 0.4064)
		(drill 0.2032)
		(layers "F.Cu" "B.Cu")
		(tenting
			(front yes)
			(back yes)
		)
		(net "GPS2_RST")
	)
	(via
		(at 154.6261 121.71139)
		(size 0.4064)
		(drill 0.2032)
		(layers "F.Cu" "B.Cu")
		(tenting
			(front yes)
			(back yes)
		)
		(net "GPS2_RST")
	)
	(segment
		(start 220.1261 62.4286)
		(end 221.8761 60.6786)
		(width 0.2032)
		(layer "In2.Cu")
		(net "GPS2_RST")
	)
	(segment
		(start 168.1261 109.5786)
		(end 177.50821 109.5786)
		(width 0.2032)
		(layer "In2.Cu")
		(net "GPS2_RST")
	)
	(segment
		(start 155.99331 121.71139)
		(end 168.1261 109.5786)
		(width 0.2032)
		(layer "In2.Cu")
		(net "GPS2_RST")
	)
	(segment
		(start 220.1261 66.96071)
		(end 220.1261 62.4286)
		(width 0.2032)
		(layer "In2.Cu")
		(net "GPS2_RST")
	)
	(segment
		(start 177.50821 109.5786)
		(end 220.1261 66.96071)
		(width 0.2032)
		(layer "In2.Cu")
		(net "GPS2_RST")
	)
	(segment
		(start 154.6261 121.71139)
		(end 155.99331 121.71139)
		(width 0.2032)
		(layer "In2.Cu")
		(net "GPS2_RST")
	)
	(segment
		(start 78.3261 95.1162)
		(end 78.4261 95.2162)
		(width 0.2032)
		(layer "F.Cu")
		(net "NetR25_1")
	)
	(segment
		(start 79.6261 95.1162)
		(end 79.8761 94.8662)
		(width 0.2032)
		(layer "F.Cu")
		(net "NetR25_1")
	)
	(segment
		(start 78.3261 95.1162)
		(end 79.6261 95.1162)
		(width 0.2032)
		(layer "F.Cu")
		(net "NetR25_1")
	)
	(segment
		(start 79.8761 94.8662)
		(end 80.5511 94.8662)
		(width 0.2032)
		(layer "F.Cu")
		(net "NetR25_1")
	)
	(segment
		(start 79.8761 95.3662)
		(end 80.5511 95.3662)
		(width 0.2032)
		(layer "F.Cu")
		(net "NetR25_1")
	)
	(segment
		(start 79.6261 95.1162)
		(end 79.8761 95.3662)
		(width 0.2032)
		(layer "F.Cu")
		(net "NetR25_1")
	)
	(segment
		(start 122.3761 85.5786)
		(end 123.3261 85.5786)
		(width 0.2032)
		(layer "F.Cu")
		(net "NetR13_1")
	)
	(segment
		(start 122.2411 85.4436)
		(end 122.3761 85.5786)
		(width 0.2032)
		(layer "F.Cu")
		(net "NetR13_1")
	)
	(segment
		(start 120.9761 85.4436)
		(end 122.2411 85.4436)
		(width 0.2032)
		(layer "F.Cu")
		(net "NetR13_1")
	)
	(segment
		(start 123.3261 85.5786)
		(end 123.3761 85.6286)
		(width 0.2032)
		(layer "F.Cu")
		(net "NetR13_1")
	)
	(segment
		(start 141.6161 84.0686)
		(end 141.6261 84.0786)
		(width 0.2032)
		(layer "F.Cu")
		(net "MAC_PPS_IN1-")
	)
	(segment
		(start 138.9361 84.0686)
		(end 141.6161 84.0686)
		(width 0.2032)
		(layer "F.Cu")
		(net "MAC_PPS_IN1-")
	)
	(segment
		(start 138.9261 84.0586)
		(end 138.9361 84.0686)
		(width 0.2032)
		(layer "F.Cu")
		(net "MAC_PPS_IN1-")
	)
	(segment
		(start 136.3261 113.2162)
		(end 136.54282 113.43292)
		(width 0.2032)
		(layer "F.Cu")
		(net "MAC_PPS_IN1-")
	)
	(segment
		(start 136.54282 113.43292)
		(end 137.66107 113.43292)
		(width 0.2032)
		(layer "F.Cu")
		(net "MAC_PPS_IN1-")
	)
	(via
		(at 136.3261 113.2162)
		(size 0.4064)
		(drill 0.2032)
		(layers "F.Cu" "B.Cu")
		(tenting
			(front yes)
			(back yes)
		)
		(net "MAC_PPS_IN1-")
	)
	(via
		(at 141.6161 84.0686)
		(size 0.4064)
		(drill 0.2032)
		(layers "F.Cu" "B.Cu")
		(tenting
			(front yes)
			(back yes)
		)
		(net "MAC_PPS_IN1-")
	)
	(segment
		(start 143.8261 89.3162)
		(end 143.8261 84.9162)
		(width 0.2032)
		(layer "In2.Cu")
		(net "MAC_PPS_IN1-")
	)
	(segment
		(start 142.3261 109.68125)
		(end 142.3261 90.4162)
		(width 0.2032)
		(layer "In2.Cu")
		(net "MAC_PPS_IN1-")
	)
	(segment
		(start 142.9261 89.8162)
		(end 143.3261 89.8162)
		(width 0.2032)
		(layer "In2.Cu")
		(net "MAC_PPS_IN1-")
	)
	(segment
		(start 141.6161 84.0686)
		(end 142.9785 84.0686)
		(width 0.2032)
		(layer "In2.Cu")
		(net "MAC_PPS_IN1-")
	)
	(segment
		(start 136.3261 113.2162)
		(end 138.79114 113.2162)
		(width 0.2032)
		(layer "In2.Cu")
		(net "MAC_PPS_IN1-")
	)
	(arc
		(start 142.32609 109.68125)
		(mid 141.290727 112.180837)
		(end 138.79114 113.2162)
		(width 0.2032)
		(layer "In2.Cu")
		(net "MAC_PPS_IN1-")
	)
	(arc
		(start 142.9785 84.0686)
		(mid 143.577844 84.316856)
		(end 143.8261 84.9162)
		(width 0.2032)
		(layer "In2.Cu")
		(net "MAC_PPS_IN1-")
	)
	(arc
		(start 142.3261 90.4162)
		(mid 142.501836 89.991936)
		(end 142.9261 89.8162)
		(width 0.2032)
		(layer "In2.Cu")
		(net "MAC_PPS_IN1-")
	)
	(arc
		(start 143.8261 89.3162)
		(mid 143.679653 89.669753)
		(end 143.3261 89.8162)
		(width 0.2032)
		(layer "In2.Cu")
		(net "MAC_PPS_IN1-")
	)
	(segment
		(start 170.84911 99.60161)
		(end 170.84911 97.94162)
		(width 0.2032)
		(layer "F.Cu")
		(net "MAC_FREQ_CTRL")
	)
	(segment
		(start 170.84911 99.60161)
		(end 170.8761 99.6286)
		(width 0.2032)
		(layer "F.Cu")
		(net "MAC_FREQ_CTRL")
	)
	(segment
		(start 170.82574 97.91825)
		(end 170.84911 97.94162)
		(width 0.2032)
		(layer "F.Cu")
		(net "MAC_FREQ_CTRL")
	)
	(via
		(at 170.8761 99.6286)
		(size 0.4064)
		(drill 0.2032)
		(layers "F.Cu" "B.Cu")
		(tenting
			(front yes)
			(back yes)
		)
		(net "MAC_FREQ_CTRL")
	)
	(segment
		(start 158.71869 93.80879)
		(end 168.99218 93.80879)
		(width 0.2032)
		(layer "In3.Cu")
		(net "MAC_FREQ_CTRL")
	)
	(segment
		(start 157.0261 92.1162)
		(end 158.71869 93.80879)
		(width 0.2032)
		(layer "In3.Cu")
		(net "MAC_FREQ_CTRL")
	)
	(segment
		(start 169.3261 97.6162)
		(end 170.8761 99.1662)
		(width 0.2032)
		(layer "In3.Cu")
		(net "MAC_FREQ_CTRL")
	)
	(segment
		(start 137.2261 93.2162)
		(end 138.3261 92.1162)
		(width 0.2032)
		(layer "In3.Cu")
		(net "MAC_FREQ_CTRL")
	)
	(segment
		(start 138.3261 92.1162)
		(end 157.0261 92.1162)
		(width 0.2032)
		(layer "In3.Cu")
		(net "MAC_FREQ_CTRL")
	)
	(segment
		(start 107.9261 93.2162)
		(end 137.2261 93.2162)
		(width 0.2032)
		(layer "In3.Cu")
		(net "MAC_FREQ_CTRL")
	)
	(segment
		(start 168.99218 93.80879)
		(end 169.3261 94.14271)
		(width 0.2032)
		(layer "In3.Cu")
		(net "MAC_FREQ_CTRL")
	)
	(segment
		(start 99.3261 94.9162)
		(end 106.2261 94.9162)
		(width 0.2032)
		(layer "In3.Cu")
		(net "MAC_FREQ_CTRL")
	)
	(segment
		(start 170.8761 99.6286)
		(end 170.8761 99.1662)
		(width 0.2032)
		(layer "In3.Cu")
		(net "MAC_FREQ_CTRL")
	)
	(segment
		(start 106.2261 94.9162)
		(end 107.9261 93.2162)
		(width 0.2032)
		(layer "In3.Cu")
		(net "MAC_FREQ_CTRL")
	)
	(segment
		(start 169.3261 97.6162)
		(end 169.3261 94.14271)
		(width 0.2032)
		(layer "In3.Cu")
		(net "MAC_FREQ_CTRL")
	)
	(segment
		(start 124.4385 87.0286)
		(end 124.7261 87.3162)
		(width 0.2032)
		(layer "F.Cu")
		(net "FPGA_MAC_PPS_OUT-")
	)
	(segment
		(start 123.3261 88.0286)
		(end 123.3261 87.0786)
		(width 0.2032)
		(layer "F.Cu")
		(net "FPGA_MAC_PPS_OUT-")
	)
	(segment
		(start 123.3261 87.0786)
		(end 123.3761 87.0286)
		(width 0.2032)
		(layer "F.Cu")
		(net "FPGA_MAC_PPS_OUT-")
	)
	(segment
		(start 124.7261 87.4162)
		(end 124.7261 87.3162)
		(width 0.2032)
		(layer "F.Cu")
		(net "FPGA_MAC_PPS_OUT-")
	)
	(segment
		(start 123.3761 87.0286)
		(end 124.4385 87.0286)
		(width 0.2032)
		(layer "F.Cu")
		(net "FPGA_MAC_PPS_OUT-")
	)
	(segment
		(start 173.32586 97.91825)
		(end 173.32598 97.91837)
		(width 0.2032)
		(layer "F.Cu")
		(net "FPGA_MAC_PPS_OUT-")
	)
	(segment
		(start 173.32598 99.62848)
		(end 173.32598 97.91837)
		(width 0.2032)
		(layer "F.Cu")
		(net "FPGA_MAC_PPS_OUT-")
	)
	(segment
		(start 173.32598 99.62848)
		(end 173.3261 99.6286)
		(width 0.2032)
		(layer "F.Cu")
		(net "FPGA_MAC_PPS_OUT-")
	)
	(via
		(at 173.3261 99.6286)
		(size 0.4064)
		(drill 0.2032)
		(layers "F.Cu" "B.Cu")
		(tenting
			(front yes)
			(back yes)
		)
		(net "FPGA_MAC_PPS_OUT-")
	)
	(via
		(at 123.3261 88.0286)
		(size 0.4064)
		(drill 0.2032)
		(layers "F.Cu" "B.Cu")
		(tenting
			(front yes)
			(back yes)
		)
		(net "FPGA_MAC_PPS_OUT-")
	)
	(segment
		(start 125.1268 88.0286)
		(end 126.1261 89.0279)
		(width 0.2032)
		(layer "In3.Cu")
		(net "FPGA_MAC_PPS_OUT-")
	)
	(segment
		(start 173.3261 99.6286)
		(end 173.3261 94.7536)
		(width 0.2032)
		(layer "In3.Cu")
		(net "FPGA_MAC_PPS_OUT-")
	)
	(segment
		(start 126.1261 89.0279)
		(end 167.6004 89.0279)
		(width 0.2032)
		(layer "In3.Cu")
		(net "FPGA_MAC_PPS_OUT-")
	)
	(segment
		(start 123.3261 88.0286)
		(end 125.1268 88.0286)
		(width 0.2032)
		(layer "In3.Cu")
		(net "FPGA_MAC_PPS_OUT-")
	)
	(segment
		(start 167.6004 89.0279)
		(end 173.3261 94.7536)
		(width 0.2032)
		(layer "In3.Cu")
		(net "FPGA_MAC_PPS_OUT-")
	)
	(segment
		(start 175.82573 99.47324)
		(end 175.82573 97.91825)
		(width 0.2032)
		(layer "F.Cu")
		(net "FPGA_MAC_PPS_IN1-")
	)
	(segment
		(start 131.0261 86.3286)
		(end 131.0261 86.3286)
		(width 0.2032)
		(layer "F.Cu")
		(net "FPGA_MAC_PPS_IN1-")
	)
	(segment
		(start 131.0261 85.3286)
		(end 134.1261 85.3286)
		(width 0.2032)
		(layer "F.Cu")
		(net "FPGA_MAC_PPS_IN1-")
	)
	(segment
		(start 175.8761 99.5786)
		(end 175.8761 99.52361)
		(width 0.2032)
		(layer "F.Cu")
		(net "FPGA_MAC_PPS_IN1-")
	)
	(segment
		(start 131.0261 86.3286)
		(end 131.0261 85.3286)
		(width 0.2032)
		(layer "F.Cu")
		(net "FPGA_MAC_PPS_IN1-")
	)
	(segment
		(start 175.82573 99.47324)
		(end 175.8761 99.52361)
		(width 0.2032)
		(layer "F.Cu")
		(net "FPGA_MAC_PPS_IN1-")
	)
	(via
		(at 175.8761 99.5786)
		(size 0.4064)
		(drill 0.2032)
		(layers "F.Cu" "B.Cu")
		(tenting
			(front yes)
			(back yes)
		)
		(net "FPGA_MAC_PPS_IN1-")
	)
	(via
		(at 131.0261 86.3286)
		(size 0.4064)
		(drill 0.2032)
		(layers "F.Cu" "B.Cu")
		(tenting
			(front yes)
			(back yes)
		)
		(net "FPGA_MAC_PPS_IN1-")
	)
	(segment
		(start 175.8761 99.5786)
		(end 175.8761 95.2286)
		(width 0.2032)
		(layer "In3.Cu")
		(net "FPGA_MAC_PPS_IN1-")
	)
	(segment
		(start 133.0011 88.3036)
		(end 168.9511 88.3036)
		(width 0.2032)
		(layer "In3.Cu")
		(net "FPGA_MAC_PPS_IN1-")
	)
	(segment
		(start 132.4261 87.7286)
		(end 133.0011 88.3036)
		(width 0.2032)
		(layer "In3.Cu")
		(net "FPGA_MAC_PPS_IN1-")
	)
	(segment
		(start 131.0261 86.3286)
		(end 132.4261 87.7286)
		(width 0.2032)
		(layer "In3.Cu")
		(net "FPGA_MAC_PPS_IN1-")
	)
	(segment
		(start 132.4261 87.7286)
		(end 132.4261 87.7286)
		(width 0.2032)
		(layer "In3.Cu")
		(net "FPGA_MAC_PPS_IN1-")
	)
	(segment
		(start 168.9511 88.3036)
		(end 175.8761 95.2286)
		(width 0.2032)
		(layer "In3.Cu")
		(net "FPGA_MAC_PPS_IN1-")
	)
	(segment
		(start 174.31348 99.61622)
		(end 174.31348 97.93063)
		(width 0.2032)
		(layer "F.Cu")
		(net "FPGA_MAC_PPS_IN0-")
	)
	(segment
		(start 131.02147 88.30859)
		(end 131.02147 87.33323)
		(width 0.2032)
		(layer "F.Cu")
		(net "FPGA_MAC_PPS_IN0-")
	)
	(segment
		(start 129.87888 88.71463)
		(end 130.61543 88.71463)
		(width 0.2032)
		(layer "F.Cu")
		(net "FPGA_MAC_PPS_IN0-")
	)
	(segment
		(start 130.61543 88.71463)
		(end 131.01684 88.31322)
		(width 0.2032)
		(layer "F.Cu")
		(net "FPGA_MAC_PPS_IN0-")
	)
	(segment
		(start 131.0261 87.3286)
		(end 132.0261 87.3286)
		(width 0.2032)
		(layer "F.Cu")
		(net "FPGA_MAC_PPS_IN0-")
	)
	(segment
		(start 131.02147 87.33323)
		(end 131.0261 87.3286)
		(width 0.2032)
		(layer "F.Cu")
		(net "FPGA_MAC_PPS_IN0-")
	)
	(segment
		(start 132.7561 86.5986)
		(end 134.1261 86.5986)
		(width 0.2032)
		(layer "F.Cu")
		(net "FPGA_MAC_PPS_IN0-")
	)
	(segment
		(start 174.31348 97.93063)
		(end 174.32586 97.91825)
		(width 0.2032)
		(layer "F.Cu")
		(net "FPGA_MAC_PPS_IN0-")
	)
	(segment
		(start 174.3011 99.6286)
		(end 174.31348 99.61622)
		(width 0.2032)
		(layer "F.Cu")
		(net "FPGA_MAC_PPS_IN0-")
	)
	(segment
		(start 131.01684 88.31322)
		(end 131.02147 88.30859)
		(width 0.2032)
		(layer "F.Cu")
		(net "FPGA_MAC_PPS_IN0-")
	)
	(segment
		(start 132.0261 87.3286)
		(end 132.7561 86.5986)
		(width 0.2032)
		(layer "F.Cu")
		(net "FPGA_MAC_PPS_IN0-")
	)
	(via
		(at 131.01684 88.31322)
		(size 0.4064)
		(drill 0.2032)
		(layers "F.Cu" "B.Cu")
		(tenting
			(front yes)
			(back yes)
		)
		(net "FPGA_MAC_PPS_IN0-")
	)
	(via
		(at 174.3011 99.6286)
		(size 0.4064)
		(drill 0.2032)
		(layers "F.Cu" "B.Cu")
		(tenting
			(front yes)
			(back yes)
		)
		(net "FPGA_MAC_PPS_IN0-")
	)
	(segment
		(start 131.01684 88.31322)
		(end 131.35847 88.65485)
		(width 0.2032)
		(layer "In3.Cu")
		(net "FPGA_MAC_PPS_IN0-")
	)
	(segment
		(start 174.3011 99.6286)
		(end 174.3011 94.9786)
		(width 0.2032)
		(layer "In3.Cu")
		(net "FPGA_MAC_PPS_IN0-")
	)
	(segment
		(start 167.97735 88.65485)
		(end 174.3011 94.9786)
		(width 0.2032)
		(layer "In3.Cu")
		(net "FPGA_MAC_PPS_IN0-")
	)
	(segment
		(start 131.35847 88.65485)
		(end 167.97735 88.65485)
		(width 0.2032)
		(layer "In3.Cu")
		(net "FPGA_MAC_PPS_IN0-")
	)
	(segment
		(start 165.31349 99.64121)
		(end 165.31349 97.93064)
		(width 0.2032)
		(layer "F.Cu")
		(net "MAC_RF_OUT")
	)
	(segment
		(start 165.9511 99.6536)
		(end 165.9511 99.59861)
		(width 0.2032)
		(layer "F.Cu")
		(net "MAC_RF_OUT")
	)
	(segment
		(start 165.82575 99.47327)
		(end 165.9511 99.59861)
		(width 0.2032)
		(layer "F.Cu")
		(net "MAC_RF_OUT")
	)
	(segment
		(start 165.31349 97.93064)
		(end 165.32588 97.91825)
		(width 0.2032)
		(layer "F.Cu")
		(net "MAC_RF_OUT")
	)
	(segment
		(start 165.82575 99.47327)
		(end 165.82575 97.91825)
		(width 0.2032)
		(layer "F.Cu")
		(net "MAC_RF_OUT")
	)
	(segment
		(start 165.3011 99.6536)
		(end 165.31349 99.64121)
		(width 0.2032)
		(layer "F.Cu")
		(net "MAC_RF_OUT")
	)
	(via
		(at 165.3011 99.6536)
		(size 0.4064)
		(drill 0.2032)
		(layers "F.Cu" "B.Cu")
		(tenting
			(front yes)
			(back yes)
		)
		(net "MAC_RF_OUT")
	)
	(via
		(at 165.9511 99.6536)
		(size 0.4064)
		(drill 0.2032)
		(layers "F.Cu" "B.Cu")
		(tenting
			(front yes)
			(back yes)
		)
		(net "MAC_RF_OUT")
	)
	(segment
		(start 163.6261 96.92649)
		(end 163.6261 94.8162)
		(width 0.2032)
		(layer "In2.Cu")
		(net "MAC_RF_OUT")
	)
	(segment
		(start 147.6782 91.1162)
		(end 154.974 91.1162)
		(width 0.2032)
		(layer "In2.Cu")
		(net "MAC_RF_OUT")
	)
	(segment
		(start 169.8782 118.1162)
		(end 194.3261 118.1162)
		(width 0.2032)
		(layer "In2.Cu")
		(net "MAC_RF_OUT")
	)
	(segment
		(start 104.0782 131.8162)
		(end 189.074 131.8162)
		(width 0.2032)
		(layer "In2.Cu")
		(net "MAC_RF_OUT")
	)
	(segment
		(start 140.87005 125.16015)
		(end 141.6261 125.9162)
		(width 0.2032)
		(layer "In2.Cu")
		(net "MAC_RF_OUT")
	)
	(segment
		(start 144.2261 113.6641)
		(end 144.2261 94.5683)
		(width 0.2032)
		(layer "In2.Cu")
		(net "MAC_RF_OUT")
	)
	(segment
		(start 156.77005 90.37225)
		(end 158.1261 89.0162)
		(width 0.2032)
		(layer "In2.Cu")
		(net "MAC_RF_OUT")
	)
	(segment
		(start 164.37005 98.72255)
		(end 165.3011 99.6536)
		(width 0.2032)
		(layer "In2.Cu")
		(net "MAC_RF_OUT")
	)
	(segment
		(start 165.3011 99.6536)
		(end 165.9511 99.6536)
		(width 0.2032)
		(layer "In2.Cu")
		(net "MAC_RF_OUT")
	)
	(segment
		(start 158.99848 88.65485)
		(end 161.11264 88.65485)
		(width 0.2032)
		(layer "In2.Cu")
		(net "MAC_RF_OUT")
	)
	(segment
		(start 165.5261 92.99193)
		(end 165.5261 92.0162)
		(width 0.2032)
		(layer "In2.Cu")
		(net "MAC_RF_OUT")
	)
	(segment
		(start 99.3261 135.5162)
		(end 102.28215 132.56015)
		(width 0.2032)
		(layer "In2.Cu")
		(net "MAC_RF_OUT")
	)
	(segment
		(start 157.1261 124.2162)
		(end 161.674 124.2162)
		(width 0.2032)
		(layer "In2.Cu")
		(net "MAC_RF_OUT")
	)
	(segment
		(start 144.97005 92.77225)
		(end 145.88215 91.86015)
		(width 0.2032)
		(layer "In2.Cu")
		(net "MAC_RF_OUT")
	)
	(segment
		(start 154.9261 125.6162)
		(end 155.76042 124.78188)
		(width 0.2032)
		(layer "In2.Cu")
		(net "MAC_RF_OUT")
	)
	(segment
		(start 141.6261 125.9162)
		(end 154.20184 125.9162)
		(width 0.2032)
		(layer "In2.Cu")
		(net "MAC_RF_OUT")
	)
	(segment
		(start 162.9087 89.3988)
		(end 165.5261 92.0162)
		(width 0.2032)
		(layer "In2.Cu")
		(net "MAC_RF_OUT")
	)
	(segment
		(start 194.7261 127.2162)
		(end 194.7261 119.08189)
		(width 0.2032)
		(layer "In2.Cu")
		(net "MAC_RF_OUT")
	)
	(segment
		(start 164.37255 94.06975)
		(end 164.37278 94.06952)
		(width 0.2032)
		(layer "In2.Cu")
		(net "MAC_RF_OUT")
	)
	(segment
		(start 163.47005 123.47225)
		(end 168.08215 118.86015)
		(width 0.2032)
		(layer "In2.Cu")
		(net "MAC_RF_OUT")
	)
	(segment
		(start 163.6261 94.8162)
		(end 164.37255 94.06975)
		(width 0.2032)
		(layer "In2.Cu")
		(net "MAC_RF_OUT")
	)
	(segment
		(start 190.87005 131.07225)
		(end 194.7261 127.2162)
		(width 0.2032)
		(layer "In2.Cu")
		(net "MAC_RF_OUT")
	)
	(segment
		(start 140.87005 118.07225)
		(end 143.48215 115.46015)
		(width 0.2032)
		(layer "In2.Cu")
		(net "MAC_RF_OUT")
	)
	(segment
		(start 140.1261 123.3641)
		(end 140.1261 119.8683)
		(width 0.2032)
		(layer "In2.Cu")
		(net "MAC_RF_OUT")
	)
	(arc
		(start 140.1261 119.8683)
		(mid 140.319446 118.896284)
		(end 140.870049 118.072249)
		(width 0.2032)
		(layer "In2.Cu")
		(net "MAC_RF_OUT")
	)
	(arc
		(start 156.770051 90.372251)
		(mid 155.946016 90.922854)
		(end 154.974 91.1162)
		(width 0.2032)
		(layer "In2.Cu")
		(net "MAC_RF_OUT")
	)
	(arc
		(start 102.282149 132.560149)
		(mid 103.106184 132.009546)
		(end 104.0782 131.8162)
		(width 0.2032)
		(layer "In2.Cu")
		(net "MAC_RF_OUT")
	)
	(arc
		(start 164.372777 94.069512)
		(mid 164.764311 93.808013)
		(end 165.2261 93.71619)
		(width 0.2032)
		(layer "In2.Cu")
		(net "MAC_RF_OUT")
	)
	(arc
		(start 154.926101 125.616201)
		(mid 154.593807 125.838233)
		(end 154.20184 125.9162)
		(width 0.2032)
		(layer "In2.Cu")
		(net "MAC_RF_OUT")
	)
	(arc
		(start 158.126094 89.016194)
		(mid 158.526348 88.748753)
		(end 158.99848 88.65484)
		(width 0.2032)
		(layer "In2.Cu")
		(net "MAC_RF_OUT")
	)
	(arc
		(start 194.326099 118.116201)
		(mid 194.622143 118.559263)
		(end 194.7261 119.08189)
		(width 0.2032)
		(layer "In2.Cu")
		(net "MAC_RF_OUT")
	)
	(arc
		(start 140.870049 125.160151)
		(mid 140.319446 124.336116)
		(end 140.1261 123.3641)
		(width 0.2032)
		(layer "In2.Cu")
		(net "MAC_RF_OUT")
	)
	(arc
		(start 155.760415 124.781885)
		(mid 156.386997 124.363217)
		(end 157.1261 124.2162)
		(width 0.2032)
		(layer "In2.Cu")
		(net "MAC_RF_OUT")
	)
	(arc
		(start 161.11264 88.65485)
		(mid 162.084656 88.848196)
		(end 162.908691 89.398799)
		(width 0.2032)
		(layer "In2.Cu")
		(net "MAC_RF_OUT")
	)
	(arc
		(start 190.870051 131.072251)
		(mid 190.046016 131.622854)
		(end 189.074 131.8162)
		(width 0.2032)
		(layer "In2.Cu")
		(net "MAC_RF_OUT")
	)
	(arc
		(start 145.882149 91.860149)
		(mid 146.706184 91.309546)
		(end 147.6782 91.1162)
		(width 0.2032)
		(layer "In2.Cu")
		(net "MAC_RF_OUT")
	)
	(arc
		(start 163.470051 123.472251)
		(mid 162.646016 124.022854)
		(end 161.674 124.2162)
		(width 0.2032)
		(layer "In2.Cu")
		(net "MAC_RF_OUT")
	)
	(arc
		(start 168.082149 118.860149)
		(mid 168.906184 118.309546)
		(end 169.8782 118.1162)
		(width 0.2032)
		(layer "In2.Cu")
		(net "MAC_RF_OUT")
	)
	(arc
		(start 144.2261 113.6641)
		(mid 144.032754 114.636116)
		(end 143.482151 115.460151)
		(width 0.2032)
		(layer "In2.Cu")
		(net "MAC_RF_OUT")
	)
	(arc
		(start 144.2261 94.5683)
		(mid 144.419446 93.596284)
		(end 144.970049 92.772249)
		(width 0.2032)
		(layer "In2.Cu")
		(net "MAC_RF_OUT")
	)
	(arc
		(start 164.370049 98.722541)
		(mid 163.819446 97.898506)
		(end 163.6261 96.92649)
		(width 0.2032)
		(layer "In2.Cu")
		(net "MAC_RF_OUT")
	)
	(arc
		(start 165.5261 92.99193)
		(mid 165.448133 93.3839)
		(end 165.2261 93.716196)
		(width 0.2032)
		(layer "In2.Cu")
		(net "MAC_RF_OUT")
	)
	(segment
		(start 200.42886 115.31344)
		(end 201.3761 114.3662)
		(width 0.2032)
		(layer "F.Cu")
		(net "EXT_EEPROM_WP")
	)
	(segment
		(start 180.7761 90.0786)
		(end 182.3761 90.0786)
		(width 0.2032)
		(layer "F.Cu")
		(net "EXT_EEPROM_WP")
	)
	(segment
		(start 180.2011 90.0786)
		(end 180.7761 90.0786)
		(width 0.2032)
		(layer "F.Cu")
		(net "EXT_EEPROM_WP")
	)
	(segment
		(start 181.0761 89.7786)
		(end 181.0761 88.14481)
		(width 0.2032)
		(layer "F.Cu")
		(net "EXT_EEPROM_WP")
	)
	(segment
		(start 180.7761 90.0786)
		(end 181.0761 89.7786)
		(width 0.2032)
		(layer "F.Cu")
		(net "EXT_EEPROM_WP")
	)
	(segment
		(start 180.2011 90.0786)
		(end 180.2261 90.1036)
		(width 0.2032)
		(layer "F.Cu")
		(net "EXT_EEPROM_WP")
	)
	(segment
		(start 199.3634 115.31344)
		(end 200.42886 115.31344)
		(width 0.2032)
		(layer "F.Cu")
		(net "EXT_EEPROM_WP")
	)
	(via
		(at 182.38436 90.07034)
		(size 0.4064)
		(drill 0.2032)
		(layers "F.Cu" "B.Cu")
		(tenting
			(front yes)
			(back yes)
		)
		(net "EXT_EEPROM_WP")
	)
	(via
		(at 201.3761 114.3662)
		(size 0.4064)
		(drill 0.2032)
		(layers "F.Cu" "B.Cu")
		(tenting
			(front yes)
			(back yes)
		)
		(net "EXT_EEPROM_WP")
	)
	(segment
		(start 202.6261 113.1162)
		(end 202.6261 108.82859)
		(width 0.2032)
		(layer "B.Cu")
		(net "EXT_EEPROM_WP")
	)
	(segment
		(start 201.3761 114.3662)
		(end 202.6261 113.1162)
		(width 0.2032)
		(layer "B.Cu")
		(net "EXT_EEPROM_WP")
	)
	(segment
		(start 182.38436 90.07034)
		(end 183.86785 90.07034)
		(width 0.2032)
		(layer "B.Cu")
		(net "EXT_EEPROM_WP")
	)
	(segment
		(start 183.86785 90.07034)
		(end 202.6261 108.82859)
		(width 0.2032)
		(layer "B.Cu")
		(net "EXT_EEPROM_WP")
	)
	(segment
		(start 182.32585 93.86847)
		(end 182.32598 93.86834)
		(width 0.2032)
		(layer "F.Cu")
		(net "GPS1_TX")
	)
	(segment
		(start 182.32598 93.86834)
		(end 182.32598 91.65373)
		(width 0.2032)
		(layer "F.Cu")
		(net "GPS1_TX")
	)
	(segment
		(start 182.32598 91.65373)
		(end 182.3261 91.6536)
		(width 0.2032)
		(layer "F.Cu")
		(net "GPS1_TX")
	)
	(segment
		(start 79.8761 71.8286)
		(end 81.9311 71.8286)
		(width 0.2032)
		(layer "F.Cu")
		(net "GPS1_TX")
	)
	(via
		(at 182.3261 91.6536)
		(size 0.4064)
		(drill 0.2032)
		(layers "F.Cu" "B.Cu")
		(tenting
			(front yes)
			(back yes)
		)
		(net "GPS1_TX")
	)
	(via
		(at 79.8761 71.8286)
		(size 0.4064)
		(drill 0.2032)
		(layers "F.Cu" "B.Cu")
		(tenting
			(front yes)
			(back yes)
		)
		(net "GPS1_TX")
	)
	(segment
		(start 85.1761 77.1286)
		(end 131.2011 77.1286)
		(width 0.2032)
		(layer "In3.Cu")
		(net "GPS1_TX")
	)
	(segment
		(start 173.4261 82.7536)
		(end 182.3261 91.6536)
		(width 0.2032)
		(layer "In3.Cu")
		(net "GPS1_TX")
	)
	(segment
		(start 131.2011 77.1286)
		(end 136.8261 82.7536)
		(width 0.2032)
		(layer "In3.Cu")
		(net "GPS1_TX")
	)
	(segment
		(start 79.8761 71.8286)
		(end 85.1761 77.1286)
		(width 0.2032)
		(layer "In3.Cu")
		(net "GPS1_TX")
	)
	(segment
		(start 136.8261 82.7536)
		(end 173.4261 82.7536)
		(width 0.2032)
		(layer "In3.Cu")
		(net "GPS1_TX")
	)
	(segment
		(start 200.56014 112.31345)
		(end 200.79851 112.07508)
		(width 0.2032)
		(layer "F.Cu")
		(net "GPS1_TP1")
	)
	(segment
		(start 199.3634 112.31345)
		(end 200.56014 112.31345)
		(width 0.2032)
		(layer "F.Cu")
		(net "GPS1_TP1")
	)
	(segment
		(start 200.79851 112.07508)
		(end 201.37688 112.07508)
		(width 0.2032)
		(layer "F.Cu")
		(net "GPS1_TP1")
	)
	(segment
		(start 86.3761 69.8286)
		(end 88.3761 69.8286)
		(width 0.2032)
		(layer "F.Cu")
		(net "GPS1_TP1")
	)
	(via
		(at 88.3761 69.8286)
		(size 0.4064)
		(drill 0.2032)
		(layers "F.Cu" "B.Cu")
		(tenting
			(front yes)
			(back yes)
		)
		(net "GPS1_TP1")
	)
	(via
		(at 201.37688 112.07508)
		(size 0.4064)
		(drill 0.2032)
		(layers "F.Cu" "B.Cu")
		(tenting
			(front yes)
			(back yes)
		)
		(net "GPS1_TP1")
	)
	(segment
		(start 201.3247 113.3092)
		(end 201.6261 113.0078)
		(width 0.2032)
		(layer "B.Cu")
		(net "GPS1_TP1")
	)
	(segment
		(start 170.11553 113.3092)
		(end 201.3247 113.3092)
		(width 0.2032)
		(layer "B.Cu")
		(net "GPS1_TP1")
	)
	(segment
		(start 139.0163 101.2188)
		(end 158.02513 101.2188)
		(width 0.2032)
		(layer "B.Cu")
		(net "GPS1_TP1")
	)
	(segment
		(start 88.3761 69.8286)
		(end 107.6261 69.8286)
		(width 0.2032)
		(layer "B.Cu")
		(net "GPS1_TP1")
	)
	(segment
		(start 201.37688 112.07938)
		(end 201.6261 112.3286)
		(width 0.2032)
		(layer "B.Cu")
		(net "GPS1_TP1")
	)
	(segment
		(start 201.6261 113.0078)
		(end 201.6261 112.3286)
		(width 0.2032)
		(layer "B.Cu")
		(net "GPS1_TP1")
	)
	(segment
		(start 107.6261 69.8286)
		(end 139.0163 101.2188)
		(width 0.2032)
		(layer "B.Cu")
		(net "GPS1_TP1")
	)
	(segment
		(start 201.37688 112.07938)
		(end 201.37688 112.07508)
		(width 0.2032)
		(layer "B.Cu")
		(net "GPS1_TP1")
	)
	(segment
		(start 158.02513 101.2188)
		(end 170.11553 113.3092)
		(width 0.2032)
		(layer "B.Cu")
		(net "GPS1_TP1")
	)
	(segment
		(start 79.8761 69.8286)
		(end 81.9311 69.8286)
		(width 0.2032)
		(layer "F.Cu")
		(net "GPS1_RX")
	)
	(segment
		(start 182.32585 97.91825)
		(end 182.33847 97.93088)
		(width 0.2032)
		(layer "F.Cu")
		(net "GPS1_RX")
	)
	(segment
		(start 182.33847 99.59097)
		(end 182.3511 99.6036)
		(width 0.2032)
		(layer "F.Cu")
		(net "GPS1_RX")
	)
	(segment
		(start 182.33847 99.59097)
		(end 182.33847 97.93088)
		(width 0.2032)
		(layer "F.Cu")
		(net "GPS1_RX")
	)
	(via
		(at 79.8761 69.8286)
		(size 0.4064)
		(drill 0.2032)
		(layers "F.Cu" "B.Cu")
		(tenting
			(front yes)
			(back yes)
		)
		(net "GPS1_RX")
	)
	(via
		(at 182.3511 99.6036)
		(size 0.4064)
		(drill 0.2032)
		(layers "F.Cu" "B.Cu")
		(tenting
			(front yes)
			(back yes)
		)
		(net "GPS1_RX")
	)
	(segment
		(start 182.8761 92.1786)
		(end 182.8761 91.3036)
		(width 0.2032)
		(layer "In3.Cu")
		(net "GPS1_RX")
	)
	(segment
		(start 182.3511 99.6036)
		(end 182.3511 97.0536)
		(width 0.2032)
		(layer "In3.Cu")
		(net "GPS1_RX")
	)
	(segment
		(start 181.8761 96.5786)
		(end 181.8761 93.1786)
		(width 0.2032)
		(layer "In3.Cu")
		(net "GPS1_RX")
	)
	(segment
		(start 137.0011 82.3036)
		(end 173.8761 82.3036)
		(width 0.2032)
		(layer "In3.Cu")
		(net "GPS1_RX")
	)
	(segment
		(start 79.8761 70.8286)
		(end 85.7761 76.7286)
		(width 0.2032)
		(layer "In3.Cu")
		(net "GPS1_RX")
	)
	(segment
		(start 79.8761 70.8286)
		(end 79.8761 69.8286)
		(width 0.2032)
		(layer "In3.Cu")
		(net "GPS1_RX")
	)
	(segment
		(start 85.7761 76.7286)
		(end 131.4261 76.7286)
		(width 0.2032)
		(layer "In3.Cu")
		(net "GPS1_RX")
	)
	(segment
		(start 181.8761 96.5786)
		(end 182.3511 97.0536)
		(width 0.2032)
		(layer "In3.Cu")
		(net "GPS1_RX")
	)
	(segment
		(start 131.4261 76.7286)
		(end 137.0011 82.3036)
		(width 0.2032)
		(layer "In3.Cu")
		(net "GPS1_RX")
	)
	(segment
		(start 181.8761 93.1786)
		(end 182.8761 92.1786)
		(width 0.2032)
		(layer "In3.Cu")
		(net "GPS1_RX")
	)
	(segment
		(start 173.8761 82.3036)
		(end 182.8761 91.3036)
		(width 0.2032)
		(layer "In3.Cu")
		(net "GPS1_RX")
	)
	(segment
		(start 115.5461 157.7576)
		(end 115.5621 157.7416)
		(width 0.2032)
		(layer "B.Cu")
		(net "NetC44_1")
	)
	(segment
		(start 115.5621 156.99168)
		(end 115.5621 152.2186)
		(width 0.127)
		(layer "B.Cu")
		(net "NetC44_1")
	)
	(arc
		(start 115.54609 152.25723)
		(mid 115.550249 152.236321)
		(end 115.562093 152.218594)
		(width 0.127)
		(layer "B.Cu")
		(net "NetC44_1")
	)
	(arc
		(start 115.5621 156.99168)
		(mid 115.552743 157.038719)
		(end 115.526098 157.078598)
		(width 0.127)
		(layer "B.Cu")
		(net "NetC44_1")
	)
	(segment
		(start 116.5781 156.95305)
		(end 116.5781 152.2186)
		(width 0.127)
		(layer "B.Cu")
		(net "NetC45_1")
	)
	(arc
		(start 116.5781 156.95305)
		(mid 116.564585 157.020995)
		(end 116.526097 157.078597)
		(width 0.127)
		(layer "B.Cu")
		(net "NetC45_1")
	)
	(segment
		(start 118.5847 156.93711)
		(end 118.5847 152.2186)
		(width 0.127)
		(layer "B.Cu")
		(net "NetC46_1")
	)
	(arc
		(start 118.5847 156.93711)
		(mid 118.569468 157.013685)
		(end 118.526092 157.078602)
		(width 0.127)
		(layer "B.Cu")
		(net "NetC46_1")
	)
	(arc
		(start 118.5847 157.66439)
		(mid 118.574687 157.714783)
		(end 118.546171 157.757521)
		(width 0.127)
		(layer "B.Cu")
		(net "NetC46_1")
	)
	(segment
		(start 119.6769 156.71451)
		(end 119.6769 152.2186)
		(width 0.127)
		(layer "B.Cu")
		(net "NetC47_1")
	)
	(arc
		(start 119.6769 156.71451)
		(mid 119.637706 156.911554)
		(end 119.526089 157.078599)
		(width 0.127)
		(layer "B.Cu")
		(net "NetC47_1")
	)
	(segment
		(start 123.5631 156.98923)
		(end 123.5631 152.2186)
		(width 0.127)
		(layer "B.Cu")
		(net "NetC48_1")
	)
	(arc
		(start 123.5631 157.71651)
		(mid 123.558677 157.738744)
		(end 123.546083 157.757593)
		(width 0.127)
		(layer "B.Cu")
		(net "NetC48_1")
	)
	(arc
		(start 123.5631 156.98923)
		(mid 123.553479 157.037597)
		(end 123.526081 157.078601)
		(width 0.127)
		(layer "B.Cu")
		(net "NetC48_1")
	)
	(segment
		(start 127.5001 157.01589)
		(end 127.5001 152.2186)
		(width 0.127)
		(layer "B.Cu")
		(net "NetC50_1")
	)
	(arc
		(start 127.500097 152.218603)
		(mid 127.534122 152.269524)
		(end 127.546069 152.32959)
		(width 0.127)
		(layer "B.Cu")
		(net "NetC50_1")
	)
	(arc
		(start 127.526074 157.078596)
		(mid 127.506851 157.049826)
		(end 127.5001 157.01589)
		(width 0.127)
		(layer "B.Cu")
		(net "NetC50_1")
	)
	(segment
		(start 128.3891 156.74792)
		(end 128.3891 152.2186)
		(width 0.127)
		(layer "B.Cu")
		(net "NetC51_1")
	)
	(arc
		(start 128.5456 157.757133)
		(mid 128.429768 157.583426)
		(end 128.3891 157.37864)
		(width 0.127)
		(layer "B.Cu")
		(net "NetC51_1")
	)
	(arc
		(start 128.526072 157.078598)
		(mid 128.424698 156.926882)
		(end 128.389101 156.74792)
		(width 0.127)
		(layer "B.Cu")
		(net "NetC51_1")
	)
	(segment
		(start 131.5641 156.98678)
		(end 131.5641 152.2186)
		(width 0.127)
		(layer "B.Cu")
		(net "NetC52_1")
	)
	(arc
		(start 131.56411 156.98678)
		(mid 131.554225 157.036475)
		(end 131.526075 157.078605)
		(width 0.127)
		(layer "B.Cu")
		(net "NetC52_1")
	)
	(arc
		(start 131.54607 152.26214)
		(mid 131.550757 152.238578)
		(end 131.564103 152.218603)
		(width 0.127)
		(layer "B.Cu")
		(net "NetC52_1")
	)
	(arc
		(start 131.5641 157.71406)
		(mid 131.559413 157.737622)
		(end 131.546067 157.757597)
		(width 0.127)
		(layer "B.Cu")
		(net "NetC52_1")
	)
	(segment
		(start 132.54606 157.7576)
		(end 132.5801 157.72356)
		(width 0.2032)
		(layer "B.Cu")
		(net "NetC53_1")
	)
	(segment
		(start 132.5801 156.94814)
		(end 132.5801 152.2186)
		(width 0.127)
		(layer "B.Cu")
		(net "NetC53_1")
	)
	(arc
		(start 132.54606 152.30077)
		(mid 132.554906 152.256298)
		(end 132.580097 152.218597)
		(width 0.127)
		(layer "B.Cu")
		(net "NetC53_1")
	)
	(arc
		(start 132.5801 156.94814)
		(mid 132.566057 157.018741)
		(end 132.526064 157.078594)
		(width 0.127)
		(layer "B.Cu")
		(net "NetC53_1")
	)
	(segment
		(start 75.1261 54.9412)
		(end 75.1261 52.8662)
		(width 0.2032)
		(layer "F.Cu")
		(net "NetD11_1")
	)
	(segment
		(start 119.5761 153.6786)
		(end 120.3761 152.8786)
		(width 0.2032)
		(layer "F.Cu")
		(net "NetP2_B17")
	)
	(segment
		(start 119.4761 148.7786)
		(end 119.4761 146.0036)
		(width 0.2032)
		(layer "F.Cu")
		(net "NetP2_B17")
	)
	(segment
		(start 119.5761 157.02859)
		(end 119.5761 153.6786)
		(width 0.2032)
		(layer "F.Cu")
		(net "NetP2_B17")
	)
	(segment
		(start 119.52609 157.0786)
		(end 119.5761 157.02859)
		(width 0.2032)
		(layer "F.Cu")
		(net "NetP2_B17")
	)
	(segment
		(start 120.3761 152.8786)
		(end 120.3761 149.6786)
		(width 0.2032)
		(layer "F.Cu")
		(net "NetP2_B17")
	)
	(segment
		(start 119.4761 148.7786)
		(end 120.3761 149.6786)
		(width 0.2032)
		(layer "F.Cu")
		(net "NetP2_B17")
	)
	(segment
		(start 133.54606 157.2623)
		(end 133.5961 157.21226)
		(width 0.2032)
		(layer "F.Cu")
		(net "NetP2_B31")
	)
	(segment
		(start 133.4761 156.53334)
		(end 133.4761 146.0036)
		(width 0.2032)
		(layer "F.Cu")
		(net "NetP2_B31")
	)
	(segment
		(start 133.4761 156.53334)
		(end 133.52606 156.5833)
		(width 0.2032)
		(layer "F.Cu")
		(net "NetP2_B31")
	)
	(segment
		(start 133.42606 146.05364)
		(end 133.4761 146.0036)
		(width 0.2032)
		(layer "F.Cu")
		(net "NetP2_B31")
	)
	(segment
		(start 203.2897 87.7312)
		(end 204.5567 86.4642)
		(width 0.2032)
		(layer "F.Cu")
		(net "NetR3_1")
	)
	(segment
		(start 201.8177 87.7312)
		(end 203.2897 87.7312)
		(width 0.2032)
		(layer "F.Cu")
		(net "NetR3_1")
	)
	(segment
		(start 204.5567 86.4642)
		(end 204.5567 85.7642)
		(width 0.2032)
		(layer "F.Cu")
		(net "NetR3_1")
	)
	(segment
		(start 209.4095 112.6262)
		(end 209.4095 111.9262)
		(width 0.2032)
		(layer "F.Cu")
		(net "NetR4_2")
	)
	(segment
		(start 209.4095 111.9262)
		(end 209.4095 110.6952)
		(width 0.2032)
		(layer "F.Cu")
		(net "NetR4_2")
	)
	(segment
		(start 209.4095 113.0372)
		(end 209.5755 113.2032)
		(width 0.2032)
		(layer "F.Cu")
		(net "NetR4_2")
	)
	(segment
		(start 209.4095 110.6952)
		(end 209.8225 110.2822)
		(width 0.2032)
		(layer "F.Cu")
		(net "NetR4_2")
	)
	(segment
		(start 209.4095 113.0372)
		(end 209.4095 112.6262)
		(width 0.2032)
		(layer "F.Cu")
		(net "NetR4_2")
	)
	(segment
		(start 210.9885 113.2032)
		(end 211.0605 113.2032)
		(width 0.2032)
		(layer "F.Cu")
		(net "NetR4_2")
	)
	(segment
		(start 209.4095 111.9262)
		(end 209.4095 112.6262)
		(width 0.2032)
		(layer "F.Cu")
		(net "NetR4_2")
	)
	(segment
		(start 209.5755 113.2032)
		(end 210.9885 113.2032)
		(width 0.2032)
		(layer "F.Cu")
		(net "NetR4_2")
	)
	(segment
		(start 209.8225 110.2822)
		(end 211.0605 110.2822)
		(width 0.2032)
		(layer "F.Cu")
		(net "NetR4_2")
	)
	(segment
		(start 208.1847 85.0264)
		(end 208.1847 84.8864)
		(width 0.2032)
		(layer "F.Cu")
		(net "NetR5_1")
	)
	(segment
		(start 207.7863 85.2848)
		(end 207.92629 85.2848)
		(width 0.2032)
		(layer "F.Cu")
		(net "NetR5_1")
	)
	(segment
		(start 207.0967 85.7642)
		(end 207.0967 85.68703)
		(width 0.2032)
		(layer "F.Cu")
		(net "NetR5_1")
	)
	(segment
		(start 207.0967 86.4642)
		(end 208.6207 87.9882)
		(width 0.2032)
		(layer "F.Cu")
		(net "NetR5_1")
	)
	(segment
		(start 207.0967 85.68703)
		(end 207.2801 85.50363)
		(width 0.2032)
		(layer "F.Cu")
		(net "NetR5_1")
	)
	(segment
		(start 207.2801 85.50363)
		(end 207.56747 85.50363)
		(width 0.2032)
		(layer "F.Cu")
		(net "NetR5_1")
	)
	(segment
		(start 208.6207 89.7082)
		(end 208.6207 87.9882)
		(width 0.2032)
		(layer "F.Cu")
		(net "NetR5_1")
	)
	(segment
		(start 207.92629 85.2848)
		(end 208.1847 85.0264)
		(width 0.2032)
		(layer "F.Cu")
		(net "NetR5_1")
	)
	(segment
		(start 207.0967 86.4642)
		(end 207.0967 85.7642)
		(width 0.2032)
		(layer "F.Cu")
		(net "NetR5_1")
	)
	(segment
		(start 207.56747 85.50363)
		(end 207.7863 85.2848)
		(width 0.2032)
		(layer "F.Cu")
		(net "NetR5_1")
	)
	(segment
		(start 203.40993 142.3762)
		(end 207.7261 142.3762)
		(width 0.2032)
		(layer "F.Cu")
		(net "NetR18_2")
	)
	(segment
		(start 200.41136 139.37763)
		(end 203.40993 142.3762)
		(width 0.2032)
		(layer "F.Cu")
		(net "NetR18_2")
	)
	(segment
		(start 212.8061 142.3762)
		(end 212.82673 142.39683)
		(width 0.2032)
		(layer "F.Cu")
		(net "NetR20_2")
	)
	(segment
		(start 212.8061 145.0962)
		(end 212.8061 142.3762)
		(width 0.2032)
		(layer "F.Cu")
		(net "NetR20_2")
	)
	(segment
		(start 213.9261 146.2162)
		(end 226.4261 146.2162)
		(width 0.2032)
		(layer "F.Cu")
		(net "NetR20_2")
	)
	(segment
		(start 212.8061 145.0962)
		(end 213.9261 146.2162)
		(width 0.2032)
		(layer "F.Cu")
		(net "NetR20_2")
	)
	(segment
		(start 226.4261 146.2162)
		(end 229.5261 143.1162)
		(width 0.2032)
		(layer "F.Cu")
		(net "NetR20_2")
	)
	(segment
		(start 217.8861 144.1762)
		(end 217.8861 142.3762)
		(width 0.2032)
		(layer "F.Cu")
		(net "NetR21_2")
	)
	(segment
		(start 217.8861 142.3762)
		(end 217.9261 142.4162)
		(width 0.2032)
		(layer "F.Cu")
		(net "NetR21_2")
	)
	(segment
		(start 219.0261 145.3162)
		(end 222.8261 145.3162)
		(width 0.2032)
		(layer "F.Cu")
		(net "NetR21_2")
	)
	(segment
		(start 222.8261 145.3162)
		(end 224.9261 143.2162)
		(width 0.2032)
		(layer "F.Cu")
		(net "NetR21_2")
	)
	(segment
		(start 217.8861 144.1762)
		(end 219.0261 145.3162)
		(width 0.2032)
		(layer "F.Cu")
		(net "NetR21_2")
	)
	(segment
		(start 195.1511 87.1536)
		(end 195.1886 87.1161)
		(width 0.2032)
		(layer "F.Cu")
		(net "SDA")
	)
	(segment
		(start 85.28867 90.58188)
		(end 85.28867 88.95363)
		(width 0.2032)
		(layer "F.Cu")
		(net "SDA")
	)
	(segment
		(start 196.3386 87.1161)
		(end 196.3761 87.0786)
		(width 0.2032)
		(layer "F.Cu")
		(net "SDA")
	)
	(segment
		(start 177.64189 99.34439)
		(end 177.64189 99.28941)
		(width 0.2032)
		(layer "F.Cu")
		(net "SDA")
	)
	(segment
		(start 179.15735 85.99364)
		(end 179.1761 86.01239)
		(width 0.2032)
		(layer "F.Cu")
		(net "SDA")
	)
	(segment
		(start 86.1261 88.1162)
		(end 87.0511 88.1162)
		(width 0.2032)
		(layer "F.Cu")
		(net "SDA")
	)
	(segment
		(start 177.64189 99.28941)
		(end 177.82573 99.10557)
		(width 0.2032)
		(layer "F.Cu")
		(net "SDA")
	)
	(segment
		(start 179.1386 84.5911)
		(end 179.15735 84.60985)
		(width 0.2032)
		(layer "F.Cu")
		(net "SDA")
	)
	(segment
		(start 179.15735 85.99364)
		(end 179.15735 84.60985)
		(width 0.2032)
		(layer "F.Cu")
		(net "SDA")
	)
	(segment
		(start 195.1886 87.1161)
		(end 196.3386 87.1161)
		(width 0.2032)
		(layer "F.Cu")
		(net "SDA")
	)
	(segment
		(start 185.8761 84.0786)
		(end 186.1261 84.3286)
		(width 0.2032)
		(layer "F.Cu")
		(net "SDA")
	)
	(segment
		(start 85.28867 88.95363)
		(end 86.1261 88.1162)
		(width 0.2032)
		(layer "F.Cu")
		(net "SDA")
	)
	(segment
		(start 186.1261 85.8161)
		(end 186.1261 84.3286)
		(width 0.2032)
		(layer "F.Cu")
		(net "SDA")
	)
	(segment
		(start 186.1261 85.8161)
		(end 186.1261 85.8161)
		(width 0.2032)
		(layer "F.Cu")
		(net "SDA")
	)
	(segment
		(start 177.82573 99.10557)
		(end 177.82573 97.91825)
		(width 0.2032)
		(layer "F.Cu")
		(net "SDA")
	)
	(segment
		(start 166.1261 89.8154)
		(end 166.1261 89.3286)
		(width 0.2032)
		(layer "F.Cu")
		(net "SDA")
	)
	(via
		(at 196.3761 87.0786)
		(size 0.4064)
		(drill 0.2032)
		(layers "F.Cu" "B.Cu")
		(tenting
			(front yes)
			(back yes)
		)
		(net "SDA")
	)
	(via
		(at 166.1261 89.8154)
		(size 0.4064)
		(drill 0.2032)
		(layers "F.Cu" "B.Cu")
		(tenting
			(front yes)
			(back yes)
		)
		(net "SDA")
	)
	(via
		(at 179.1386 84.5911)
		(size 0.4064)
		(drill 0.2032)
		(layers "F.Cu" "B.Cu")
		(tenting
			(front yes)
			(back yes)
		)
		(net "SDA")
	)
	(via
		(at 85.28867 90.58188)
		(size 0.4064)
		(drill 0.2032)
		(layers "F.Cu" "B.Cu")
		(tenting
			(front yes)
			(back yes)
		)
		(net "SDA")
	)
	(via
		(at 185.8761 84.0786)
		(size 0.4064)
		(drill 0.2032)
		(layers "F.Cu" "B.Cu")
		(tenting
			(front yes)
			(back yes)
		)
		(net "SDA")
	)
	(via
		(at 177.64189 99.34439)
		(size 0.4064)
		(drill 0.2032)
		(layers "F.Cu" "B.Cu")
		(tenting
			(front yes)
			(back yes)
		)
		(net "SDA")
	)
	(segment
		(start 189.5459 83.2484)
		(end 193.3761 87.0786)
		(width 0.2032)
		(layer "B.Cu")
		(net "SDA")
	)
	(segment
		(start 186.7063 83.2484)
		(end 189.5459 83.2484)
		(width 0.2032)
		(layer "B.Cu")
		(net "SDA")
	)
	(segment
		(start 185.8761 84.0786)
		(end 186.7063 83.2484)
		(width 0.2032)
		(layer "B.Cu")
		(net "SDA")
	)
	(segment
		(start 193.3761 87.0786)
		(end 196.3761 87.0786)
		(width 0.2032)
		(layer "B.Cu")
		(net "SDA")
	)
	(segment
		(start 166.1261 89.8154)
		(end 171.3504 84.5911)
		(width 0.2032)
		(layer "In2.Cu")
		(net "SDA")
	)
	(segment
		(start 173.3959 90.5484)
		(end 176.6011 93.7536)
		(width 0.2032)
		(layer "In2.Cu")
		(net "SDA")
	)
	(segment
		(start 176.6011 98.3036)
		(end 177.64189 99.34439)
		(width 0.2032)
		(layer "In2.Cu")
		(net "SDA")
	)
	(segment
		(start 171.3504 84.5911)
		(end 179.1386 84.5911)
		(width 0.2032)
		(layer "In2.Cu")
		(net "SDA")
	)
	(segment
		(start 166.1261 89.8154)
		(end 166.8591 90.5484)
		(width 0.2032)
		(layer "In2.Cu")
		(net "SDA")
	)
	(segment
		(start 176.6011 98.3036)
		(end 176.6011 93.7536)
		(width 0.2032)
		(layer "In2.Cu")
		(net "SDA")
	)
	(segment
		(start 166.8591 90.5484)
		(end 173.3959 90.5484)
		(width 0.2032)
		(layer "In2.Cu")
		(net "SDA")
	)
	(segment
		(start 163.6261 89.3662)
		(end 163.62987 89.36243)
		(width 0.2032)
		(layer "In3.Cu")
		(net "SDA")
	)
	(segment
		(start 130.62809 89.8662)
		(end 131.12808 89.3662)
		(width 0.2032)
		(layer "In3.Cu")
		(net "SDA")
	)
	(segment
		(start 92.2261 84.8162)
		(end 98.4861 84.8162)
		(width 0.2032)
		(layer "In3.Cu")
		(net "SDA")
	)
	(segment
		(start 165.67313 89.36243)
		(end 166.1261 89.8154)
		(width 0.2032)
		(layer "In3.Cu")
		(net "SDA")
	)
	(segment
		(start 179.1386 84.5911)
		(end 179.6511 84.0786)
		(width 0.2032)
		(layer "In3.Cu")
		(net "SDA")
	)
	(segment
		(start 84.4261 89.71931)
		(end 84.4261 88.2162)
		(width 0.2032)
		(layer "In3.Cu")
		(net "SDA")
	)
	(segment
		(start 84.4261 89.71931)
		(end 85.28867 90.58188)
		(width 0.2032)
		(layer "In3.Cu")
		(net "SDA")
	)
	(segment
		(start 179.6511 84.0786)
		(end 185.8761 84.0786)
		(width 0.2032)
		(layer "In3.Cu")
		(net "SDA")
	)
	(segment
		(start 84.4261 88.2162)
		(end 87.5261 85.1162)
		(width 0.2032)
		(layer "In3.Cu")
		(net "SDA")
	)
	(segment
		(start 86.00435 89.8662)
		(end 130.62809 89.8662)
		(width 0.2032)
		(layer "In3.Cu")
		(net "SDA")
	)
	(segment
		(start 163.62987 89.36243)
		(end 165.67313 89.36243)
		(width 0.2032)
		(layer "In3.Cu")
		(net "SDA")
	)
	(segment
		(start 131.12808 89.3662)
		(end 163.6261 89.3662)
		(width 0.2032)
		(layer "In3.Cu")
		(net "SDA")
	)
	(segment
		(start 91.9261 85.1162)
		(end 92.2261 84.8162)
		(width 0.2032)
		(layer "In3.Cu")
		(net "SDA")
	)
	(segment
		(start 87.5261 85.1162)
		(end 91.9261 85.1162)
		(width 0.2032)
		(layer "In3.Cu")
		(net "SDA")
	)
	(segment
		(start 98.4861 84.8162)
		(end 99.2861 85.6162)
		(width 0.2032)
		(layer "In3.Cu")
		(net "SDA")
	)
	(segment
		(start 85.28867 90.58188)
		(end 86.00435 89.8662)
		(width 0.2032)
		(layer "In3.Cu")
		(net "SDA")
	)
	(segment
		(start 86.1261 88.6162)
		(end 87.0511 88.6162)
		(width 0.2032)
		(layer "F.Cu")
		(net "SCL")
	)
	(segment
		(start 186.6261 85.8161)
		(end 186.6261 84.38358)
		(width 0.2032)
		(layer "F.Cu")
		(net "SCL")
	)
	(segment
		(start 179.30248 97.94162)
		(end 179.32585 97.91825)
		(width 0.2032)
		(layer "F.Cu")
		(net "SCL")
	)
	(segment
		(start 164.6261 89.3286)
		(end 164.62909 89.33159)
		(width 0.2032)
		(layer "F.Cu")
		(net "SCL")
	)
	(segment
		(start 85.8761 90.7448)
		(end 85.8761 88.8662)
		(width 0.2032)
		(layer "F.Cu")
		(net "SCL")
	)
	(segment
		(start 179.30248 99.57722)
		(end 179.30248 97.94162)
		(width 0.2032)
		(layer "F.Cu")
		(net "SCL")
	)
	(segment
		(start 186.8761 84.13358)
		(end 186.8761 84.0866)
		(width 0.2032)
		(layer "F.Cu")
		(net "SCL")
	)
	(segment
		(start 164.62909 89.87043)
		(end 164.62909 89.33159)
		(width 0.2032)
		(layer "F.Cu")
		(net "SCL")
	)
	(segment
		(start 180.8681 84.63359)
		(end 180.8681 84.5866)
		(width 0.2032)
		(layer "F.Cu")
		(net "SCL")
	)
	(segment
		(start 180.8681 84.63359)
		(end 181.0761 84.84159)
		(width 0.2032)
		(layer "F.Cu")
		(net "SCL")
	)
	(segment
		(start 196.35735 87.80985)
		(end 196.3636 87.8161)
		(width 0.2032)
		(layer "F.Cu")
		(net "SCL")
	)
	(segment
		(start 186.6261 84.38358)
		(end 186.8761 84.13358)
		(width 0.2032)
		(layer "F.Cu")
		(net "SCL")
	)
	(segment
		(start 195.1511 87.8036)
		(end 195.15735 87.80985)
		(width 0.2032)
		(layer "F.Cu")
		(net "SCL")
	)
	(segment
		(start 85.8761 88.8662)
		(end 86.1261 88.6162)
		(width 0.2032)
		(layer "F.Cu")
		(net "SCL")
	)
	(segment
		(start 179.2761 99.6036)
		(end 179.30248 99.57722)
		(width 0.2032)
		(layer "F.Cu")
		(net "SCL")
	)
	(segment
		(start 181.0761 86.01239)
		(end 181.0761 84.84159)
		(width 0.2032)
		(layer "F.Cu")
		(net "SCL")
	)
	(segment
		(start 195.15735 87.80985)
		(end 196.35735 87.80985)
		(width 0.2032)
		(layer "F.Cu")
		(net "SCL")
	)
	(via
		(at 186.8761 84.0866)
		(size 0.4064)
		(drill 0.2032)
		(layers "F.Cu" "B.Cu")
		(tenting
			(front yes)
			(back yes)
		)
		(net "SCL")
	)
	(via
		(at 180.8681 84.5866)
		(size 0.4064)
		(drill 0.2032)
		(layers "F.Cu" "B.Cu")
		(tenting
			(front yes)
			(back yes)
		)
		(net "SCL")
	)
	(via
		(at 164.62909 89.87043)
		(size 0.4064)
		(drill 0.2032)
		(layers "F.Cu" "B.Cu")
		(tenting
			(front yes)
			(back yes)
		)
		(net "SCL")
	)
	(via
		(at 85.8761 90.7448)
		(size 0.4064)
		(drill 0.2032)
		(layers "F.Cu" "B.Cu")
		(tenting
			(front yes)
			(back yes)
		)
		(net "SCL")
	)
	(via
		(at 179.2761 99.6036)
		(size 0.4064)
		(drill 0.2032)
		(layers "F.Cu" "B.Cu")
		(tenting
			(front yes)
			(back yes)
		)
		(net "SCL")
	)
	(via
		(at 196.3636 87.8161)
		(size 0.4064)
		(drill 0.2032)
		(layers "F.Cu" "B.Cu")
		(tenting
			(front yes)
			(back yes)
		)
		(net "SCL")
	)
	(segment
		(start 187.3841 83.5786)
		(end 189.1261 83.5786)
		(width 0.2032)
		(layer "B.Cu")
		(net "SCL")
	)
	(segment
		(start 196.3511 87.8286)
		(end 196.3636 87.8161)
		(width 0.2032)
		(layer "B.Cu")
		(net "SCL")
	)
	(segment
		(start 186.8761 84.0866)
		(end 187.3841 83.5786)
		(width 0.2032)
		(layer "B.Cu")
		(net "SCL")
	)
	(segment
		(start 193.3761 87.8286)
		(end 196.3511 87.8286)
		(width 0.2032)
		(layer "B.Cu")
		(net "SCL")
	)
	(segment
		(start 189.1261 83.5786)
		(end 193.3761 87.8286)
		(width 0.2032)
		(layer "B.Cu")
		(net "SCL")
	)
	(segment
		(start 176.2011 98.7036)
		(end 177.3637 99.8662)
		(width 0.2032)
		(layer "In2.Cu")
		(net "SCL")
	)
	(segment
		(start 172.9011 90.8786)
		(end 176.2011 94.1786)
		(width 0.2032)
		(layer "In2.Cu")
		(net "SCL")
	)
	(segment
		(start 176.2011 98.7036)
		(end 176.2011 94.1786)
		(width 0.2032)
		(layer "In2.Cu")
		(net "SCL")
	)
	(segment
		(start 179.0135 99.8662)
		(end 179.2761 99.6036)
		(width 0.2032)
		(layer "In2.Cu")
		(net "SCL")
	)
	(segment
		(start 164.6011 88.2036)
		(end 168.8761 83.9286)
		(width 0.2032)
		(layer "In2.Cu")
		(net "SCL")
	)
	(segment
		(start 164.6011 89.84244)
		(end 164.6011 88.2036)
		(width 0.2032)
		(layer "In2.Cu")
		(net "SCL")
	)
	(segment
		(start 177.3637 99.8662)
		(end 179.0135 99.8662)
		(width 0.2032)
		(layer "In2.Cu")
		(net "SCL")
	)
	(segment
		(start 168.8761 83.9286)
		(end 180.2101 83.9286)
		(width 0.2032)
		(layer "In2.Cu")
		(net "SCL")
	)
	(segment
		(start 165.6893 90.8786)
		(end 172.9011 90.8786)
		(width 0.2032)
		(layer "In2.Cu")
		(net "SCL")
	)
	(segment
		(start 164.6011 89.84244)
		(end 164.62909 89.87043)
		(width 0.2032)
		(layer "In2.Cu")
		(net "SCL")
	)
	(segment
		(start 180.2101 83.9286)
		(end 180.8681 84.5866)
		(width 0.2032)
		(layer "In2.Cu")
		(net "SCL")
	)
	(segment
		(start 164.6261 89.8154)
		(end 165.6893 90.8786)
		(width 0.2032)
		(layer "In2.Cu")
		(net "SCL")
	)
	(segment
		(start 83.8261 87.6662)
		(end 87.0261 84.4662)
		(width 0.2032)
		(layer "In3.Cu")
		(net "SCL")
	)
	(segment
		(start 186.3761 84.5866)
		(end 186.8761 84.0866)
		(width 0.2032)
		(layer "In3.Cu")
		(net "SCL")
	)
	(segment
		(start 91.7761 84.4662)
		(end 92.1261 84.1162)
		(width 0.2032)
		(layer "In3.Cu")
		(net "SCL")
	)
	(segment
		(start 100.3261 84.1162)
		(end 101.8261 85.6162)
		(width 0.2032)
		(layer "In3.Cu")
		(net "SCL")
	)
	(segment
		(start 83.8261 91.3162)
		(end 85.3047 91.3162)
		(width 0.2032)
		(layer "In3.Cu")
		(net "SCL")
	)
	(segment
		(start 163.18332 91.3162)
		(end 164.62909 89.87043)
		(width 0.2032)
		(layer "In3.Cu")
		(net "SCL")
	)
	(segment
		(start 85.3047 91.3162)
		(end 85.8761 90.7448)
		(width 0.2032)
		(layer "In3.Cu")
		(net "SCL")
	)
	(segment
		(start 180.8601 84.5946)
		(end 180.8681 84.5866)
		(width 0.2032)
		(layer "In3.Cu")
		(net "SCL")
	)
	(segment
		(start 110.18491 91.3162)
		(end 163.18332 91.3162)
		(width 0.2032)
		(layer "In3.Cu")
		(net "SCL")
	)
	(segment
		(start 85.8761 90.7448)
		(end 86.4245 90.1964)
		(width 0.2032)
		(layer "In3.Cu")
		(net "SCL")
	)
	(segment
		(start 180.8681 84.5866)
		(end 186.3761 84.5866)
		(width 0.2032)
		(layer "In3.Cu")
		(net "SCL")
	)
	(segment
		(start 83.8261 91.3162)
		(end 83.8261 87.6662)
		(width 0.2032)
		(layer "In3.Cu")
		(net "SCL")
	)
	(segment
		(start 92.1261 84.1162)
		(end 100.3261 84.1162)
		(width 0.2032)
		(layer "In3.Cu")
		(net "SCL")
	)
	(segment
		(start 86.4245 90.1964)
		(end 109.06511 90.1964)
		(width 0.2032)
		(layer "In3.Cu")
		(net "SCL")
	)
	(segment
		(start 87.0261 84.4662)
		(end 91.7761 84.4662)
		(width 0.2032)
		(layer "In3.Cu")
		(net "SCL")
	)
	(segment
		(start 109.06511 90.1964)
		(end 110.18491 91.3162)
		(width 0.2032)
		(layer "In3.Cu")
		(net "SCL")
	)
	(segment
		(start 209.5261 145.9162)
		(end 210.2661 145.1762)
		(width 0.2032)
		(layer "F.Cu")
		(net "NetR19_2")
	)
	(segment
		(start 210.2261 142.4162)
		(end 210.2661 142.3762)
		(width 0.2032)
		(layer "F.Cu")
		(net "NetR19_2")
	)
	(segment
		(start 210.2661 145.1762)
		(end 210.2661 142.3762)
		(width 0.2032)
		(layer "F.Cu")
		(net "NetR19_2")
	)
	(segment
		(start 202.74993 145.9162)
		(end 209.5261 145.9162)
		(width 0.2032)
		(layer "F.Cu")
		(net "NetR19_2")
	)
	(segment
		(start 200.31136 143.47763)
		(end 202.74993 145.9162)
		(width 0.2032)
		(layer "F.Cu")
		(net "NetR19_2")
	)
	(segment
		(start 205.4755 114.0202)
		(end 206.8695 112.6262)
		(width 0.2032)
		(layer "F.Cu")
		(net "NetR2_1")
	)
	(segment
		(start 206.8695 112.6262)
		(end 206.8695 111.9262)
		(width 0.2032)
		(layer "F.Cu")
		(net "NetR2_1")
	)
	(segment
		(start 204.1305 114.0202)
		(end 205.4755 114.0202)
		(width 0.2032)
		(layer "F.Cu")
		(net "NetR2_1")
	)
	(segment
		(start 221.5511 86.7162)
		(end 221.5537 86.7162)
		(width 0.508)
		(layer "F.Cu")
		(net "NetD4_1")
	)
	(segment
		(start 221.5537 86.7162)
		(end 221.5537 85.1662)
		(width 0.508)
		(layer "F.Cu")
		(net "NetD4_1")
	)
	(segment
		(start 124.54608 157.7576)
		(end 124.5791 157.72458)
		(width 0.2032)
		(layer "B.Cu")
		(net "NetC49_1")
	)
	(segment
		(start 124.5791 156.9506)
		(end 124.5791 152.2186)
		(width 0.127)
		(layer "B.Cu")
		(net "NetC49_1")
	)
	(arc
		(start 124.5791 156.9506)
		(mid 124.565321 157.019873)
		(end 124.52608 157.0786)
		(width 0.127)
		(layer "B.Cu")
		(net "NetC49_1")
	)
	(arc
		(start 124.5791 157.67788)
		(mid 124.570518 157.721024)
		(end 124.546079 157.757599)
		(width 0.127)
		(layer "B.Cu")
		(net "NetC49_1")
	)
	(segment
		(start 206.7637 84.2662)
		(end 206.9637 84.0662)
		(width 0.2032)
		(layer "F.Cu")
		(net "NetC22_2")
	)
	(segment
		(start 206.9637 84.0662)
		(end 206.9637 83.4592)
		(width 0.2032)
		(layer "F.Cu")
		(net "NetC22_2")
	)
	(segment
		(start 206.0637 84.2662)
		(end 206.7637 84.2662)
		(width 0.2032)
		(layer "F.Cu")
		(net "NetC22_2")
	)
	(segment
		(start 205.8267 84.5032)
		(end 206.0637 84.2662)
		(width 0.2032)
		(layer "F.Cu")
		(net "NetC22_2")
	)
	(segment
		(start 205.8267 85.7642)
		(end 205.8267 84.5032)
		(width 0.2032)
		(layer "F.Cu")
		(net "NetC22_2")
	)
	(segment
		(start 206.9637 83.4592)
		(end 207.0097 83.4132)
		(width 0.2032)
		(layer "F.Cu")
		(net "NetC22_2")
	)
	(segment
		(start 205.6597 83.4132)
		(end 205.6597 81.8802)
		(width 0.2032)
		(layer "F.Cu")
		(net "NetC22_1")
	)
	(segment
		(start 205.8267 83.4912)
		(end 205.9047 83.4132)
		(width 0.2032)
		(layer "F.Cu")
		(net "NetC22_1")
	)
	(segment
		(start 205.6597 81.8802)
		(end 205.6737 81.8662)
		(width 0.2032)
		(layer "F.Cu")
		(net "NetC22_1")
	)
	(segment
		(start 201.5087 85.7372)
		(end 203.25969 85.7372)
		(width 0.2032)
		(layer "F.Cu")
		(net "NetC21_2")
	)
	(segment
		(start 203.25969 85.7372)
		(end 203.2867 85.7642)
		(width 0.2032)
		(layer "F.Cu")
		(net "NetC21_2")
	)
	(segment
		(start 208.1395 111.9262)
		(end 208.1395 110.5152)
		(width 0.2032)
		(layer "F.Cu")
		(net "NetC20_2")
	)
	(segment
		(start 209.0885 110.2662)
		(end 209.3885 109.9662)
		(width 0.2032)
		(layer "F.Cu")
		(net "NetC20_2")
	)
	(segment
		(start 208.3885 110.2662)
		(end 209.0885 110.2662)
		(width 0.2032)
		(layer "F.Cu")
		(net "NetC20_2")
	)
	(segment
		(start 209.3885 109.9662)
		(end 209.3885 109.2552)
		(width 0.2032)
		(layer "F.Cu")
		(net "NetC20_2")
	)
	(segment
		(start 208.1395 110.5152)
		(end 208.3885 110.2662)
		(width 0.2032)
		(layer "F.Cu")
		(net "NetC20_2")
	)
	(segment
		(start 209.3885 109.2552)
		(end 209.4495 109.1942)
		(width 0.2032)
		(layer "F.Cu")
		(net "NetC20_2")
	)
	(segment
		(start 208.0985 107.6662)
		(end 208.0995 107.6672)
		(width 0.2032)
		(layer "F.Cu")
		(net "NetC20_1")
	)
	(segment
		(start 208.0995 109.1942)
		(end 208.0995 107.6672)
		(width 0.2032)
		(layer "F.Cu")
		(net "NetC20_1")
	)
	(segment
		(start 208.1395 109.3992)
		(end 208.3445 109.1942)
		(width 0.2032)
		(layer "F.Cu")
		(net "NetC20_1")
	)
	(segment
		(start 205.5995 111.9262)
		(end 205.5995 111.8286)
		(width 0.2032)
		(layer "F.Cu")
		(net "NetC19_2")
	)
	(segment
		(start 203.9485 111.6452)
		(end 205.4161 111.6452)
		(width 0.2032)
		(layer "F.Cu")
		(net "NetC19_2")
	)
	(segment
		(start 205.4161 111.6452)
		(end 205.5995 111.8286)
		(width 0.2032)
		(layer "F.Cu")
		(net "NetC19_2")
	)
	(segment
		(start 207.5425 119.8622)
		(end 208.1395 119.2652)
		(width 0.508)
		(layer "F.Cu")
		(net "NetC4_2")
	)
	(segment
		(start 207.5425 122.0832)
		(end 207.5425 119.8622)
		(width 0.508)
		(layer "F.Cu")
		(net "NetC4_2")
	)
	(segment
		(start 207.5425 122.0832)
		(end 210.4015 124.9422)
		(width 0.508)
		(layer "F.Cu")
		(net "NetC4_2")
	)
	(segment
		(start 208.1395 119.2652)
		(end 208.1395 116.8762)
		(width 0.508)
		(layer "F.Cu")
		(net "NetC4_2")
	)
	(segment
		(start 205.5995 119.5192)
		(end 205.9425 119.8622)
		(width 0.2032)
		(layer "F.Cu")
		(net "NetC4_1")
	)
	(segment
		(start 205.5995 119.5192)
		(end 205.5995 116.8762)
		(width 0.2032)
		(layer "F.Cu")
		(net "NetC4_1")
	)
	(segment
		(start 203.5261 95.0162)
		(end 205.8267 92.7156)
		(width 0.508)
		(layer "F.Cu")
		(net "NetC3_2")
	)
	(segment
		(start 202.4261 96.6162)
		(end 202.4261 95.0162)
		(width 0.508)
		(layer "F.Cu")
		(net "NetC3_2")
	)
	(segment
		(start 202.4261 95.0162)
		(end 203.5261 95.0162)
		(width 0.508)
		(layer "F.Cu")
		(net "NetC3_2")
	)
	(segment
		(start 202.4261 96.6162)
		(end 205.0261 99.2162)
		(width 0.508)
		(layer "F.Cu")
		(net "NetC3_2")
	)
	(segment
		(start 205.8267 92.7156)
		(end 205.8267 90.7142)
		(width 0.508)
		(layer "F.Cu")
		(net "NetC3_2")
	)
	(segment
		(start 205.0261 99.2162)
		(end 206.0761 99.2162)
		(width 0.508)
		(layer "F.Cu")
		(net "NetC3_2")
	)
	(segment
		(start 202.4261 93.4162)
		(end 203.2867 92.5556)
		(width 0.254)
		(layer "F.Cu")
		(net "NetC3_1")
	)
	(segment
		(start 203.2867 92.5556)
		(end 203.2867 90.7142)
		(width 0.254)
		(layer "F.Cu")
		(net "NetC3_1")
	)
	(segment
		(start 164.32588 93.86847)
		(end 164.32588 92.00382)
		(width 0.2032)
		(layer "F.Cu")
		(net "MAC_USB_PWR")
	)
	(segment
		(start 164.32588 92.00382)
		(end 164.36242 91.96728)
		(width 0.2032)
		(layer "F.Cu")
		(net "MAC_USB_PWR")
	)
	(segment
		(start 142.94998 113.94092)
		(end 143.1936 113.6973)
		(width 0.2032)
		(layer "F.Cu")
		(net "MAC_USB_PWR")
	)
	(segment
		(start 141.66107 113.94092)
		(end 142.94998 113.94092)
		(width 0.2032)
		(layer "F.Cu")
		(net "MAC_USB_PWR")
	)
	(via
		(at 143.1936 113.6973)
		(size 0.4064)
		(drill 0.2032)
		(layers "F.Cu" "B.Cu")
		(net "MAC_USB_PWR")
	)
	(via
		(at 157.6181 106.1162)
		(size 0.4064)
		(drill 0.2032)
		(layers "F.Cu" "B.Cu")
		(tenting
			(front yes)
			(back yes)
		)
		(net "MAC_USB_PWR")
	)
	(via
		(at 164.36242 91.96728)
		(size 0.4064)
		(drill 0.2032)
		(layers "F.Cu" "B.Cu")
		(tenting
			(front yes)
			(back yes)
		)
		(net "MAC_USB_PWR")
	)
	(segment
		(start 141.2261 113.1162)
		(end 141.80719 113.6973)
		(width 0.2032)
		(layer "B.Cu")
		(net "MAC_USB_PWR")
	)
	(segment
		(start 144.9261 105.9162)
		(end 157.4181 105.9162)
		(width 0.2032)
		(layer "B.Cu")
		(net "MAC_USB_PWR")
	)
	(segment
		(start 141.2261 113.1162)
		(end 141.2261 109.6162)
		(width 0.2032)
		(layer "B.Cu")
		(net "MAC_USB_PWR")
	)
	(segment
		(start 141.2261 109.6162)
		(end 144.9261 105.9162)
		(width 0.2032)
		(layer "B.Cu")
		(net "MAC_USB_PWR")
	)
	(segment
		(start 141.80719 113.6973)
		(end 143.1936 113.6973)
		(width 0.2032)
		(layer "B.Cu")
		(net "MAC_USB_PWR")
	)
	(segment
		(start 157.4181 105.9162)
		(end 157.6181 106.1162)
		(width 0.2032)
		(layer "B.Cu")
		(net "MAC_USB_PWR")
	)
	(segment
		(start 157.6261 106.1082)
		(end 157.6261 96.5786)
		(width 0.2032)
		(layer "In2.Cu")
		(net "MAC_USB_PWR")
	)
	(segment
		(start 157.6181 106.1162)
		(end 157.6261 106.1082)
		(width 0.2032)
		(layer "In2.Cu")
		(net "MAC_USB_PWR")
	)
	(segment
		(start 157.6261 96.5786)
		(end 162.23742 91.96728)
		(width 0.2032)
		(layer "In2.Cu")
		(net "MAC_USB_PWR")
	)
	(segment
		(start 162.23742 91.96728)
		(end 164.36242 91.96728)
		(width 0.2032)
		(layer "In2.Cu")
		(net "MAC_USB_PWR")
	)
	(segment
		(start 142.69631 113.43292)
		(end 143.10167 113.02755)
		(width 0.2032)
		(layer "F.Cu")
		(net "MAC_USB-")
	)
	(segment
		(start 141.66107 113.43292)
		(end 142.69631 113.43292)
		(width 0.2032)
		(layer "F.Cu")
		(net "MAC_USB-")
	)
	(segment
		(start 181.06552 92.35601)
		(end 181.06552 92.30102)
		(width 0.2032)
		(layer "F.Cu")
		(net "MAC_USB-")
	)
	(segment
		(start 180.82572 93.86847)
		(end 180.82572 92.5958)
		(width 0.2032)
		(layer "F.Cu")
		(net "MAC_USB-")
	)
	(segment
		(start 180.82572 92.5958)
		(end 181.06552 92.35601)
		(width 0.2032)
		(layer "F.Cu")
		(net "MAC_USB-")
	)
	(via
		(at 181.06552 92.30102)
		(size 0.4064)
		(drill 0.2032)
		(layers "F.Cu" "B.Cu")
		(tenting
			(front yes)
			(back yes)
		)
		(net "MAC_USB-")
	)
	(via
		(at 143.10167 113.02755)
		(size 0.4064)
		(drill 0.2032)
		(layers "F.Cu" "B.Cu")
		(net "MAC_USB-")
	)
	(via
		(at 159.1181 106.8662)
		(size 0.4064)
		(drill 0.2032)
		(layers "F.Cu" "B.Cu")
		(tenting
			(front yes)
			(back yes)
		)
		(net "MAC_USB-")
	)
	(segment
		(start 144.8661 108.6162)
		(end 157.3681 108.6162)
		(width 0.2032)
		(layer "B.Cu")
		(net "MAC_USB-")
	)
	(segment
		(start 142.3261 112.25197)
		(end 142.3261 111.1562)
		(width 0.2032)
		(layer "B.Cu")
		(net "MAC_USB-")
	)
	(segment
		(start 181.06552 92.30102)
		(end 181.09581 92.33131)
		(width 0.2032)
		(layer "B.Cu")
		(net "MAC_USB-")
	)
	(arc
		(start 142.3261 111.1562)
		(mid 143.070049 109.360149)
		(end 144.8661 108.6162)
		(width 0.2032)
		(layer "B.Cu")
		(net "MAC_USB-")
	)
	(arc
		(start 159.1181 106.8662)
		(mid 158.605537 108.103637)
		(end 157.3681 108.6162)
		(width 0.2032)
		(layer "B.Cu")
		(net "MAC_USB-")
	)
	(arc
		(start 143.10167 113.02755)
		(mid 142.553252 112.800388)
		(end 142.32609 112.25197)
		(width 0.2032)
		(layer "B.Cu")
		(net "MAC_USB-")
	)
	(segment
		(start 159.1181 106.8662)
		(end 177.0885 106.8662)
		(width 0.2032)
		(layer "In2.Cu")
		(net "MAC_USB-")
	)
	(segment
		(start 177.0885 106.8662)
		(end 181.06552 102.88918)
		(width 0.2032)
		(layer "In2.Cu")
		(net "MAC_USB-")
	)
	(segment
		(start 181.06552 102.88918)
		(end 181.06552 92.30102)
		(width 0.2032)
		(layer "In2.Cu")
		(net "MAC_USB-")
	)
	(segment
		(start 142.39667 112.92492)
		(end 143.00975 112.31184)
		(width 0.2032)
		(layer "F.Cu")
		(net "MAC_USB+")
	)
	(segment
		(start 180.3011 91.6286)
		(end 180.31348 91.64098)
		(width 0.2032)
		(layer "F.Cu")
		(net "MAC_USB+")
	)
	(segment
		(start 180.31348 93.8561)
		(end 180.31348 91.64098)
		(width 0.2032)
		(layer "F.Cu")
		(net "MAC_USB+")
	)
	(segment
		(start 180.31348 93.8561)
		(end 180.32585 93.86847)
		(width 0.2032)
		(layer "F.Cu")
		(net "MAC_USB+")
	)
	(segment
		(start 141.66107 112.92492)
		(end 142.39667 112.92492)
		(width 0.2032)
		(layer "F.Cu")
		(net "MAC_USB+")
	)
	(via
		(at 180.3011 91.6286)
		(size 0.4064)
		(drill 0.2032)
		(layers "F.Cu" "B.Cu")
		(tenting
			(front yes)
			(back yes)
		)
		(net "MAC_USB+")
	)
	(via
		(at 143.00975 112.31184)
		(size 0.4064)
		(drill 0.2032)
		(layers "F.Cu" "B.Cu")
		(net "MAC_USB+")
	)
	(via
		(at 159.6261 106.3582)
		(size 0.4064)
		(drill 0.2032)
		(layers "F.Cu" "B.Cu")
		(tenting
			(front yes)
			(back yes)
		)
		(net "MAC_USB+")
	)
	(segment
		(start 143.00975 112.31184)
		(end 143.00975 111.13255)
		(width 0.2032)
		(layer "B.Cu")
		(net "MAC_USB+")
	)
	(segment
		(start 159.6261 106.5762)
		(end 159.6261 106.3582)
		(width 0.2032)
		(layer "B.Cu")
		(net "MAC_USB+")
	)
	(segment
		(start 145.0261 109.1162)
		(end 157.0861 109.1162)
		(width 0.2032)
		(layer "B.Cu")
		(net "MAC_USB+")
	)
	(arc
		(start 143.00975 111.13255)
		(mid 143.600325 109.706775)
		(end 145.0261 109.1162)
		(width 0.2032)
		(layer "B.Cu")
		(net "MAC_USB+")
	)
	(arc
		(start 159.6261 106.5762)
		(mid 158.882151 108.372251)
		(end 157.0861 109.1162)
		(width 0.2032)
		(layer "B.Cu")
		(net "MAC_USB+")
	)
	(segment
		(start 176.8965 106.3582)
		(end 180.3011 102.9536)
		(width 0.2032)
		(layer "In2.Cu")
		(net "MAC_USB+")
	)
	(segment
		(start 159.6261 106.3582)
		(end 176.8965 106.3582)
		(width 0.2032)
		(layer "In2.Cu")
		(net "MAC_USB+")
	)
	(segment
		(start 180.3011 102.9536)
		(end 180.3011 91.6286)
		(width 0.2032)
		(layer "In2.Cu")
		(net "MAC_USB+")
	)
	(segment
		(start 168.82132 93.86405)
		(end 168.82575 93.86847)
		(width 0.2032)
		(layer "F.Cu")
		(net "MAC_TX")
	)
	(segment
		(start 168.81689 91.73781)
		(end 168.82132 91.74224)
		(width 0.2032)
		(layer "F.Cu")
		(net "MAC_TX")
	)
	(segment
		(start 168.82132 93.86405)
		(end 168.82132 91.74224)
		(width 0.2032)
		(layer "F.Cu")
		(net "MAC_TX")
	)
	(via
		(at 167.7261 105.1162)
		(size 0.4064)
		(drill 0.2032)
		(layers "F.Cu" "B.Cu")
		(net "MAC_TX")
	)
	(via
		(at 168.81689 91.73781)
		(size 0.4064)
		(drill 0.2032)
		(layers "F.Cu" "B.Cu")
		(tenting
			(front yes)
			(back yes)
		)
		(net "MAC_TX")
	)
	(segment
		(start 168.81689 92.90699)
		(end 170.7261 94.8162)
		(width 0.2032)
		(layer "In2.Cu")
		(net "MAC_TX")
	)
	(segment
		(start 170.7261 97.58634)
		(end 172.0924 98.95264)
		(width 0.2032)
		(layer "In2.Cu")
		(net "MAC_TX")
	)
	(segment
		(start 167.7261 105.1162)
		(end 172.0924 100.7499)
		(width 0.2032)
		(layer "In2.Cu")
		(net "MAC_TX")
	)
	(segment
		(start 172.0924 100.7499)
		(end 172.0924 98.95264)
		(width 0.2032)
		(layer "In2.Cu")
		(net "MAC_TX")
	)
	(segment
		(start 170.7261 97.58634)
		(end 170.7261 94.8162)
		(width 0.2032)
		(layer "In2.Cu")
		(net "MAC_TX")
	)
	(segment
		(start 168.81689 92.90699)
		(end 168.81689 91.73781)
		(width 0.2032)
		(layer "In2.Cu")
		(net "MAC_TX")
	)
	(segment
		(start 131.8261 138.2162)
		(end 143.5261 126.5162)
		(width 0.2032)
		(layer "In3.Cu")
		(net "MAC_TX")
	)
	(segment
		(start 167.7261 114.9162)
		(end 167.7261 105.1162)
		(width 0.2032)
		(layer "In3.Cu")
		(net "MAC_TX")
	)
	(segment
		(start 143.5261 126.5162)
		(end 156.1261 126.5162)
		(width 0.2032)
		(layer "In3.Cu")
		(net "MAC_TX")
	)
	(segment
		(start 156.1261 126.5162)
		(end 167.7261 114.9162)
		(width 0.2032)
		(layer "In3.Cu")
		(net "MAC_TX")
	)
	(segment
		(start 169.32587 93.86847)
		(end 169.32587 91.98382)
		(width 0.2032)
		(layer "F.Cu")
		(net "MAC_RX")
	)
	(segment
		(start 169.5261 91.78359)
		(end 169.5261 91.7286)
		(width 0.2032)
		(layer "F.Cu")
		(net "MAC_RX")
	)
	(segment
		(start 169.32587 91.98382)
		(end 169.5261 91.78359)
		(width 0.2032)
		(layer "F.Cu")
		(net "MAC_RX")
	)
	(via
		(at 169.00212 105.04772)
		(size 0.4064)
		(drill 0.2032)
		(layers "F.Cu" "B.Cu")
		(net "MAC_RX")
	)
	(via
		(at 169.5261 91.7286)
		(size 0.4064)
		(drill 0.2032)
		(layers "F.Cu" "B.Cu")
		(tenting
			(front yes)
			(back yes)
		)
		(net "MAC_RX")
	)
	(segment
		(start 173.43364 100.6162)
		(end 174.7261 100.6162)
		(width 0.2032)
		(layer "In2.Cu")
		(net "MAC_RX")
	)
	(segment
		(start 169.5261 91.7286)
		(end 170.3011 91.7286)
		(width 0.2032)
		(layer "In2.Cu")
		(net "MAC_RX")
	)
	(segment
		(start 175.0261 100.3162)
		(end 175.0261 97.9162)
		(width 0.2032)
		(layer "In2.Cu")
		(net "MAC_RX")
	)
	(segment
		(start 174.7261 100.6162)
		(end 175.0261 100.3162)
		(width 0.2032)
		(layer "In2.Cu")
		(net "MAC_RX")
	)
	(segment
		(start 173.5261 96.4162)
		(end 173.5261 94.9536)
		(width 0.2032)
		(layer "In2.Cu")
		(net "MAC_RX")
	)
	(segment
		(start 173.5261 96.4162)
		(end 175.0261 97.9162)
		(width 0.2032)
		(layer "In2.Cu")
		(net "MAC_RX")
	)
	(segment
		(start 170.3011 91.7286)
		(end 173.5261 94.9536)
		(width 0.2032)
		(layer "In2.Cu")
		(net "MAC_RX")
	)
	(segment
		(start 169.00212 105.04772)
		(end 173.43364 100.6162)
		(width 0.2032)
		(layer "In2.Cu")
		(net "MAC_RX")
	)
	(segment
		(start 169.0261 115.3162)
		(end 169.0261 105.07171)
		(width 0.2032)
		(layer "In3.Cu")
		(net "MAC_RX")
	)
	(segment
		(start 134.8261 138.2162)
		(end 145.2261 127.8162)
		(width 0.2032)
		(layer "In3.Cu")
		(net "MAC_RX")
	)
	(segment
		(start 156.5261 127.8162)
		(end 169.0261 115.3162)
		(width 0.2032)
		(layer "In3.Cu")
		(net "MAC_RX")
	)
	(segment
		(start 145.2261 127.8162)
		(end 156.5261 127.8162)
		(width 0.2032)
		(layer "In3.Cu")
		(net "MAC_RX")
	)
	(segment
		(start 169.00212 105.04772)
		(end 169.0261 105.07171)
		(width 0.2032)
		(layer "In3.Cu")
		(net "MAC_RX")
	)
	(segment
		(start 136.3261 118.0162)
		(end 136.84539 117.49692)
		(width 0.2032)
		(layer "F.Cu")
		(net "MAC_PPS_OUT-")
	)
	(segment
		(start 136.84539 117.49692)
		(end 137.66107 117.49692)
		(width 0.2032)
		(layer "F.Cu")
		(net "MAC_PPS_OUT-")
	)
	(segment
		(start 113.94853 84.1736)
		(end 116.2761 84.1736)
		(width 0.2032)
		(layer "F.Cu")
		(net "MAC_PPS_OUT-")
	)
	(segment
		(start 112.3761 84.3286)
		(end 113.7511 84.3286)
		(width 0.2032)
		(layer "F.Cu")
		(net "MAC_PPS_OUT-")
	)
	(segment
		(start 113.7511 84.3286)
		(end 113.8761 84.2036)
		(width 0.2032)
		(layer "F.Cu")
		(net "MAC_PPS_OUT-")
	)
	(via
		(at 136.3261 118.0162)
		(size 0.4064)
		(drill 0.2032)
		(layers "F.Cu" "B.Cu")
		(tenting
			(front yes)
			(back yes)
		)
		(net "MAC_PPS_OUT-")
	)
	(via
		(at 112.3761 84.3286)
		(size 0.4064)
		(drill 0.2032)
		(layers "F.Cu" "B.Cu")
		(tenting
			(front yes)
			(back yes)
		)
		(net "MAC_PPS_OUT-")
	)
	(arc
		(start 113.876101 84.203591)
		(mid 113.876187 84.203505)
		(end 113.876274 84.203419)
		(width 0.2032)
		(layer "F.Cu")
		(net "MAC_PPS_OUT-")
	)
	(arc
		(start 113.876274 84.203419)
		(mid 113.909445 84.181341)
		(end 113.94853 84.17359)
		(width 0.2032)
		(layer "F.Cu")
		(net "MAC_PPS_OUT-")
	)
	(segment
		(start 111.9261 98.26409)
		(end 111.9261 84.7786)
		(width 0.2032)
		(layer "In2.Cu")
		(net "MAC_PPS_OUT-")
	)
	(segment
		(start 131.5782 117.9162)
		(end 136.08467 117.9162)
		(width 0.2032)
		(layer "In2.Cu")
		(net "MAC_PPS_OUT-")
	)
	(segment
		(start 112.67005 100.06015)
		(end 129.78215 117.17225)
		(width 0.2032)
		(layer "In2.Cu")
		(net "MAC_PPS_OUT-")
	)
	(arc
		(start 112.670049 100.060141)
		(mid 112.119446 99.236106)
		(end 111.9261 98.26409)
		(width 0.2032)
		(layer "In2.Cu")
		(net "MAC_PPS_OUT-")
	)
	(arc
		(start 136.08467 117.9162)
		(mid 136.21533 117.94219)
		(end 136.326097 118.016203)
		(width 0.2032)
		(layer "In2.Cu")
		(net "MAC_PPS_OUT-")
	)
	(arc
		(start 111.9261 84.7786)
		(mid 112.057902 84.460402)
		(end 112.3761 84.3286)
		(width 0.2032)
		(layer "In2.Cu")
		(net "MAC_PPS_OUT-")
	)
	(arc
		(start 131.5782 117.9162)
		(mid 130.606184 117.722854)
		(end 129.782149 117.172251)
		(width 0.2032)
		(layer "In2.Cu")
		(net "MAC_PPS_OUT-")
	)
	(segment
		(start 113.7511 85.5786)
		(end 113.8761 85.4536)
		(width 0.2032)
		(layer "F.Cu")
		(net "MAC_PPS_OUT+")
	)
	(segment
		(start 113.90024 85.4436)
		(end 116.2761 85.4436)
		(width 0.2032)
		(layer "F.Cu")
		(net "MAC_PPS_OUT+")
	)
	(segment
		(start 136.29263 117.37033)
		(end 136.67404 116.98892)
		(width 0.2032)
		(layer "F.Cu")
		(net "MAC_PPS_OUT+")
	)
	(segment
		(start 136.67404 116.98892)
		(end 137.66107 116.98892)
		(width 0.2032)
		(layer "F.Cu")
		(net "MAC_PPS_OUT+")
	)
	(segment
		(start 112.3761 85.5786)
		(end 113.7511 85.5786)
		(width 0.2032)
		(layer "F.Cu")
		(net "MAC_PPS_OUT+")
	)
	(via
		(at 136.29263 117.37033)
		(size 0.4064)
		(drill 0.2032)
		(layers "F.Cu" "B.Cu")
		(tenting
			(front yes)
			(back yes)
		)
		(net "MAC_PPS_OUT+")
	)
	(via
		(at 112.3761 85.5786)
		(size 0.4064)
		(drill 0.2032)
		(layers "F.Cu" "B.Cu")
		(tenting
			(front yes)
			(back yes)
		)
		(net "MAC_PPS_OUT+")
	)
	(arc
		(start 113.876099 85.453599)
		(mid 113.887175 85.446198)
		(end 113.90024 85.443599)
		(width 0.2032)
		(layer "F.Cu")
		(net "MAC_PPS_OUT+")
	)
	(segment
		(start 112.3761 98.1141)
		(end 112.3761 85.5786)
		(width 0.2032)
		(layer "In2.Cu")
		(net "MAC_PPS_OUT+")
	)
	(segment
		(start 131.63233 117.37033)
		(end 136.29263 117.37033)
		(width 0.2032)
		(layer "In2.Cu")
		(net "MAC_PPS_OUT+")
	)
	(segment
		(start 113.12005 99.91015)
		(end 129.83628 116.62638)
		(width 0.2032)
		(layer "In2.Cu")
		(net "MAC_PPS_OUT+")
	)
	(arc
		(start 113.120049 99.910151)
		(mid 112.569446 99.086116)
		(end 112.3761 98.1141)
		(width 0.2032)
		(layer "In2.Cu")
		(net "MAC_PPS_OUT+")
	)
	(arc
		(start 131.63233 117.37033)
		(mid 130.660314 117.176984)
		(end 129.836279 116.626381)
		(width 0.2032)
		(layer "In2.Cu")
		(net "MAC_PPS_OUT+")
	)
	(segment
		(start 136.93482 112.92492)
		(end 137.66107 112.92492)
		(width 0.2032)
		(layer "F.Cu")
		(net "MAC_PPS_IN1+")
	)
	(segment
		(start 136.4261 112.4162)
		(end 136.93482 112.92492)
		(width 0.2032)
		(layer "F.Cu")
		(net "MAC_PPS_IN1+")
	)
	(segment
		(start 138.9261 85.3286)
		(end 143.1261 85.3286)
		(width 0.2032)
		(layer "F.Cu")
		(net "MAC_PPS_IN1+")
	)
	(via
		(at 143.1261 85.3286)
		(size 0.4064)
		(drill 0.2032)
		(layers "F.Cu" "B.Cu")
		(tenting
			(front yes)
			(back yes)
		)
		(net "MAC_PPS_IN1+")
	)
	(via
		(at 136.4261 112.4162)
		(size 0.4064)
		(drill 0.2032)
		(layers "F.Cu" "B.Cu")
		(tenting
			(front yes)
			(back yes)
		)
		(net "MAC_PPS_IN1+")
	)
	(segment
		(start 136.4261 112.4162)
		(end 138.9861 112.4162)
		(width 0.2032)
		(layer "In2.Cu")
		(net "MAC_PPS_IN1+")
	)
	(segment
		(start 141.5261 109.8762)
		(end 141.5261 90.0162)
		(width 0.2032)
		(layer "In2.Cu")
		(net "MAC_PPS_IN1+")
	)
	(segment
		(start 143.1261 88.4162)
		(end 143.1261 85.3286)
		(width 0.2032)
		(layer "In2.Cu")
		(net "MAC_PPS_IN1+")
	)
	(arc
		(start 141.5261 90.0162)
		(mid 141.731125 89.521225)
		(end 142.2261 89.3162)
		(width 0.2032)
		(layer "In2.Cu")
		(net "MAC_PPS_IN1+")
	)
	(arc
		(start 141.5261 109.8762)
		(mid 140.782151 111.672251)
		(end 138.9861 112.4162)
		(width 0.2032)
		(layer "In2.Cu")
		(net "MAC_PPS_IN1+")
	)
	(arc
		(start 143.1261 88.4162)
		(mid 142.862496 89.052596)
		(end 142.2261 89.3162)
		(width 0.2032)
		(layer "In2.Cu")
		(net "MAC_PPS_IN1+")
	)
	(segment
		(start 141.0065 87.8536)
		(end 141.0645 87.7956)
		(width 0.2032)
		(layer "F.Cu")
		(net "MAC_PPS_IN0-")
	)
	(segment
		(start 138.9411 87.8536)
		(end 141.0065 87.8536)
		(width 0.2032)
		(layer "F.Cu")
		(net "MAC_PPS_IN0-")
	)
	(segment
		(start 141.0645 87.7956)
		(end 141.6161 87.7956)
		(width 0.2032)
		(layer "F.Cu")
		(net "MAC_PPS_IN0-")
	)
	(segment
		(start 138.9261 87.8686)
		(end 138.9411 87.8536)
		(width 0.2032)
		(layer "F.Cu")
		(net "MAC_PPS_IN0-")
	)
	(segment
		(start 136.29261 114.41957)
		(end 136.32195 114.44892)
		(width 0.2032)
		(layer "F.Cu")
		(net "MAC_PPS_IN0-")
	)
	(segment
		(start 136.32195 114.44892)
		(end 137.66107 114.44892)
		(width 0.2032)
		(layer "F.Cu")
		(net "MAC_PPS_IN0-")
	)
	(via
		(at 136.29261 114.41957)
		(size 0.4064)
		(drill 0.2032)
		(layers "F.Cu" "B.Cu")
		(tenting
			(front yes)
			(back yes)
		)
		(net "MAC_PPS_IN0-")
	)
	(via
		(at 141.6161 87.7956)
		(size 0.4064)
		(drill 0.2032)
		(layers "F.Cu" "B.Cu")
		(tenting
			(front yes)
			(back yes)
		)
		(net "MAC_PPS_IN0-")
	)
	(segment
		(start 135.22947 114.41957)
		(end 136.29261 114.41957)
		(width 0.2032)
		(layer "In2.Cu")
		(net "MAC_PPS_IN0-")
	)
	(segment
		(start 134.4261 113.6162)
		(end 134.4261 90.3356)
		(width 0.2032)
		(layer "In2.Cu")
		(net "MAC_PPS_IN0-")
	)
	(segment
		(start 136.9661 87.7956)
		(end 141.6161 87.7956)
		(width 0.2032)
		(layer "In2.Cu")
		(net "MAC_PPS_IN0-")
	)
	(arc
		(start 135.22947 114.41957)
		(mid 134.661402 114.184268)
		(end 134.4261 113.6162)
		(width 0.2032)
		(layer "In2.Cu")
		(net "MAC_PPS_IN0-")
	)
	(arc
		(start 134.4261 90.3356)
		(mid 135.170049 88.539549)
		(end 136.9661 87.7956)
		(width 0.2032)
		(layer "In2.Cu")
		(net "MAC_PPS_IN0-")
	)
	(segment
		(start 141.6161 86.5886)
		(end 141.6261 86.5786)
		(width 0.2032)
		(layer "F.Cu")
		(net "MAC_PPS_IN0+")
	)
	(segment
		(start 138.9261 86.5986)
		(end 138.9361 86.5886)
		(width 0.2032)
		(layer "F.Cu")
		(net "MAC_PPS_IN0+")
	)
	(segment
		(start 136.45082 113.94092)
		(end 137.66107 113.94092)
		(width 0.2032)
		(layer "F.Cu")
		(net "MAC_PPS_IN0+")
	)
	(segment
		(start 136.3261 113.8162)
		(end 136.45082 113.94092)
		(width 0.2032)
		(layer "F.Cu")
		(net "MAC_PPS_IN0+")
	)
	(segment
		(start 138.9361 86.5886)
		(end 141.6161 86.5886)
		(width 0.2032)
		(layer "F.Cu")
		(net "MAC_PPS_IN0+")
	)
	(via
		(at 141.6261 86.5786)
		(size 0.4064)
		(drill 0.2032)
		(layers "F.Cu" "B.Cu")
		(tenting
			(front yes)
			(back yes)
		)
		(net "MAC_PPS_IN0+")
	)
	(via
		(at 136.3261 113.8162)
		(size 0.4064)
		(drill 0.2032)
		(layers "F.Cu" "B.Cu")
		(tenting
			(front yes)
			(back yes)
		)
		(net "MAC_PPS_IN0+")
	)
	(segment
		(start 135.9261 113.8162)
		(end 136.3261 113.8162)
		(width 0.2032)
		(layer "In2.Cu")
		(net "MAC_PPS_IN0+")
	)
	(segment
		(start 137.44621 88.4162)
		(end 142.1261 88.4162)
		(width 0.2032)
		(layer "In2.Cu")
		(net "MAC_PPS_IN0+")
	)
	(segment
		(start 134.9261 112.8162)
		(end 134.9261 90.94845)
		(width 0.2032)
		(layer "In2.Cu")
		(net "MAC_PPS_IN0+")
	)
	(segment
		(start 142.4261 88.1162)
		(end 142.4261 87.37859)
		(width 0.2032)
		(layer "In2.Cu")
		(net "MAC_PPS_IN0+")
	)
	(segment
		(start 137.44621 88.42834)
		(end 137.44621 88.4162)
		(width 0.2032)
		(layer "In2.Cu")
		(net "MAC_PPS_IN0+")
	)
	(arc
		(start 135.9261 113.8162)
		(mid 135.218993 113.523307)
		(end 134.9261 112.8162)
		(width 0.2032)
		(layer "In2.Cu")
		(net "MAC_PPS_IN0+")
	)
	(arc
		(start 142.4261 88.1162)
		(mid 142.338232 88.328332)
		(end 142.1261 88.4162)
		(width 0.2032)
		(layer "In2.Cu")
		(net "MAC_PPS_IN0+")
	)
	(arc
		(start 134.9261 90.94845)
		(mid 135.664223 89.166463)
		(end 137.44621 88.42834)
		(width 0.2032)
		(layer "In2.Cu")
		(net "MAC_PPS_IN0+")
	)
	(arc
		(start 141.6261 86.57859)
		(mid 142.191785 86.812905)
		(end 142.4261 87.37859)
		(width 0.2032)
		(layer "In2.Cu")
		(net "MAC_PPS_IN0+")
	)
	(segment
		(start 171.84911 98.95161)
		(end 172.5511 99.6536)
		(width 0.2032)
		(layer "F.Cu")
		(net "MAC_BITE")
	)
	(segment
		(start 171.82574 97.91825)
		(end 171.84911 97.94162)
		(width 0.2032)
		(layer "F.Cu")
		(net "MAC_BITE")
	)
	(segment
		(start 171.84911 98.95161)
		(end 171.84911 97.94162)
		(width 0.2032)
		(layer "F.Cu")
		(net "MAC_BITE")
	)
	(via
		(at 172.5511 99.6536)
		(size 0.4064)
		(drill 0.2032)
		(layers "F.Cu" "B.Cu")
		(tenting
			(front yes)
			(back yes)
		)
		(net "MAC_BITE")
	)
	(segment
		(start 151.5261 138.2162)
		(end 172.5511 117.1912)
		(width 0.2032)
		(layer "In3.Cu")
		(net "MAC_BITE")
	)
	(segment
		(start 137.8261 138.2162)
		(end 151.5261 138.2162)
		(width 0.2032)
		(layer "In3.Cu")
		(net "MAC_BITE")
	)
	(segment
		(start 172.5511 117.1912)
		(end 172.5511 99.6536)
		(width 0.2032)
		(layer "In3.Cu")
		(net "MAC_BITE")
	)
	(segment
		(start 141.66107 117.49692)
		(end 142.84126 117.49692)
		(width 0.2032)
		(layer "F.Cu")
		(net "MAC_ALARM")
	)
	(segment
		(start 171.32587 99.27338)
		(end 171.6261 99.57361)
		(width 0.2032)
		(layer "F.Cu")
		(net "MAC_ALARM")
	)
	(segment
		(start 171.32587 99.27338)
		(end 171.32587 97.91825)
		(width 0.2032)
		(layer "F.Cu")
		(net "MAC_ALARM")
	)
	(segment
		(start 142.84126 117.49692)
		(end 143.04919 117.28899)
		(width 0.2032)
		(layer "F.Cu")
		(net "MAC_ALARM")
	)
	(segment
		(start 171.6261 99.6286)
		(end 171.6261 99.57361)
		(width 0.2032)
		(layer "F.Cu")
		(net "MAC_ALARM")
	)
	(via
		(at 171.6261 99.6286)
		(size 0.4064)
		(drill 0.2032)
		(layers "F.Cu" "B.Cu")
		(tenting
			(front yes)
			(back yes)
		)
		(net "MAC_ALARM")
	)
	(via
		(at 143.04919 117.28899)
		(size 0.4064)
		(drill 0.2032)
		(layers "F.Cu" "B.Cu")
		(net "MAC_ALARM")
	)
	(segment
		(start 144.43019 117.28899)
		(end 146.0074 118.8662)
		(width 0.2032)
		(layer "In2.Cu")
		(net "MAC_ALARM")
	)
	(segment
		(start 158.3761 104.0036)
		(end 161.9261 100.4536)
		(width 0.2032)
		(layer "In2.Cu")
		(net "MAC_ALARM")
	)
	(segment
		(start 158.3761 113.6162)
		(end 158.3761 104.0036)
		(width 0.2032)
		(layer "In2.Cu")
		(net "MAC_ALARM")
	)
	(segment
		(start 146.0074 118.8662)
		(end 153.1261 118.8662)
		(width 0.2032)
		(layer "In2.Cu")
		(net "MAC_ALARM")
	)
	(segment
		(start 170.8011 100.4536)
		(end 171.6261 99.6286)
		(width 0.2032)
		(layer "In2.Cu")
		(net "MAC_ALARM")
	)
	(segment
		(start 153.1261 118.8662)
		(end 158.3761 113.6162)
		(width 0.2032)
		(layer "In2.Cu")
		(net "MAC_ALARM")
	)
	(segment
		(start 143.04919 117.28899)
		(end 144.43019 117.28899)
		(width 0.2032)
		(layer "In2.Cu")
		(net "MAC_ALARM")
	)
	(segment
		(start 161.9261 100.4536)
		(end 170.8011 100.4536)
		(width 0.2032)
		(layer "In2.Cu")
		(net "MAC_ALARM")
	)
	(segment
		(start 79.8761 67.8286)
		(end 81.9311 67.8286)
		(width 0.2032)
		(layer "F.Cu")
		(net "GPS1_TP2")
	)
	(segment
		(start 199.3634 112.81332)
		(end 200.92008 112.81332)
		(width 0.2032)
		(layer "F.Cu")
		(net "GPS1_TP2")
	)
	(segment
		(start 200.92008 112.81332)
		(end 201.06311 112.67029)
		(width 0.2032)
		(layer "F.Cu")
		(net "GPS1_TP2")
	)
	(segment
		(start 201.06311 112.67029)
		(end 201.1181 112.67029)
		(width 0.2032)
		(layer "F.Cu")
		(net "GPS1_TP2")
	)
	(via
		(at 79.8761 67.8286)
		(size 0.4064)
		(drill 0.2032)
		(layers "F.Cu" "B.Cu")
		(tenting
			(front yes)
			(back yes)
		)
		(net "GPS1_TP2")
	)
	(via
		(at 201.1181 112.67029)
		(size 0.4064)
		(drill 0.2032)
		(layers "F.Cu" "B.Cu")
		(tenting
			(front yes)
			(back yes)
		)
		(net "GPS1_TP2")
	)
	(segment
		(start 103.09307 64.8286)
		(end 139.15307 100.8886)
		(width 0.2032)
		(layer "B.Cu")
		(net "GPS1_TP2")
	)
	(segment
		(start 79.8761 67.8286)
		(end 79.8761 66.3286)
		(width 0.2032)
		(layer "B.Cu")
		(net "GPS1_TP2")
	)
	(segment
		(start 79.8761 66.3286)
		(end 81.3761 64.8286)
		(width 0.2032)
		(layer "B.Cu")
		(net "GPS1_TP2")
	)
	(segment
		(start 139.15307 100.8886)
		(end 158.1619 100.8886)
		(width 0.2032)
		(layer "B.Cu")
		(net "GPS1_TP2")
	)
	(segment
		(start 158.1619 100.8886)
		(end 169.94359 112.67029)
		(width 0.2032)
		(layer "B.Cu")
		(net "GPS1_TP2")
	)
	(segment
		(start 81.3761 64.8286)
		(end 103.09307 64.8286)
		(width 0.2032)
		(layer "B.Cu")
		(net "GPS1_TP2")
	)
	(segment
		(start 169.94359 112.67029)
		(end 201.1181 112.67029)
		(width 0.2032)
		(layer "B.Cu")
		(net "GPS1_TP2")
	)
	(segment
		(start 199.3634 109.81332)
		(end 199.37104 109.82096)
		(width 0.2032)
		(layer "F.Cu")
		(net "GPS1_RST")
	)
	(segment
		(start 199.37104 109.82096)
		(end 201.36846 109.82096)
		(width 0.2032)
		(layer "F.Cu")
		(net "GPS1_RST")
	)
	(segment
		(start 201.36846 109.82096)
		(end 201.3761 109.8286)
		(width 0.2032)
		(layer "F.Cu")
		(net "GPS1_RST")
	)
	(segment
		(start 86.3761 71.8286)
		(end 88.3761 71.8286)
		(width 0.2032)
		(layer "F.Cu")
		(net "GPS1_RST")
	)
	(via
		(at 88.3761 71.8286)
		(size 0.4064)
		(drill 0.2032)
		(layers "F.Cu" "B.Cu")
		(tenting
			(front yes)
			(back yes)
		)
		(net "GPS1_RST")
	)
	(via
		(at 201.3761 109.8286)
		(size 0.4064)
		(drill 0.2032)
		(layers "F.Cu" "B.Cu")
		(tenting
			(front yes)
			(back yes)
		)
		(net "GPS1_RST")
	)
	(segment
		(start 202.2959 112.9464)
		(end 202.2959 110.7484)
		(width 0.2032)
		(layer "B.Cu")
		(net "GPS1_RST")
	)
	(segment
		(start 88.3761 71.8286)
		(end 109.15913 71.8286)
		(width 0.2032)
		(layer "B.Cu")
		(net "GPS1_RST")
	)
	(segment
		(start 201.6029 113.6394)
		(end 202.2959 112.9464)
		(width 0.2032)
		(layer "B.Cu")
		(net "GPS1_RST")
	)
	(segment
		(start 169.9729 113.6394)
		(end 201.6029 113.6394)
		(width 0.2032)
		(layer "B.Cu")
		(net "GPS1_RST")
	)
	(segment
		(start 157.8825 101.549)
		(end 169.9729 113.6394)
		(width 0.2032)
		(layer "B.Cu")
		(net "GPS1_RST")
	)
	(segment
		(start 138.87953 101.549)
		(end 157.8825 101.549)
		(width 0.2032)
		(layer "B.Cu")
		(net "GPS1_RST")
	)
	(segment
		(start 201.3761 109.8286)
		(end 202.2959 110.7484)
		(width 0.2032)
		(layer "B.Cu")
		(net "GPS1_RST")
	)
	(segment
		(start 109.15913 71.8286)
		(end 138.87953 101.549)
		(width 0.2032)
		(layer "B.Cu")
		(net "GPS1_RST")
	)
	(segment
		(start 72.8511 135.6162)
		(end 76.8761 135.6162)
		(width 0.2032)
		(layer "F.Cu")
		(net "NetAN4_1")
	)
	(segment
		(start 72.8261 135.5912)
		(end 72.8511 135.6162)
		(width 0.2032)
		(layer "F.Cu")
		(net "NetAN4_1")
	)
	(segment
		(start 72.8135 135.5786)
		(end 72.8261 135.5912)
		(width 0.2032)
		(layer "F.Cu")
		(net "NetAN4_1")
	)
	(segment
		(start 72.8261 135.5912)
		(end 72.8261 129.2162)
		(width 0.2032)
		(layer "F.Cu")
		(net "NetAN4_1")
	)
	(segment
		(start 60.9761 135.5786)
		(end 72.8135 135.5786)
		(width 0.2032)
		(layer "F.Cu")
		(net "NetAN4_1")
	)
	(segment
		(start 72.8131 108.5782)
		(end 72.8511 108.6162)
		(width 0.2032)
		(layer "F.Cu")
		(net "NetAN2_1")
	)
	(segment
		(start 60.9761 108.5782)
		(end 72.8131 108.5782)
		(width 0.2032)
		(layer "F.Cu")
		(net "NetAN2_1")
	)
	(segment
		(start 72.8511 108.6162)
		(end 77.1761 108.6162)
		(width 0.2032)
		(layer "F.Cu")
		(net "NetAN2_1")
	)
	(segment
		(start 72.8131 108.5782)
		(end 72.8261 108.5652)
		(width 0.2032)
		(layer "F.Cu")
		(net "NetAN2_1")
	)
	(segment
		(start 72.8261 108.5652)
		(end 72.8261 101.8662)
		(width 0.2032)
		(layer "F.Cu")
		(net "NetAN2_1")
	)
	(segment
		(start 72.8261 127.0162)
		(end 72.8261 122.0782)
		(width 0.2032)
		(layer "F.Cu")
		(net "NetAN3_1")
	)
	(segment
		(start 73.1011 121.8662)
		(end 77.1761 121.8662)
		(width 0.2032)
		(layer "F.Cu")
		(net "NetAN3_1")
	)
	(segment
		(start 72.9761 121.9912)
		(end 73.1011 121.8662)
		(width 0.2032)
		(layer "F.Cu")
		(net "NetAN3_1")
	)
	(segment
		(start 72.8261 121.8912)
		(end 72.8511 121.8662)
		(width 0.2032)
		(layer "F.Cu")
		(net "NetAN3_1")
	)
	(segment
		(start 72.8261 122.0782)
		(end 72.8261 121.8912)
		(width 0.2032)
		(layer "F.Cu")
		(net "NetAN3_1")
	)
	(segment
		(start 60.9761 122.0782)
		(end 72.8261 122.0782)
		(width 0.2032)
		(layer "F.Cu")
		(net "NetAN3_1")
	)
	(segment
		(start 72.8511 99.6412)
		(end 72.8511 95.1162)
		(width 0.2032)
		(layer "F.Cu")
		(net "NetAN1_1")
	)
	(segment
		(start 72.8511 95.1162)
		(end 76.9261 95.1162)
		(width 0.2032)
		(layer "F.Cu")
		(net "NetAN1_1")
	)
	(segment
		(start 72.8261 99.6662)
		(end 72.8511 99.6412)
		(width 0.2032)
		(layer "F.Cu")
		(net "NetAN1_1")
	)
	(segment
		(start 60.9761 95.0786)
		(end 72.8135 95.0786)
		(width 0.2032)
		(layer "F.Cu")
		(net "NetAN1_1")
	)
	(segment
		(start 72.8135 95.0786)
		(end 72.8511 95.1162)
		(width 0.2032)
		(layer "F.Cu")
		(net "NetAN1_1")
	)
	(segment
		(start 75.1261 57.3662)
		(end 75.1261 56.2912)
		(width 0.2032)
		(layer "F.Cu")
		(net "LED4")
	)
	(segment
		(start 193.2761 121.6536)
		(end 193.93593 122.31343)
		(width 0.2032)
		(layer "F.Cu")
		(net "LED4")
	)
	(segment
		(start 193.93593 122.31343)
		(end 195.31363 122.31343)
		(width 0.2032)
		(layer "F.Cu")
		(net "LED4")
	)
	(via
		(at 193.2761 121.6536)
		(size 0.4064)
		(drill 0.2032)
		(layers "F.Cu" "B.Cu")
		(tenting
			(front yes)
			(back yes)
		)
		(net "LED4")
	)
	(via
		(at 75.1261 57.3662)
		(size 0.4064)
		(drill 0.2032)
		(layers "F.Cu" "B.Cu")
		(tenting
			(front yes)
			(back yes)
		)
		(net "LED4")
	)
	(segment
		(start 90.6761 115.01163)
		(end 103.48067 127.8162)
		(width 0.2032)
		(layer "In2.Cu")
		(net "LED4")
	)
	(segment
		(start 75.1261 84.11619)
		(end 75.1261 57.3662)
		(width 0.2032)
		(layer "In2.Cu")
		(net "LED4")
	)
	(segment
		(start 75.1261 84.11619)
		(end 90.6761 99.6662)
		(width 0.2032)
		(layer "In2.Cu")
		(net "LED4")
	)
	(segment
		(start 156.3385 125.2162)
		(end 189.7135 125.2162)
		(width 0.2032)
		(layer "In2.Cu")
		(net "LED4")
	)
	(segment
		(start 90.6761 115.01163)
		(end 90.6761 99.6662)
		(width 0.2032)
		(layer "In2.Cu")
		(net "LED4")
	)
	(segment
		(start 153.7385 127.8162)
		(end 156.3385 125.2162)
		(width 0.2032)
		(layer "In2.Cu")
		(net "LED4")
	)
	(segment
		(start 103.48067 127.8162)
		(end 153.7385 127.8162)
		(width 0.2032)
		(layer "In2.Cu")
		(net "LED4")
	)
	(segment
		(start 189.7135 125.2162)
		(end 193.2761 121.6536)
		(width 0.2032)
		(layer "In2.Cu")
		(net "LED4")
	)
	(segment
		(start 73.3761 57.3662)
		(end 73.3761 56.2912)
		(width 0.2032)
		(layer "F.Cu")
		(net "LED3")
	)
	(segment
		(start 193.6358 122.8133)
		(end 195.31363 122.8133)
		(width 0.2032)
		(layer "F.Cu")
		(net "LED3")
	)
	(segment
		(start 193.2761 122.4536)
		(end 193.6358 122.8133)
		(width 0.2032)
		(layer "F.Cu")
		(net "LED3")
	)
	(via
		(at 193.2761 122.4536)
		(size 0.4064)
		(drill 0.2032)
		(layers "F.Cu" "B.Cu")
		(tenting
			(front yes)
			(back yes)
		)
		(net "LED3")
	)
	(via
		(at 73.3761 57.3662)
		(size 0.4064)
		(drill 0.2032)
		(layers "F.Cu" "B.Cu")
		(tenting
			(front yes)
			(back yes)
		)
		(net "LED3")
	)
	(segment
		(start 73.1261 57.6162)
		(end 73.3761 57.3662)
		(width 0.2032)
		(layer "In2.Cu")
		(net "LED3")
	)
	(segment
		(start 73.1261 82.58317)
		(end 73.1261 57.6162)
		(width 0.2032)
		(layer "In2.Cu")
		(net "LED3")
	)
	(segment
		(start 156.1385 126.0162)
		(end 189.7135 126.0162)
		(width 0.2032)
		(layer "In2.Cu")
		(net "LED3")
	)
	(segment
		(start 103.5137 128.3162)
		(end 153.8385 128.3162)
		(width 0.2032)
		(layer "In2.Cu")
		(net "LED3")
	)
	(segment
		(start 189.7135 126.0162)
		(end 193.2761 122.4536)
		(width 0.2032)
		(layer "In2.Cu")
		(net "LED3")
	)
	(segment
		(start 90.3459 115.1484)
		(end 103.5137 128.3162)
		(width 0.2032)
		(layer "In2.Cu")
		(net "LED3")
	)
	(segment
		(start 153.8385 128.3162)
		(end 156.1385 126.0162)
		(width 0.2032)
		(layer "In2.Cu")
		(net "LED3")
	)
	(segment
		(start 90.3459 115.1484)
		(end 90.3459 99.80297)
		(width 0.2032)
		(layer "In2.Cu")
		(net "LED3")
	)
	(segment
		(start 73.1261 82.58317)
		(end 90.3459 99.80297)
		(width 0.2032)
		(layer "In2.Cu")
		(net "LED3")
	)
	(segment
		(start 102.50489 154.05081)
		(end 102.77962 153.77608)
		(width 0.508)
		(layer "F.Cu")
		(net "+12V_PCIE")
	)
	(segment
		(start 103.54612 157.7576)
		(end 103.54612 154.4601)
		(width 0.508)
		(layer "F.Cu")
		(net "+12V_PCIE")
	)
	(segment
		(start 101.54613 157.7576)
		(end 101.54613 154.48357)
		(width 0.508)
		(layer "F.Cu")
		(net "+12V_PCIE")
	)
	(segment
		(start 102.54612 157.7576)
		(end 102.54612 154.09205)
		(width 0.508)
		(layer "F.Cu")
		(net "+12V_PCIE")
	)
	(segment
		(start 102.77962 153.77608)
		(end 102.8621 153.77608)
		(width 0.508)
		(layer "F.Cu")
		(net "+12V_PCIE")
	)
	(segment
		(start 102.54612 154.09205)
		(end 102.8621 153.77608)
		(width 0.508)
		(layer "F.Cu")
		(net "+12V_PCIE")
	)
	(segment
		(start 101.97888 154.05081)
		(end 102.50489 154.05081)
		(width 0.508)
		(layer "F.Cu")
		(net "+12V_PCIE")
	)
	(segment
		(start 101.54613 154.48357)
		(end 101.97888 154.05081)
		(width 0.508)
		(layer "F.Cu")
		(net "+12V_PCIE")
	)
	(via
		(at 103.4261 154.0786)
		(size 0.4064)
		(drill 0.2032)
		(layers "F.Cu" "B.Cu")
		(tenting
			(front yes)
			(back yes)
		)
		(net "+12V_PCIE")
	)
	(via
		(at 233.7261 131.8162)
		(size 0.4064)
		(drill 0.2032)
		(layers "F.Cu" "B.Cu")
		(tenting
			(front yes)
			(back yes)
		)
		(net "+12V_PCIE")
	)
	(via
		(at 233.7261 131.0162)
		(size 0.4064)
		(drill 0.2032)
		(layers "F.Cu" "B.Cu")
		(tenting
			(front yes)
			(back yes)
		)
		(net "+12V_PCIE")
	)
	(via
		(at 102.6261 146.2162)
		(size 0.4064)
		(drill 0.2032)
		(layers "F.Cu" "B.Cu")
		(tenting
			(front yes)
			(back yes)
		)
		(net "+12V_PCIE")
	)
	(via
		(at 102.4261 154.0786)
		(size 0.4064)
		(drill 0.2032)
		(layers "F.Cu" "B.Cu")
		(tenting
			(front yes)
			(back yes)
		)
		(net "+12V_PCIE")
	)
	(via
		(at 234.7261 131.8162)
		(size 0.4064)
		(drill 0.2032)
		(layers "F.Cu" "B.Cu")
		(tenting
			(front yes)
			(back yes)
		)
		(net "+12V_PCIE")
	)
	(via
		(at 102.4261 153.2786)
		(size 0.4064)
		(drill 0.2032)
		(layers "F.Cu" "B.Cu")
		(tenting
			(front yes)
			(back yes)
		)
		(net "+12V_PCIE")
	)
	(via
		(at 234.2261 131.8162)
		(size 0.4064)
		(drill 0.2032)
		(layers "F.Cu" "B.Cu")
		(tenting
			(front yes)
			(back yes)
		)
		(net "+12V_PCIE")
	)
	(via
		(at 103.1261 146.2162)
		(size 0.4064)
		(drill 0.2032)
		(layers "F.Cu" "B.Cu")
		(tenting
			(front yes)
			(back yes)
		)
		(net "+12V_PCIE")
	)
	(via
		(at 103.4261 153.2786)
		(size 0.4064)
		(drill 0.2032)
		(layers "F.Cu" "B.Cu")
		(tenting
			(front yes)
			(back yes)
		)
		(net "+12V_PCIE")
	)
	(via
		(at 102.9261 153.2786)
		(size 0.4064)
		(drill 0.2032)
		(layers "F.Cu" "B.Cu")
		(tenting
			(front yes)
			(back yes)
		)
		(net "+12V_PCIE")
	)
	(via
		(at 234.2261 131.0162)
		(size 0.4064)
		(drill 0.2032)
		(layers "F.Cu" "B.Cu")
		(tenting
			(front yes)
			(back yes)
		)
		(net "+12V_PCIE")
	)
	(via
		(at 102.9261 154.0786)
		(size 0.4064)
		(drill 0.2032)
		(layers "F.Cu" "B.Cu")
		(tenting
			(front yes)
			(back yes)
		)
		(net "+12V_PCIE")
	)
	(via
		(at 102.1261 147.0162)
		(size 0.4064)
		(drill 0.2032)
		(layers "F.Cu" "B.Cu")
		(tenting
			(front yes)
			(back yes)
		)
		(net "+12V_PCIE")
	)
	(via
		(at 102.1261 146.2162)
		(size 0.4064)
		(drill 0.2032)
		(layers "F.Cu" "B.Cu")
		(tenting
			(front yes)
			(back yes)
		)
		(net "+12V_PCIE")
	)
	(via
		(at 102.6261 147.0162)
		(size 0.4064)
		(drill 0.2032)
		(layers "F.Cu" "B.Cu")
		(tenting
			(front yes)
			(back yes)
		)
		(net "+12V_PCIE")
	)
	(via
		(at 234.7261 131.0162)
		(size 0.4064)
		(drill 0.2032)
		(layers "F.Cu" "B.Cu")
		(tenting
			(front yes)
			(back yes)
		)
		(net "+12V_PCIE")
	)
	(via
		(at 103.1261 147.0162)
		(size 0.4064)
		(drill 0.2032)
		(layers "F.Cu" "B.Cu")
		(tenting
			(front yes)
			(back yes)
		)
		(net "+12V_PCIE")
	)
	(segment
		(start 190.8261 130.1162)
		(end 193.4261 130.1162)
		(width 1.9682)
		(layer "B.Cu")
		(net "+12V_PCIE")
	)
	(segment
		(start 195.0261 128.5162)
		(end 225.2261 128.5162)
		(width 1.9682)
		(layer "B.Cu")
		(net "+12V_PCIE")
	)
	(segment
		(start 102.6261 146.54571)
		(end 106.05561 143.1162)
		(width 1.9682)
		(layer "B.Cu")
		(net "+12V_PCIE")
	)
	(segment
		(start 106.05561 143.1162)
		(end 177.8261 143.1162)
		(width 1.9682)
		(layer "B.Cu")
		(net "+12V_PCIE")
	)
	(segment
		(start 102.54612 157.7576)
		(end 102.54612 154.03707)
		(width 0.508)
		(layer "B.Cu")
		(net "+12V_PCIE")
	)
	(segment
		(start 102.8621 153.72109)
		(end 103.54612 154.40511)
		(width 0.508)
		(layer "B.Cu")
		(net "+12V_PCIE")
	)
	(segment
		(start 233.1261 132.4162)
		(end 234.2261 131.3162)
		(width 1.9682)
		(layer "B.Cu")
		(net "+12V_PCIE")
	)
	(segment
		(start 102.54612 154.03707)
		(end 102.8621 153.72109)
		(width 0.508)
		(layer "B.Cu")
		(net "+12V_PCIE")
	)
	(segment
		(start 225.2261 128.5162)
		(end 229.1261 132.4162)
		(width 1.9682)
		(layer "B.Cu")
		(net "+12V_PCIE")
	)
	(segment
		(start 229.1261 132.4162)
		(end 233.1261 132.4162)
		(width 1.9682)
		(layer "B.Cu")
		(net "+12V_PCIE")
	)
	(segment
		(start 103.54612 157.7576)
		(end 103.54612 154.40511)
		(width 0.508)
		(layer "B.Cu")
		(net "+12V_PCIE")
	)
	(segment
		(start 177.8261 143.1162)
		(end 190.8261 130.1162)
		(width 1.9682)
		(layer "B.Cu")
		(net "+12V_PCIE")
	)
	(segment
		(start 102.6261 147.0162)
		(end 102.6261 146.54571)
		(width 1.9682)
		(layer "B.Cu")
		(net "+12V_PCIE")
	)
	(segment
		(start 193.4261 130.1162)
		(end 195.0261 128.5162)
		(width 1.9682)
		(layer "B.Cu")
		(net "+12V_PCIE")
	)
	(segment
		(start 108.52611 157.0786)
		(end 108.52611 153.97858)
		(width 0.508)
		(layer "F.Cu")
		(net "+3.3V_PCIE")
	)
	(segment
		(start 108.52611 153.97858)
		(end 108.8261 153.6786)
		(width 0.508)
		(layer "F.Cu")
		(net "+3.3V_PCIE")
	)
	(segment
		(start 108.54611 157.7576)
		(end 108.62417 157.67954)
		(width 0.508)
		(layer "F.Cu")
		(net "+3.3V_PCIE")
	)
	(segment
		(start 108.8261 153.6786)
		(end 109.5261 153.6786)
		(width 0.508)
		(layer "F.Cu")
		(net "+3.3V_PCIE")
	)
	(via
		(at 109.5261 154.0786)
		(size 0.4064)
		(drill 0.2032)
		(layers "F.Cu" "B.Cu")
		(tenting
			(front yes)
			(back yes)
		)
		(net "+3.3V_PCIE")
	)
	(via
		(at 110.5261 153.2786)
		(size 0.4064)
		(drill 0.2032)
		(layers "F.Cu" "B.Cu")
		(tenting
			(front yes)
			(back yes)
		)
		(net "+3.3V_PCIE")
	)
	(via
		(at 110.5261 154.0786)
		(size 0.4064)
		(drill 0.2032)
		(layers "F.Cu" "B.Cu")
		(tenting
			(front yes)
			(back yes)
		)
		(net "+3.3V_PCIE")
	)
	(via
		(at 108.6261 154.0786)
		(size 0.4064)
		(drill 0.2032)
		(layers "F.Cu" "B.Cu")
		(tenting
			(front yes)
			(back yes)
		)
		(net "+3.3V_PCIE")
	)
	(via
		(at 109.5261 153.2786)
		(size 0.4064)
		(drill 0.2032)
		(layers "F.Cu" "B.Cu")
		(tenting
			(front yes)
			(back yes)
		)
		(net "+3.3V_PCIE")
	)
	(via
		(at 108.6261 153.2786)
		(size 0.4064)
		(drill 0.2032)
		(layers "F.Cu" "B.Cu")
		(tenting
			(front yes)
			(back yes)
		)
		(net "+3.3V_PCIE")
	)
	(segment
		(start 109.5931 153.2456)
		(end 110.51504 154.16754)
		(width 0.508)
		(layer "B.Cu")
		(net "+3.3V_PCIE")
	)
	(segment
		(start 109.52611 157.0786)
		(end 109.52611 154.07861)
		(width 0.508)
		(layer "B.Cu")
		(net "+3.3V_PCIE")
	)
	(segment
		(start 110.51504 157.72653)
		(end 110.51504 154.16754)
		(width 0.508)
		(layer "B.Cu")
		(net "+3.3V_PCIE")
	)
	(segment
		(start 109.5261 154.0786)
		(end 109.52611 154.07861)
		(width 0.508)
		(layer "B.Cu")
		(net "+3.3V_PCIE")
	)
	(segment
		(start 110.51504 157.72653)
		(end 110.54611 157.7576)
		(width 0.508)
		(layer "B.Cu")
		(net "+3.3V_PCIE")
	)
	(segment
		(start 115.0887 145.1536)
		(end 119.4761 145.1536)
		(width 0.2032)
		(layer "F.Cu")
		(net "PRSNT")
	)
	(segment
		(start 108.4761 150.9786)
		(end 109.2637 150.9786)
		(width 0.2032)
		(layer "F.Cu")
		(net "PRSNT")
	)
	(segment
		(start 109.2637 150.9786)
		(end 115.0887 145.1536)
		(width 0.2032)
		(layer "F.Cu")
		(net "PRSNT")
	)
	(segment
		(start 119.4761 145.1536)
		(end 133.4761 145.1536)
		(width 0.2032)
		(layer "F.Cu")
		(net "PRSNT")
	)
	(via
		(at 108.4761 150.9786)
		(size 0.4064)
		(drill 0.2032)
		(layers "F.Cu" "B.Cu")
		(tenting
			(front yes)
			(back yes)
		)
		(net "PRSNT")
	)
	(segment
		(start 101.6713 152.75235)
		(end 103.44505 150.9786)
		(width 0.2032)
		(layer "B.Cu")
		(net "PRSNT")
	)
	(segment
		(start 101.6713 157.13713)
		(end 101.6713 152.75235)
		(width 0.2032)
		(layer "B.Cu")
		(net "PRSNT")
	)
	(segment
		(start 101.54613 157.2623)
		(end 101.6713 157.13713)
		(width 0.2032)
		(layer "B.Cu")
		(net "PRSNT")
	)
	(segment
		(start 103.44505 150.9786)
		(end 108.4761 150.9786)
		(width 0.2032)
		(layer "B.Cu")
		(net "PRSNT")
	)
	(segment
		(start 177.83583 131.45545)
		(end 177.8437 131.46332)
		(width 0.127)
		(layer "F.Cu")
		(net "PCIE_TX3_N")
	)
	(segment
		(start 177.83583 132.91887)
		(end 177.83583 131.45545)
		(width 0.127)
		(layer "F.Cu")
		(net "PCIE_TX3_N")
	)
	(via
		(at 132.5761 150.2786)
		(size 0.4064)
		(drill 0.2032)
		(layers "F.Cu" "B.Cu")
		(tenting
			(front yes)
			(back yes)
		)
		(net "PCIE_TX3_N")
	)
	(via
		(at 177.7261 133.0286)
		(size 0.4064)
		(drill 0.2032)
		(layers "F.Cu" "B.Cu")
		(tenting
			(front yes)
			(back yes)
		)
		(net "PCIE_TX3_N")
	)
	(arc
		(start 177.83583 132.91887)
		(mid 177.803691 132.996461)
		(end 177.7261 133.0286)
		(width 0.127)
		(layer "F.Cu")
		(net "PCIE_TX3_N")
	)
	(segment
		(start 132.5761 151.3546)
		(end 132.5801 151.3586)
		(width 0.127)
		(layer "B.Cu")
		(net "PCIE_TX3_N")
	)
	(segment
		(start 132.5761 151.3546)
		(end 132.5761 150.2786)
		(width 0.127)
		(layer "B.Cu")
		(net "PCIE_TX3_N")
	)
	(segment
		(start 132.2176 149.38072)
		(end 132.2176 147.77919)
		(width 0.127)
		(layer "In3.Cu")
		(net "PCIE_TX3_N")
	)
	(segment
		(start 180.51093 144.0265)
		(end 181.47957 143.05786)
		(width 0.127)
		(layer "In3.Cu")
		(net "PCIE_TX3_N")
	)
	(segment
		(start 178.71776 134.31274)
		(end 181.05333 136.6483)
		(width 0.127)
		(layer "In3.Cu")
		(net "PCIE_TX3_N")
	)
	(segment
		(start 135.0532 145.0662)
		(end 151.6761 145.0662)
		(width 0.127)
		(layer "In3.Cu")
		(net "PCIE_TX3_N")
	)
	(segment
		(start 132.8511 146.2162)
		(end 133.25715 145.81015)
		(width 0.127)
		(layer "In3.Cu")
		(net "PCIE_TX3_N")
	)
	(segment
		(start 132.2176 147.77919)
		(end 132.2176 147.74558)
		(width 0.127)
		(layer "In3.Cu")
		(net "PCIE_TX3_N")
	)
	(segment
		(start 151.6761 145.0662)
		(end 177.66559 145.0662)
		(width 0.127)
		(layer "In3.Cu")
		(net "PCIE_TX3_N")
	)
	(segment
		(start 178.6801 134.22247)
		(end 178.6801 133.38272)
		(width 0.127)
		(layer "In3.Cu")
		(net "PCIE_TX3_N")
	)
	(segment
		(start 177.7261 133.0286)
		(end 177.81629 133.11879)
		(width 0.127)
		(layer "In3.Cu")
		(net "PCIE_TX3_N")
	)
	(segment
		(start 181.6305 142.73859)
		(end 181.6305 137.94509)
		(width 0.127)
		(layer "In3.Cu")
		(net "PCIE_TX3_N")
	)
	(segment
		(start 181.48049 143.05694)
		(end 181.51239 143.02504)
		(width 0.127)
		(layer "In3.Cu")
		(net "PCIE_TX3_N")
	)
	(segment
		(start 132.2176 149.41311)
		(end 132.2176 149.38072)
		(width 0.127)
		(layer "In3.Cu")
		(net "PCIE_TX3_N")
	)
	(arc
		(start 178.0324 133.029062)
		(mid 178.570395 132.662296)
		(end 178.713714 133.297446)
		(width 0.127)
		(layer "In3.Cu")
		(net "PCIE_TX3_N")
	)
	(arc
		(start 178.717761 134.312734)
		(mid 178.689893 134.271373)
		(end 178.6801 134.22247)
		(width 0.127)
		(layer "In3.Cu")
		(net "PCIE_TX3_N")
	)
	(arc
		(start 178.680103 133.382717)
		(mid 178.688949 133.336945)
		(end 178.713716 133.297449)
		(width 0.127)
		(layer "In3.Cu")
		(net "PCIE_TX3_N")
	)
	(arc
		(start 133.257149 145.810149)
		(mid 134.081184 145.259546)
		(end 135.0532 145.0662)
		(width 0.127)
		(layer "In3.Cu")
		(net "PCIE_TX3_N")
	)
	(arc
		(start 180.510927 144.026495)
		(mid 179.203159 144.8608)
		(end 177.665585 145.066196)
		(width 0.127)
		(layer "In3.Cu")
		(net "PCIE_TX3_N")
	)
	(arc
		(start 178.032398 133.029062)
		(mid 177.954101 133.145591)
		(end 177.816292 133.118792)
		(width 0.127)
		(layer "In3.Cu")
		(net "PCIE_TX3_N")
	)
	(arc
		(start 132.543393 150.199638)
		(mid 132.5676 150.235867)
		(end 132.5761 150.278601)
		(width 0.127)
		(layer "In3.Cu")
		(net "PCIE_TX3_N")
	)
	(arc
		(start 132.54339 150.199638)
		(mid 132.30227 149.838776)
		(end 132.2176 149.41311)
		(width 0.127)
		(layer "In3.Cu")
		(net "PCIE_TX3_N")
	)
	(arc
		(start 181.6305 142.73859)
		(mid 181.599814 142.893509)
		(end 181.51239 143.025033)
		(width 0.127)
		(layer "In3.Cu")
		(net "PCIE_TX3_N")
	)
	(arc
		(start 181.053326 136.648307)
		(mid 181.479691 137.235376)
		(end 181.6305 137.94509)
		(width 0.127)
		(layer "In3.Cu")
		(net "PCIE_TX3_N")
	)
	(arc
		(start 132.21761 147.74558)
		(mid 132.382249 146.917885)
		(end 132.8511 146.2162)
		(width 0.127)
		(layer "In3.Cu")
		(net "PCIE_TX3_N")
	)
	(arc
		(start 181.480496 143.056938)
		(mid 181.480038 143.057401)
		(end 181.479577 143.057861)
		(width 0.127)
		(layer "In3.Cu")
		(net "PCIE_TX3_N")
	)
	(segment
		(start 178.33595 132.93845)
		(end 178.33595 131.45545)
		(width 0.127)
		(layer "F.Cu")
		(net "PCIE_TX3_P")
	)
	(via
		(at 178.4261 133.0286)
		(size 0.4064)
		(drill 0.2032)
		(layers "F.Cu" "B.Cu")
		(tenting
			(front yes)
			(back yes)
		)
		(net "PCIE_TX3_P")
	)
	(via
		(at 131.57971 150.18609)
		(size 0.4064)
		(drill 0.2032)
		(layers "F.Cu" "B.Cu")
		(tenting
			(front yes)
			(back yes)
		)
		(net "PCIE_TX3_P")
	)
	(arc
		(start 178.4261 133.0286)
		(mid 178.362354 133.002196)
		(end 178.33595 132.93845)
		(width 0.127)
		(layer "F.Cu")
		(net "PCIE_TX3_P")
	)
	(segment
		(start 131.5761 151.32962)
		(end 131.5761 150.21614)
		(width 0.127)
		(layer "B.Cu")
		(net "PCIE_TX3_P")
	)
	(segment
		(start 131.57809 150.19377)
		(end 131.57941 150.18639)
		(width 0.127)
		(layer "B.Cu")
		(net "PCIE_TX3_P")
	)
	(segment
		(start 131.57941 150.18639)
		(end 131.57971 150.18609)
		(width 0.127)
		(layer "B.Cu")
		(net "PCIE_TX3_P")
	)
	(arc
		(start 131.5761 150.21614)
		(mid 131.576597 150.20491)
		(end 131.578086 150.193768)
		(width 0.127)
		(layer "B.Cu")
		(net "PCIE_TX3_P")
	)
	(arc
		(start 131.57611 151.32962)
		(mid 131.572991 151.345302)
		(end 131.564107 151.358597)
		(width 0.127)
		(layer "B.Cu")
		(net "PCIE_TX3_P")
	)
	(segment
		(start 131.9382 149.38072)
		(end 131.9382 147.77919)
		(width 0.127)
		(layer "In3.Cu")
		(net "PCIE_TX3_P")
	)
	(segment
		(start 131.9382 149.47852)
		(end 131.9382 149.38072)
		(width 0.127)
		(layer "In3.Cu")
		(net "PCIE_TX3_P")
	)
	(segment
		(start 132.6508 146.02136)
		(end 133.06056 145.61161)
		(width 0.127)
		(layer "In3.Cu")
		(net "PCIE_TX3_P")
	)
	(segment
		(start 135.05181 144.7868)
		(end 151.6761 144.7868)
		(width 0.127)
		(layer "In3.Cu")
		(net "PCIE_TX3_P")
	)
	(segment
		(start 178.63291 134.62301)
		(end 180.95715 136.94725)
		(width 0.127)
		(layer "In3.Cu")
		(net "PCIE_TX3_P")
	)
	(segment
		(start 181.3511 142.73859)
		(end 181.3511 137.89834)
		(width 0.127)
		(layer "In3.Cu")
		(net "PCIE_TX3_P")
	)
	(segment
		(start 178.50115 134.45533)
		(end 178.50703 134.46121)
		(width 0.127)
		(layer "In3.Cu")
		(net "PCIE_TX3_P")
	)
	(segment
		(start 151.6761 144.7868)
		(end 177.66559 144.7868)
		(width 0.127)
		(layer "In3.Cu")
		(net "PCIE_TX3_P")
	)
	(segment
		(start 181.20099 142.94131)
		(end 181.31429 142.82801)
		(width 0.127)
		(layer "In3.Cu")
		(net "PCIE_TX3_P")
	)
	(segment
		(start 178.4261 134.27508)
		(end 178.4261 133.0286)
		(width 0.127)
		(layer "In3.Cu")
		(net "PCIE_TX3_P")
	)
	(segment
		(start 180.30825 143.83405)
		(end 181.20017 142.94213)
		(width 0.127)
		(layer "In3.Cu")
		(net "PCIE_TX3_P")
	)
	(segment
		(start 131.9382 147.77919)
		(end 131.9382 147.74173)
		(width 0.127)
		(layer "In3.Cu")
		(net "PCIE_TX3_P")
	)
	(arc
		(start 131.658673 150.153383)
		(mid 131.622444 150.17759)
		(end 131.57971 150.186091)
		(width 0.127)
		(layer "In3.Cu")
		(net "PCIE_TX3_P")
	)
	(arc
		(start 178.507022 134.461219)
		(mid 178.517002 134.472593)
		(end 178.525559 134.485074)
		(width 0.127)
		(layer "In3.Cu")
		(net "PCIE_TX3_P")
	)
	(arc
		(start 131.9382 149.47852)
		(mid 131.865551 149.843752)
		(end 131.658664 150.153381)
		(width 0.127)
		(layer "In3.Cu")
		(net "PCIE_TX3_P")
	)
	(arc
		(start 178.632916 134.623004)
		(mid 178.581955 134.566213)
		(end 178.537421 134.504254)
		(width 0.127)
		(layer "In3.Cu")
		(net "PCIE_TX3_P")
	)
	(arc
		(start 133.060555 145.611605)
		(mid 133.974151 145.00116)
		(end 135.05181 144.7868)
		(width 0.127)
		(layer "In3.Cu")
		(net "PCIE_TX3_P")
	)
	(arc
		(start 180.308258 143.834047)
		(mid 179.093296 144.605469)
		(end 177.665591 144.786802)
		(width 0.127)
		(layer "In3.Cu")
		(net "PCIE_TX3_P")
	)
	(arc
		(start 178.50115 134.455338)
		(mid 178.445612 134.372709)
		(end 178.4261 134.27508)
		(width 0.127)
		(layer "In3.Cu")
		(net "PCIE_TX3_P")
	)
	(arc
		(start 181.3511 142.73859)
		(mid 181.341538 142.786935)
		(end 181.314293 142.828001)
		(width 0.127)
		(layer "In3.Cu")
		(net "PCIE_TX3_P")
	)
	(arc
		(start 131.93821 147.74173)
		(mid 132.123408 146.810677)
		(end 132.650807 146.021367)
		(width 0.127)
		(layer "In3.Cu")
		(net "PCIE_TX3_P")
	)
	(arc
		(start 178.537421 134.504254)
		(mid 178.53142 134.494708)
		(end 178.525573 134.485067)
		(width 0.127)
		(layer "In3.Cu")
		(net "PCIE_TX3_P")
	)
	(arc
		(start 181.200992 142.941313)
		(mid 181.200585 142.94172)
		(end 181.200176 142.942125)
		(width 0.127)
		(layer "In3.Cu")
		(net "PCIE_TX3_P")
	)
	(arc
		(start 180.957146 136.947256)
		(mid 181.248714 137.383615)
		(end 181.3511 137.898337)
		(width 0.127)
		(layer "In3.Cu")
		(net "PCIE_TX3_P")
	)
	(segment
		(start 179.33595 137.60482)
		(end 179.33595 135.50523)
		(width 0.127)
		(layer "F.Cu")
		(net "PCIE_TX2_N")
	)
	(via
		(at 179.3261 137.6286)
		(size 0.4064)
		(drill 0.2032)
		(layers "F.Cu" "B.Cu")
		(tenting
			(front yes)
			(back yes)
		)
		(net "PCIE_TX2_N")
	)
	(via
		(at 128.3761 150.2786)
		(size 0.4064)
		(drill 0.2032)
		(layers "F.Cu" "B.Cu")
		(tenting
			(front yes)
			(back yes)
		)
		(net "PCIE_TX2_N")
	)
	(arc
		(start 179.33595 137.60482)
		(mid 179.33339 137.61769)
		(end 179.3261 137.6286)
		(width 0.127)
		(layer "F.Cu")
		(net "PCIE_TX2_N")
	)
	(segment
		(start 128.3761 151.32721)
		(end 128.3761 150.2786)
		(width 0.127)
		(layer "B.Cu")
		(net "PCIE_TX2_N")
	)
	(arc
		(start 128.389099 151.358591)
		(mid 128.379479 151.344193)
		(end 128.376101 151.32721)
		(width 0.127)
		(layer "B.Cu")
		(net "PCIE_TX2_N")
	)
	(segment
		(start 129.64254 145.26883)
		(end 130.90697 144.00441)
		(width 0.127)
		(layer "In3.Cu")
		(net "PCIE_TX2_N")
	)
	(segment
		(start 128.81773 148.11058)
		(end 128.81773 147.26009)
		(width 0.127)
		(layer "In3.Cu")
		(net "PCIE_TX2_N")
	)
	(segment
		(start 128.79906 148.15566)
		(end 128.79906 148.15565)
		(width 0.127)
		(layer "In3.Cu")
		(net "PCIE_TX2_N")
	)
	(segment
		(start 179.5864 139.8038)
		(end 179.5864 138.25702)
		(width 0.127)
		(layer "In3.Cu")
		(net "PCIE_TX2_N")
	)
	(segment
		(start 128.2157 150.33206)
		(end 128.24704 150.33206)
		(width 0.127)
		(layer "In3.Cu")
		(net "PCIE_TX2_N")
	)
	(segment
		(start 127.29916 149.65553)
		(end 127.29972 149.65497)
		(width 0.127)
		(layer "In3.Cu")
		(net "PCIE_TX2_N")
	)
	(segment
		(start 127.29972 149.65497)
		(end 128.79906 148.15566)
		(width 0.127)
		(layer "In3.Cu")
		(net "PCIE_TX2_N")
	)
	(segment
		(start 127.24235 150.58482)
		(end 127.24303 150.58549)
		(width 0.127)
		(layer "In3.Cu")
		(net "PCIE_TX2_N")
	)
	(segment
		(start 128.0658 150.50319)
		(end 128.0658 150.48196)
		(width 0.127)
		(layer "In3.Cu")
		(net "PCIE_TX2_N")
	)
	(segment
		(start 178.00665 142.43565)
		(end 178.84245 141.59985)
		(width 0.127)
		(layer "In3.Cu")
		(net "PCIE_TX2_N")
	)
	(segment
		(start 127.08161 150.22666)
		(end 127.08166 150.22751)
		(width 0.127)
		(layer "In3.Cu")
		(net "PCIE_TX2_N")
	)
	(segment
		(start 132.89822 143.1796)
		(end 176.2106 143.1796)
		(width 0.127)
		(layer "In3.Cu")
		(net "PCIE_TX2_N")
	)
	(arc
		(start 178.006651 142.435651)
		(mid 177.182616 142.986254)
		(end 176.2106 143.1796)
		(width 0.127)
		(layer "In3.Cu")
		(net "PCIE_TX2_N")
	)
	(arc
		(start 179.5864 139.8038)
		(mid 179.393054 140.775816)
		(end 178.842451 141.599851)
		(width 0.127)
		(layer "In3.Cu")
		(net "PCIE_TX2_N")
	)
	(arc
		(start 128.81773 147.26009)
		(mid 129.032091 146.182427)
		(end 129.642538 145.268828)
		(width 0.127)
		(layer "In3.Cu")
		(net "PCIE_TX2_N")
	)
	(arc
		(start 127.081603 150.226667)
		(mid 127.130115 149.918146)
		(end 127.299151 149.655534)
		(width 0.127)
		(layer "In3.Cu")
		(net "PCIE_TX2_N")
	)
	(arc
		(start 128.0658 150.48196)
		(mid 128.07721 150.424597)
		(end 128.109703 150.375966)
		(width 0.127)
		(layer "In3.Cu")
		(net "PCIE_TX2_N")
	)
	(arc
		(start 127.242342 150.584826)
		(mid 127.129342 150.420854)
		(end 127.081659 150.227509)
		(width 0.127)
		(layer "In3.Cu")
		(net "PCIE_TX2_N")
	)
	(arc
		(start 179.326107 137.628593)
		(mid 179.518759 137.916918)
		(end 179.58641 138.25702)
		(width 0.127)
		(layer "In3.Cu")
		(net "PCIE_TX2_N")
	)
	(arc
		(start 128.0658 150.50319)
		(mid 128.055193 150.553999)
		(end 128.025145 150.596322)
		(width 0.127)
		(layer "In3.Cu")
		(net "PCIE_TX2_N")
	)
	(arc
		(start 128.025146 150.596325)
		(mid 127.631909 150.747996)
		(end 127.243025 150.585491)
		(width 0.127)
		(layer "In3.Cu")
		(net "PCIE_TX2_N")
	)
	(arc
		(start 128.109705 150.375965)
		(mid 128.158336 150.343471)
		(end 128.2157 150.33206)
		(width 0.127)
		(layer "In3.Cu")
		(net "PCIE_TX2_N")
	)
	(arc
		(start 128.376101 150.278601)
		(mid 128.316887 150.318166)
		(end 128.24704 150.33206)
		(width 0.127)
		(layer "In3.Cu")
		(net "PCIE_TX2_N")
	)
	(arc
		(start 130.906965 144.004405)
		(mid 131.820561 143.39396)
		(end 132.89822 143.1796)
		(width 0.127)
		(layer "In3.Cu")
		(net "PCIE_TX2_N")
	)
	(arc
		(start 128.81773 148.11058)
		(mid 128.812877 148.134976)
		(end 128.799058 148.155658)
		(width 0.127)
		(layer "In3.Cu")
		(net "PCIE_TX2_N")
	)
	(segment
		(start 179.83582 136.9278)
		(end 179.83582 135.50523)
		(width 0.127)
		(layer "F.Cu")
		(net "PCIE_TX2_P")
	)
	(via
		(at 127.55447 150.21916)
		(size 0.4064)
		(drill 0.2032)
		(layers "F.Cu" "B.Cu")
		(tenting
			(front yes)
			(back yes)
		)
		(net "PCIE_TX2_P")
	)
	(via
		(at 180.1261 137.6286)
		(size 0.4064)
		(drill 0.2032)
		(layers "F.Cu" "B.Cu")
		(tenting
			(front yes)
			(back yes)
		)
		(net "PCIE_TX2_P")
	)
	(arc
		(start 180.126101 137.628599)
		(mid 179.911262 137.30707)
		(end 179.835821 136.9278)
		(width 0.127)
		(layer "F.Cu")
		(net "PCIE_TX2_P")
	)
	(segment
		(start 127.4761 151.30066)
		(end 127.4761 150.33546)
		(width 0.127)
		(layer "B.Cu")
		(net "PCIE_TX2_P")
	)
	(arc
		(start 127.5001 151.3586)
		(mid 127.482338 151.332017)
		(end 127.4761 151.30066)
		(width 0.127)
		(layer "B.Cu")
		(net "PCIE_TX2_P")
	)
	(arc
		(start 127.476104 150.335451)
		(mid 127.497783 150.265506)
		(end 127.554475 150.219157)
		(width 0.127)
		(layer "B.Cu")
		(net "PCIE_TX2_P")
	)
	(segment
		(start 127.41061 150.11074)
		(end 127.41865 150.13135)
		(width 0.127)
		(layer "In3.Cu")
		(net "PCIE_TX2_P")
	)
	(segment
		(start 129.09713 147.60044)
		(end 129.09713 147.26147)
		(width 0.127)
		(layer "In3.Cu")
		(net "PCIE_TX2_P")
	)
	(segment
		(start 127.46614 150.25308)
		(end 127.49764 150.22158)
		(width 0.127)
		(layer "In3.Cu")
		(net "PCIE_TX2_P")
	)
	(segment
		(start 127.54929 150.21916)
		(end 127.55447 150.21916)
		(width 0.127)
		(layer "In3.Cu")
		(net "PCIE_TX2_P")
	)
	(segment
		(start 127.41865 150.13135)
		(end 127.46614 150.25308)
		(width 0.127)
		(layer "In3.Cu")
		(net "PCIE_TX2_P")
	)
	(segment
		(start 129.01081 148.40311)
		(end 129.05571 148.35821)
		(width 0.127)
		(layer "In3.Cu")
		(net "PCIE_TX2_P")
	)
	(segment
		(start 128.20257 149.48075)
		(end 128.30472 149.5829)
		(width 0.127)
		(layer "In3.Cu")
		(net "PCIE_TX2_P")
	)
	(segment
		(start 129.0108 148.67252)
		(end 129.11295 148.77468)
		(width 0.127)
		(layer "In3.Cu")
		(net "PCIE_TX2_P")
	)
	(segment
		(start 129.1158 148.24551)
		(end 129.1158 147.64552)
		(width 0.127)
		(layer "In3.Cu")
		(net "PCIE_TX2_P")
	)
	(segment
		(start 180.1261 137.6286)
		(end 180.1261 137.6286)
		(width 0.127)
		(layer "In3.Cu")
		(net "PCIE_TX2_P")
	)
	(segment
		(start 179.8658 139.80759)
		(end 179.8658 138.25702)
		(width 0.127)
		(layer "In3.Cu")
		(net "PCIE_TX2_P")
	)
	(segment
		(start 127.54687 150.22158)
		(end 127.54929 150.21916)
		(width 0.127)
		(layer "In3.Cu")
		(net "PCIE_TX2_P")
	)
	(segment
		(start 178.20324 142.63419)
		(end 179.04269 141.79474)
		(width 0.127)
		(layer "In3.Cu")
		(net "PCIE_TX2_P")
	)
	(segment
		(start 129.05571 148.35821)
		(end 129.07805 148.33587)
		(width 0.127)
		(layer "In3.Cu")
		(net "PCIE_TX2_P")
	)
	(segment
		(start 127.41061 150.11074)
		(end 127.43912 149.97478)
		(width 0.127)
		(layer "In3.Cu")
		(net "PCIE_TX2_P")
	)
	(segment
		(start 128.42198 149.16134)
		(end 128.57413 149.31349)
		(width 0.127)
		(layer "In3.Cu")
		(net "PCIE_TX2_P")
	)
	(segment
		(start 129.84108 145.46542)
		(end 131.10356 144.20295)
		(width 0.127)
		(layer "In3.Cu")
		(net "PCIE_TX2_P")
	)
	(segment
		(start 129.05571 148.35821)
		(end 129.05571 148.35821)
		(width 0.127)
		(layer "In3.Cu")
		(net "PCIE_TX2_P")
	)
	(segment
		(start 129.0108 148.40311)
		(end 129.01081 148.40311)
		(width 0.127)
		(layer "In3.Cu")
		(net "PCIE_TX2_P")
	)
	(segment
		(start 128.69139 148.89193)
		(end 128.84354 149.04408)
		(width 0.127)
		(layer "In3.Cu")
		(net "PCIE_TX2_P")
	)
	(segment
		(start 127.49764 150.22158)
		(end 127.54687 150.22158)
		(width 0.127)
		(layer "In3.Cu")
		(net "PCIE_TX2_P")
	)
	(segment
		(start 127.43912 149.97478)
		(end 127.93317 149.48074)
		(width 0.127)
		(layer "In3.Cu")
		(net "PCIE_TX2_P")
	)
	(segment
		(start 132.89961 143.459)
		(end 176.21198 143.459)
		(width 0.127)
		(layer "In3.Cu")
		(net "PCIE_TX2_P")
	)
	(arc
		(start 129.112951 149.044086)
		(mid 128.978249 149.09988)
		(end 128.843547 149.044084)
		(width 0.127)
		(layer "In3.Cu")
		(net "PCIE_TX2_P")
	)
	(arc
		(start 128.421986 149.161334)
		(mid 128.36619 149.026632)
		(end 128.421983 148.891929)
		(width 0.127)
		(layer "In3.Cu")
		(net "PCIE_TX2_P")
	)
	(arc
		(start 179.8658 139.807583)
		(mid 179.651881 140.883018)
		(end 179.042695 141.794728)
		(width 0.127)
		(layer "In3.Cu")
		(net "PCIE_TX2_P")
	)
	(arc
		(start 129.078049 148.335872)
		(mid 129.078328 148.335594)
		(end 129.078607 148.335317)
		(width 0.127)
		(layer "In3.Cu")
		(net "PCIE_TX2_P")
	)
	(arc
		(start 128.574131 149.582896)
		(mid 128.439429 149.63869)
		(end 128.304727 149.582894)
		(width 0.127)
		(layer "In3.Cu")
		(net "PCIE_TX2_P")
	)
	(arc
		(start 129.1158 148.24551)
		(mid 129.106132 148.294112)
		(end 129.0786 148.335315)
		(width 0.127)
		(layer "In3.Cu")
		(net "PCIE_TX2_P")
	)
	(arc
		(start 131.103559 144.202949)
		(mid 131.927594 143.652346)
		(end 132.89961 143.459)
		(width 0.127)
		(layer "In3.Cu")
		(net "PCIE_TX2_P")
	)
	(arc
		(start 129.09713 147.26147)
		(mid 129.290476 146.289454)
		(end 129.841079 145.465419)
		(width 0.127)
		(layer "In3.Cu")
		(net "PCIE_TX2_P")
	)
	(arc
		(start 179.8658 138.25702)
		(mid 179.93345 137.916922)
		(end 180.126099 137.628601)
		(width 0.127)
		(layer "In3.Cu")
		(net "PCIE_TX2_P")
	)
	(arc
		(start 127.933167 149.480745)
		(mid 128.067871 149.42495)
		(end 128.202574 149.480746)
		(width 0.127)
		(layer "In3.Cu")
		(net "PCIE_TX2_P")
	)
	(arc
		(start 129.010797 148.672525)
		(mid 128.955 148.537821)
		(end 129.010796 148.403116)
		(width 0.127)
		(layer "In3.Cu")
		(net "PCIE_TX2_P")
	)
	(arc
		(start 128.421986 148.891936)
		(mid 128.55669 148.83614)
		(end 128.691394 148.891936)
		(width 0.127)
		(layer "In3.Cu")
		(net "PCIE_TX2_P")
	)
	(arc
		(start 128.574134 149.313486)
		(mid 128.62993 149.44819)
		(end 128.574134 149.582894)
		(width 0.127)
		(layer "In3.Cu")
		(net "PCIE_TX2_P")
	)
	(arc
		(start 129.115802 147.645518)
		(mid 129.101983 147.624836)
		(end 129.09713 147.60044)
		(width 0.127)
		(layer "In3.Cu")
		(net "PCIE_TX2_P")
	)
	(arc
		(start 178.203242 142.634192)
		(mid 177.289643 143.244639)
		(end 176.21198 143.459)
		(width 0.127)
		(layer "In3.Cu")
		(net "PCIE_TX2_P")
	)
	(arc
		(start 129.112954 148.774676)
		(mid 129.16875 148.90938)
		(end 129.112954 149.044084)
		(width 0.127)
		(layer "In3.Cu")
		(net "PCIE_TX2_P")
	)
	(segment
		(start 176.0261 137.6286)
		(end 176.0261 137.51658)
		(width 0.127)
		(layer "F.Cu")
		(net "PCIE_TX1_N")
	)
	(segment
		(start 176.33596 136.76772)
		(end 176.33596 135.50523)
		(width 0.127)
		(layer "F.Cu")
		(net "PCIE_TX1_N")
	)
	(segment
		(start 176.0261 137.51578)
		(end 176.0261 137.51658)
		(width 0.127)
		(layer "F.Cu")
		(net "PCIE_TX1_N")
	)
	(via
		(at 176.0261 137.6286)
		(size 0.4064)
		(drill 0.2032)
		(layers "F.Cu" "B.Cu")
		(tenting
			(front yes)
			(back yes)
		)
		(net "PCIE_TX1_N")
	)
	(via
		(at 124.5761 150.2786)
		(size 0.4064)
		(drill 0.2032)
		(layers "F.Cu" "B.Cu")
		(tenting
			(front yes)
			(back yes)
		)
		(net "PCIE_TX1_N")
	)
	(arc
		(start 176.0261 137.51578)
		(mid 176.078875 137.250465)
		(end 176.229164 137.025542)
		(width 0.127)
		(layer "F.Cu")
		(net "PCIE_TX1_N")
	)
	(arc
		(start 176.33596 136.76772)
		(mid 176.308206 136.90725)
		(end 176.229168 137.025538)
		(width 0.127)
		(layer "F.Cu")
		(net "PCIE_TX1_N")
	)
	(segment
		(start 124.5761 151.3556)
		(end 124.5761 150.2786)
		(width 0.127)
		(layer "B.Cu")
		(net "PCIE_TX1_N")
	)
	(segment
		(start 124.5761 151.3556)
		(end 124.5791 151.3586)
		(width 0.127)
		(layer "B.Cu")
		(net "PCIE_TX1_N")
	)
	(segment
		(start 176.0261 137.6324)
		(end 176.0261 137.6286)
		(width 0.127)
		(layer "In3.Cu")
		(net "PCIE_TX1_N")
	)
	(segment
		(start 125.27436 148.17196)
		(end 125.3213 148.17196)
		(width 0.127)
		(layer "In3.Cu")
		(net "PCIE_TX1_N")
	)
	(segment
		(start 125.27436 148.55296)
		(end 125.3213 148.55296)
		(width 0.127)
		(layer "In3.Cu")
		(net "PCIE_TX1_N")
	)
	(segment
		(start 124.5761 150.27861)
		(end 124.5761 150.2786)
		(width 0.127)
		(layer "In3.Cu")
		(net "PCIE_TX1_N")
	)
	(segment
		(start 125.37172 150.19983)
		(end 125.4864 149.82947)
		(width 0.127)
		(layer "In3.Cu")
		(net "PCIE_TX1_N")
	)
	(segment
		(start 125.24464 147.79096)
		(end 125.3213 147.79096)
		(width 0.127)
		(layer "In3.Cu")
		(net "PCIE_TX1_N")
	)
	(segment
		(start 125.4864 147.21946)
		(end 125.4864 146.77495)
		(width 0.127)
		(layer "In3.Cu")
		(net "PCIE_TX1_N")
	)
	(segment
		(start 125.4864 149.82947)
		(end 125.4864 149.50546)
		(width 0.127)
		(layer "In3.Cu")
		(net "PCIE_TX1_N")
	)
	(segment
		(start 125.29588 149.31496)
		(end 125.2959 149.31496)
		(width 0.127)
		(layer "In3.Cu")
		(net "PCIE_TX1_N")
	)
	(segment
		(start 125.3542 150.2242)
		(end 125.35461 150.22366)
		(width 0.127)
		(layer "In3.Cu")
		(net "PCIE_TX1_N")
	)
	(segment
		(start 129.91515 141.935)
		(end 174.26264 141.935)
		(width 0.127)
		(layer "In3.Cu")
		(net "PCIE_TX1_N")
	)
	(segment
		(start 125.4864 146.77495)
		(end 125.4864 146.36419)
		(width 0.127)
		(layer "In3.Cu")
		(net "PCIE_TX1_N")
	)
	(segment
		(start 125.24464 147.40996)
		(end 125.2959 147.40996)
		(width 0.127)
		(layer "In3.Cu")
		(net "PCIE_TX1_N")
	)
	(segment
		(start 176.2364 139.86805)
		(end 176.2364 138.14011)
		(width 0.127)
		(layer "In3.Cu")
		(net "PCIE_TX1_N")
	)
	(segment
		(start 125.29588 148.93396)
		(end 125.3213 148.93396)
		(width 0.127)
		(layer "In3.Cu")
		(net "PCIE_TX1_N")
	)
	(segment
		(start 126.31151 144.37219)
		(end 127.9239 142.75981)
		(width 0.127)
		(layer "In3.Cu")
		(net "PCIE_TX1_N")
	)
	(arc
		(start 125.24464 147.79096)
		(mid 125.05414 147.60046)
		(end 125.24464 147.40996)
		(width 0.127)
		(layer "In3.Cu")
		(net "PCIE_TX1_N")
	)
	(arc
		(start 125.3213 147.79096)
		(mid 125.5118 147.98146)
		(end 125.3213 148.17196)
		(width 0.127)
		(layer "In3.Cu")
		(net "PCIE_TX1_N")
	)
	(arc
		(start 125.2959 149.31496)
		(mid 125.430604 149.370756)
		(end 125.4864 149.50546)
		(width 0.127)
		(layer "In3.Cu")
		(net "PCIE_TX1_N")
	)
	(arc
		(start 125.354195 150.224197)
		(mid 125.338159 150.244173)
		(end 125.321158 150.263334)
		(width 0.127)
		(layer "In3.Cu")
		(net "PCIE_TX1_N")
	)
	(arc
		(start 125.27436 148.55296)
		(mid 125.08386 148.36246)
		(end 125.27436 148.17196)
		(width 0.127)
		(layer "In3.Cu")
		(net "PCIE_TX1_N")
	)
	(arc
		(start 125.3213 148.55296)
		(mid 125.5118 148.74346)
		(end 125.3213 148.93396)
		(width 0.127)
		(layer "In3.Cu")
		(net "PCIE_TX1_N")
	)
	(arc
		(start 127.923895 142.759805)
		(mid 128.837491 142.14936)
		(end 129.91515 141.935)
		(width 0.127)
		(layer "In3.Cu")
		(net "PCIE_TX1_N")
	)
	(arc
		(start 125.4864 146.36419)
		(mid 125.700839 145.286133)
		(end 126.311509 144.372199)
		(width 0.127)
		(layer "In3.Cu")
		(net "PCIE_TX1_N")
	)
	(arc
		(start 125.321158 150.263333)
		(mid 124.951856 150.42845)
		(end 124.576097 150.278605)
		(width 0.127)
		(layer "In3.Cu")
		(net "PCIE_TX1_N")
	)
	(arc
		(start 125.4864 147.21946)
		(mid 125.430604 147.354164)
		(end 125.2959 147.40996)
		(width 0.127)
		(layer "In3.Cu")
		(net "PCIE_TX1_N")
	)
	(arc
		(start 176.0261 137.6324)
		(mid 176.181745 137.865339)
		(end 176.2364 138.14011)
		(width 0.127)
		(layer "In3.Cu")
		(net "PCIE_TX1_N")
	)
	(arc
		(start 125.371719 150.199831)
		(mid 125.363295 150.211839)
		(end 125.354604 150.223656)
		(width 0.127)
		(layer "In3.Cu")
		(net "PCIE_TX1_N")
	)
	(arc
		(start 125.29588 149.31496)
		(mid 125.10538 149.12446)
		(end 125.29588 148.93396)
		(width 0.127)
		(layer "In3.Cu")
		(net "PCIE_TX1_N")
	)
	(arc
		(start 176.2364 139.86805)
		(mid 176.074046 140.684256)
		(end 175.611703 141.376203)
		(width 0.127)
		(layer "In3.Cu")
		(net "PCIE_TX1_N")
	)
	(arc
		(start 175.611701 141.376201)
		(mid 174.992747 141.789773)
		(end 174.26264 141.935)
		(width 0.127)
		(layer "In3.Cu")
		(net "PCIE_TX1_N")
	)
	(segment
		(start 176.83583 137.36369)
		(end 176.83583 135.50523)
		(width 0.127)
		(layer "F.Cu")
		(net "PCIE_TX1_P")
	)
	(via
		(at 176.7261 137.6286)
		(size 0.4064)
		(drill 0.2032)
		(layers "F.Cu" "B.Cu")
		(tenting
			(front yes)
			(back yes)
		)
		(net "PCIE_TX1_P")
	)
	(via
		(at 123.5761 150.2786)
		(size 0.4064)
		(drill 0.2032)
		(layers "F.Cu" "B.Cu")
		(tenting
			(front yes)
			(back yes)
		)
		(net "PCIE_TX1_P")
	)
	(arc
		(start 176.83583 137.36369)
		(mid 176.807312 137.507059)
		(end 176.7261 137.6286)
		(width 0.127)
		(layer "F.Cu")
		(net "PCIE_TX1_P")
	)
	(segment
		(start 123.5761 151.32721)
		(end 123.5761 150.2786)
		(width 0.127)
		(layer "B.Cu")
		(net "PCIE_TX1_P")
	)
	(arc
		(start 123.5761 151.32721)
		(mid 123.572722 151.344193)
		(end 123.563101 151.358591)
		(width 0.127)
		(layer "B.Cu")
		(net "PCIE_TX1_P")
	)
	(segment
		(start 126.50975 144.56908)
		(end 128.12049 142.95835)
		(width 0.127)
		(layer "In3.Cu")
		(net "PCIE_TX1_P")
	)
	(segment
		(start 176.5158 139.87187)
		(end 176.5158 138.14011)
		(width 0.127)
		(layer "In3.Cu")
		(net "PCIE_TX1_P")
	)
	(segment
		(start 176.7261 137.6324)
		(end 176.7261 137.6286)
		(width 0.127)
		(layer "In3.Cu")
		(net "PCIE_TX1_P")
	)
	(segment
		(start 125.7658 149.84976)
		(end 125.7658 146.36514)
		(width 0.127)
		(layer "In3.Cu")
		(net "PCIE_TX1_P")
	)
	(segment
		(start 123.73229 150.4348)
		(end 123.73229 150.4348)
		(width 0.127)
		(layer "In3.Cu")
		(net "PCIE_TX1_P")
	)
	(segment
		(start 129.91654 142.2144)
		(end 174.2636 142.2144)
		(width 0.127)
		(layer "In3.Cu")
		(net "PCIE_TX1_P")
	)
	(segment
		(start 175.80859 141.57444)
		(end 175.81197 141.57106)
		(width 0.127)
		(layer "In3.Cu")
		(net "PCIE_TX1_P")
	)
	(segment
		(start 123.5761 150.2786)
		(end 123.73229 150.4348)
		(width 0.127)
		(layer "In3.Cu")
		(net "PCIE_TX1_P")
	)
	(segment
		(start 125.7658 149.8509)
		(end 125.7658 149.84976)
		(width 0.127)
		(layer "In3.Cu")
		(net "PCIE_TX1_P")
	)
	(arc
		(start 176.5158 139.871873)
		(mid 176.33288 140.791468)
		(end 175.811971 141.571062)
		(width 0.127)
		(layer "In3.Cu")
		(net "PCIE_TX1_P")
	)
	(arc
		(start 175.808593 141.574443)
		(mid 175.099744 142.048081)
		(end 174.2636 142.2144)
		(width 0.127)
		(layer "In3.Cu")
		(net "PCIE_TX1_P")
	)
	(arc
		(start 125.7658 146.36514)
		(mid 125.959146 145.393124)
		(end 126.509749 144.569089)
		(width 0.127)
		(layer "In3.Cu")
		(net "PCIE_TX1_P")
	)
	(arc
		(start 125.76579 149.850895)
		(mid 125.654316 150.285644)
		(end 125.347406 150.613118)
		(width 0.127)
		(layer "In3.Cu")
		(net "PCIE_TX1_P")
	)
	(arc
		(start 128.120489 142.958349)
		(mid 128.944524 142.407746)
		(end 129.91654 142.2144)
		(width 0.127)
		(layer "In3.Cu")
		(net "PCIE_TX1_P")
	)
	(arc
		(start 125.347413 150.613118)
		(mid 124.508485 150.808083)
		(end 123.732297 150.434794)
		(width 0.127)
		(layer "In3.Cu")
		(net "PCIE_TX1_P")
	)
	(arc
		(start 176.5158 138.14011)
		(mid 176.570455 137.865341)
		(end 176.726098 137.632403)
		(width 0.127)
		(layer "In3.Cu")
		(net "PCIE_TX1_P")
	)
	(segment
		(start 174.83583 132.91887)
		(end 174.83583 131.45545)
		(width 0.127)
		(layer "F.Cu")
		(net "PCIE_TX0_N")
	)
	(via
		(at 119.6761 150.2786)
		(size 0.4064)
		(drill 0.2032)
		(layers "F.Cu" "B.Cu")
		(tenting
			(front yes)
			(back yes)
		)
		(net "PCIE_TX0_N")
	)
	(via
		(at 174.7261 133.0286)
		(size 0.4064)
		(drill 0.2032)
		(layers "F.Cu" "B.Cu")
		(tenting
			(front yes)
			(back yes)
		)
		(net "PCIE_TX0_N")
	)
	(arc
		(start 174.83583 132.91887)
		(mid 174.803691 132.996461)
		(end 174.7261 133.0286)
		(width 0.127)
		(layer "F.Cu")
		(net "PCIE_TX0_N")
	)
	(segment
		(start 119.6761 151.3578)
		(end 119.6761 150.2786)
		(width 0.127)
		(layer "B.Cu")
		(net "PCIE_TX0_N")
	)
	(segment
		(start 119.6761 151.3578)
		(end 119.6769 151.3586)
		(width 0.127)
		(layer "B.Cu")
		(net "PCIE_TX0_N")
	)
	(segment
		(start 172.62851 136.2962)
		(end 173.8845 136.2962)
		(width 0.127)
		(layer "In3.Cu")
		(net "PCIE_TX0_N")
	)
	(segment
		(start 171.3953 138.03093)
		(end 171.3953 137.52941)
		(width 0.127)
		(layer "In3.Cu")
		(net "PCIE_TX0_N")
	)
	(segment
		(start 174.7261 133.0324)
		(end 174.7261 133.0286)
		(width 0.127)
		(layer "In3.Cu")
		(net "PCIE_TX0_N")
	)
	(segment
		(start 118.8233 150.66721)
		(end 118.82444 150.66721)
		(width 0.127)
		(layer "In3.Cu")
		(net "PCIE_TX0_N")
	)
	(segment
		(start 118.82444 150.66721)
		(end 119.28749 150.66721)
		(width 0.127)
		(layer "In3.Cu")
		(net "PCIE_TX0_N")
	)
	(segment
		(start 118.54299 150.66721)
		(end 118.8233 150.66721)
		(width 0.127)
		(layer "In3.Cu")
		(net "PCIE_TX0_N")
	)
	(segment
		(start 117.37514 149.90496)
		(end 117.37514 149.90496)
		(width 0.127)
		(layer "In3.Cu")
		(net "PCIE_TX0_N")
	)
	(segment
		(start 171.43229 137.36001)
		(end 172.45911 136.33319)
		(width 0.127)
		(layer "In3.Cu")
		(net "PCIE_TX0_N")
	)
	(segment
		(start 117.37514 149.90496)
		(end 117.60374 150.13357)
		(width 0.127)
		(layer "In3.Cu")
		(net "PCIE_TX0_N")
	)
	(segment
		(start 174.04244 136.23085)
		(end 174.04256 136.23073)
		(width 0.127)
		(layer "In3.Cu")
		(net "PCIE_TX0_N")
	)
	(segment
		(start 118.04191 146.96346)
		(end 124.02356 140.98181)
		(width 0.127)
		(layer "In3.Cu")
		(net "PCIE_TX0_N")
	)
	(segment
		(start 117.2171 149.52344)
		(end 117.2171 148.95472)
		(width 0.127)
		(layer "In3.Cu")
		(net "PCIE_TX0_N")
	)
	(segment
		(start 170.36931 139.88759)
		(end 170.80685 139.45005)
		(width 0.127)
		(layer "In3.Cu")
		(net "PCIE_TX0_N")
	)
	(segment
		(start 118.32225 150.6162)
		(end 118.3761 150.6162)
		(width 0.127)
		(layer "In3.Cu")
		(net "PCIE_TX0_N")
	)
	(segment
		(start 126.01482 140.157)
		(end 169.7189 140.157)
		(width 0.127)
		(layer "In3.Cu")
		(net "PCIE_TX0_N")
	)
	(segment
		(start 174.7261 133.0324)
		(end 174.80361 133.1099)
		(width 0.127)
		(layer "In3.Cu")
		(net "PCIE_TX0_N")
	)
	(segment
		(start 174.68829 135.585)
		(end 174.68829 134.02948)
		(width 0.127)
		(layer "In3.Cu")
		(net "PCIE_TX0_N")
	)
	(segment
		(start 174.9364 133.4305)
		(end 174.9364 133.4305)
		(width 0.127)
		(layer "In3.Cu")
		(net "PCIE_TX0_N")
	)
	(segment
		(start 174.04256 136.23073)
		(end 174.68829 135.585)
		(width 0.127)
		(layer "In3.Cu")
		(net "PCIE_TX0_N")
	)
	(segment
		(start 117.60374 150.13357)
		(end 117.91813 150.44796)
		(width 0.127)
		(layer "In3.Cu")
		(net "PCIE_TX0_N")
	)
	(arc
		(start 174.9364 133.4305)
		(mid 174.901888 133.604005)
		(end 174.803605 133.751095)
		(width 0.127)
		(layer "In3.Cu")
		(net "PCIE_TX0_N")
	)
	(arc
		(start 174.68829 134.02948)
		(mid 174.718259 133.878818)
		(end 174.803602 133.751092)
		(width 0.127)
		(layer "In3.Cu")
		(net "PCIE_TX0_N")
	)
	(arc
		(start 171.3953 138.03093)
		(mid 171.242356 138.799071)
		(end 170.806852 139.450046)
		(width 0.127)
		(layer "In3.Cu")
		(net "PCIE_TX0_N")
	)
	(arc
		(start 118.322245 150.61621)
		(mid 118.103346 150.57253)
		(end 117.918122 150.447962)
		(width 0.127)
		(layer "In3.Cu")
		(net "PCIE_TX0_N")
	)
	(arc
		(start 117.375133 149.904967)
		(mid 117.258171 149.729921)
		(end 117.217099 149.52344)
		(width 0.127)
		(layer "In3.Cu")
		(net "PCIE_TX0_N")
	)
	(arc
		(start 124.023565 140.981805)
		(mid 124.937161 140.37136)
		(end 126.01482 140.157)
		(width 0.127)
		(layer "In3.Cu")
		(net "PCIE_TX0_N")
	)
	(arc
		(start 174.042439 136.23085)
		(mid 173.969962 136.279217)
		(end 173.8845 136.2962)
		(width 0.127)
		(layer "In3.Cu")
		(net "PCIE_TX0_N")
	)
	(arc
		(start 119.6761 150.2786)
		(mid 119.562279 150.553389)
		(end 119.28749 150.66721)
		(width 0.127)
		(layer "In3.Cu")
		(net "PCIE_TX0_N")
	)
	(arc
		(start 118.542985 150.667207)
		(mid 118.50681 150.661706)
		(end 118.473705 150.64612)
		(width 0.127)
		(layer "In3.Cu")
		(net "PCIE_TX0_N")
	)
	(arc
		(start 172.459104 136.333192)
		(mid 172.541811 136.305556)
		(end 172.62851 136.2962)
		(width 0.127)
		(layer "In3.Cu")
		(net "PCIE_TX0_N")
	)
	(arc
		(start 117.2171 148.95472)
		(mid 117.431461 147.877057)
		(end 118.041908 146.963458)
		(width 0.127)
		(layer "In3.Cu")
		(net "PCIE_TX0_N")
	)
	(arc
		(start 174.803612 133.109898)
		(mid 174.901897 133.256991)
		(end 174.93641 133.4305)
		(width 0.127)
		(layer "In3.Cu")
		(net "PCIE_TX0_N")
	)
	(arc
		(start 170.369311 139.887591)
		(mid 170.0709 140.086983)
		(end 169.7189 140.157)
		(width 0.127)
		(layer "In3.Cu")
		(net "PCIE_TX0_N")
	)
	(arc
		(start 118.3761 150.6162)
		(mid 118.427146 150.623849)
		(end 118.473709 150.646123)
		(width 0.127)
		(layer "In3.Cu")
		(net "PCIE_TX0_N")
	)
	(arc
		(start 171.3953 137.52941)
		(mid 171.404655 137.442713)
		(end 171.43229 137.360007)
		(width 0.127)
		(layer "In3.Cu")
		(net "PCIE_TX0_N")
	)
	(segment
		(start 175.33596 132.93846)
		(end 175.33596 131.45545)
		(width 0.127)
		(layer "F.Cu")
		(net "PCIE_TX0_P")
	)
	(via
		(at 175.4261 133.0286)
		(size 0.4064)
		(drill 0.2032)
		(layers "F.Cu" "B.Cu")
		(tenting
			(front yes)
			(back yes)
		)
		(net "PCIE_TX0_P")
	)
	(via
		(at 118.61112 150.1395)
		(size 0.4064)
		(drill 0.2032)
		(layers "F.Cu" "B.Cu")
		(tenting
			(front yes)
			(back yes)
		)
		(net "PCIE_TX0_P")
	)
	(arc
		(start 175.4261 133.0286)
		(mid 175.362361 133.002199)
		(end 175.33596 132.93846)
		(width 0.127)
		(layer "F.Cu")
		(net "PCIE_TX0_P")
	)
	(segment
		(start 118.6095 150.14126)
		(end 118.61082 150.1398)
		(width 0.127)
		(layer "B.Cu")
		(net "PCIE_TX0_P")
	)
	(segment
		(start 118.5761 150.29143)
		(end 118.57679 150.22501)
		(width 0.127)
		(layer "B.Cu")
		(net "PCIE_TX0_P")
	)
	(segment
		(start 118.61082 150.1398)
		(end 118.61112 150.1395)
		(width 0.127)
		(layer "B.Cu")
		(net "PCIE_TX0_P")
	)
	(segment
		(start 118.5761 151.35)
		(end 118.5761 150.29143)
		(width 0.127)
		(layer "B.Cu")
		(net "PCIE_TX0_P")
	)
	(segment
		(start 118.5761 151.35)
		(end 118.5847 151.3586)
		(width 0.127)
		(layer "B.Cu")
		(net "PCIE_TX0_P")
	)
	(arc
		(start 118.576797 150.225012)
		(mid 118.585489 150.180146)
		(end 118.6095 150.141261)
		(width 0.127)
		(layer "B.Cu")
		(net "PCIE_TX0_P")
	)
	(segment
		(start 117.57271 149.7074)
		(end 118.00438 150.13908)
		(width 0.127)
		(layer "In3.Cu")
		(net "PCIE_TX0_P")
	)
	(segment
		(start 171.6747 137.92765)
		(end 171.6747 137.52941)
		(width 0.127)
		(layer "In3.Cu")
		(net "PCIE_TX0_P")
	)
	(segment
		(start 118.61082 150.13979)
		(end 118.61112 150.1395)
		(width 0.127)
		(layer "In3.Cu")
		(net "PCIE_TX0_P")
	)
	(segment
		(start 171.71149 137.44002)
		(end 172.5391 136.61241)
		(width 0.127)
		(layer "In3.Cu")
		(net "PCIE_TX0_P")
	)
	(segment
		(start 175.4261 133.0324)
		(end 175.4261 133.0286)
		(width 0.127)
		(layer "In3.Cu")
		(net "PCIE_TX0_P")
	)
	(segment
		(start 126.0162 140.4364)
		(end 169.71986 140.4364)
		(width 0.127)
		(layer "In3.Cu")
		(net "PCIE_TX0_P")
	)
	(segment
		(start 118.24045 147.16005)
		(end 124.22015 141.18035)
		(width 0.127)
		(layer "In3.Cu")
		(net "PCIE_TX0_P")
	)
	(segment
		(start 174.96769 135.58571)
		(end 174.96769 134.08735)
		(width 0.127)
		(layer "In3.Cu")
		(net "PCIE_TX0_P")
	)
	(segment
		(start 174.23914 136.42928)
		(end 174.88635 135.78207)
		(width 0.127)
		(layer "In3.Cu")
		(net "PCIE_TX0_P")
	)
	(segment
		(start 170.5662 140.08583)
		(end 170.93247 139.71957)
		(width 0.127)
		(layer "In3.Cu")
		(net "PCIE_TX0_P")
	)
	(segment
		(start 118.60487 150.1417)
		(end 118.61082 150.13979)
		(width 0.127)
		(layer "In3.Cu")
		(net "PCIE_TX0_P")
	)
	(segment
		(start 172.62851 136.5756)
		(end 173.88589 136.5756)
		(width 0.127)
		(layer "In3.Cu")
		(net "PCIE_TX0_P")
	)
	(segment
		(start 175.38951 133.06898)
		(end 175.4261 133.0324)
		(width 0.127)
		(layer "In3.Cu")
		(net "PCIE_TX0_P")
	)
	(segment
		(start 117.4965 149.52343)
		(end 117.4965 148.9561)
		(width 0.127)
		(layer "In3.Cu")
		(net "PCIE_TX0_P")
	)
	(arc
		(start 175.2158 133.48836)
		(mid 175.170653 133.71533)
		(end 175.042085 133.907745)
		(width 0.127)
		(layer "In3.Cu")
		(net "PCIE_TX0_P")
	)
	(arc
		(start 174.239146 136.429276)
		(mid 174.077071 136.537571)
		(end 173.88589 136.575599)
		(width 0.127)
		(layer "In3.Cu")
		(net "PCIE_TX0_P")
	)
	(arc
		(start 124.220149 141.180349)
		(mid 125.044184 140.629746)
		(end 126.0162 140.4364)
		(width 0.127)
		(layer "In3.Cu")
		(net "PCIE_TX0_P")
	)
	(arc
		(start 174.96769 134.08735)
		(mid 174.987025 133.990145)
		(end 175.042088 133.907738)
		(width 0.127)
		(layer "In3.Cu")
		(net "PCIE_TX0_P")
	)
	(arc
		(start 174.96769 135.58571)
		(mid 174.946551 135.691981)
		(end 174.886354 135.782074)
		(width 0.127)
		(layer "In3.Cu")
		(net "PCIE_TX0_P")
	)
	(arc
		(start 171.6747 137.92765)
		(mid 171.481799 138.897427)
		(end 170.932465 139.719565)
		(width 0.127)
		(layer "In3.Cu")
		(net "PCIE_TX0_P")
	)
	(arc
		(start 117.572712 149.707398)
		(mid 117.516314 149.622993)
		(end 117.49651 149.52343)
		(width 0.127)
		(layer "In3.Cu")
		(net "PCIE_TX0_P")
	)
	(arc
		(start 118.30779 150.26476)
		(mid 118.143584 150.232097)
		(end 118.004378 150.139082)
		(width 0.127)
		(layer "In3.Cu")
		(net "PCIE_TX0_P")
	)
	(arc
		(start 118.604874 150.141704)
		(mid 118.468571 150.232779)
		(end 118.30779 150.26476)
		(width 0.127)
		(layer "In3.Cu")
		(net "PCIE_TX0_P")
	)
	(arc
		(start 170.566203 140.085833)
		(mid 170.177898 140.34529)
		(end 169.71986 140.4364)
		(width 0.127)
		(layer "In3.Cu")
		(net "PCIE_TX0_P")
	)
	(arc
		(start 172.539099 136.612407)
		(mid 172.580165 136.585161)
		(end 172.62851 136.5756)
		(width 0.127)
		(layer "In3.Cu")
		(net "PCIE_TX0_P")
	)
	(arc
		(start 117.4965 148.9561)
		(mid 117.689846 147.984084)
		(end 118.240449 147.160049)
		(width 0.127)
		(layer "In3.Cu")
		(net "PCIE_TX0_P")
	)
	(arc
		(start 171.6747 137.52941)
		(mid 171.684256 137.48108)
		(end 171.711484 137.440022)
		(width 0.127)
		(layer "In3.Cu")
		(net "PCIE_TX0_P")
	)
	(arc
		(start 175.2158 133.48836)
		(mid 175.260946 133.261394)
		(end 175.389512 133.068982)
		(width 0.127)
		(layer "In3.Cu")
		(net "PCIE_TX0_P")
	)
	(segment
		(start 173.3261 137.6286)
		(end 173.3261 137.27002)
		(width 0.127)
		(layer "F.Cu")
		(net "PCIE_CLK_P")
	)
	(segment
		(start 173.83583 136.03942)
		(end 173.83583 135.50523)
		(width 0.127)
		(layer "F.Cu")
		(net "PCIE_CLK_P")
	)
	(via
		(at 115.5761 150.2786)
		(size 0.4064)
		(drill 0.2032)
		(layers "F.Cu" "B.Cu")
		(tenting
			(front yes)
			(back yes)
		)
		(net "PCIE_CLK_P")
	)
	(via
		(at 173.3261 137.6286)
		(size 0.4064)
		(drill 0.2032)
		(layers "F.Cu" "B.Cu")
		(tenting
			(front yes)
			(back yes)
		)
		(net "PCIE_CLK_P")
	)
	(arc
		(start 173.3261 137.27002)
		(mid 173.352089 137.139364)
		(end 173.4261 137.0286)
		(width 0.127)
		(layer "F.Cu")
		(net "PCIE_CLK_P")
	)
	(arc
		(start 173.83584 136.03942)
		(mid 173.729354 136.574764)
		(end 173.426106 137.028606)
		(width 0.127)
		(layer "F.Cu")
		(net "PCIE_CLK_P")
	)
	(segment
		(start 115.5761 151.3248)
		(end 115.5761 150.2786)
		(width 0.127)
		(layer "B.Cu")
		(net "PCIE_CLK_P")
	)
	(arc
		(start 115.5761 151.3248)
		(mid 115.572461 151.343092)
		(end 115.5621 151.3586)
		(width 0.127)
		(layer "B.Cu")
		(net "PCIE_CLK_P")
	)
	(segment
		(start 173.3261 137.6324)
		(end 173.3261 137.6286)
		(width 0.127)
		(layer "In3.Cu")
		(net "PCIE_CLK_P")
	)
	(segment
		(start 118.09567 151.858)
		(end 120.27732 151.858)
		(width 0.127)
		(layer "In3.Cu")
		(net "PCIE_CLK_P")
	)
	(segment
		(start 122.7797 145.1608)
		(end 126.07435 141.86615)
		(width 0.127)
		(layer "In3.Cu")
		(net "PCIE_CLK_P")
	)
	(segment
		(start 127.8704 141.1222)
		(end 169.1882 141.1222)
		(width 0.127)
		(layer "In3.Cu")
		(net "PCIE_CLK_P")
	)
	(segment
		(start 115.61682 150.29547)
		(end 115.8094 150.29547)
		(width 0.127)
		(layer "In3.Cu")
		(net "PCIE_CLK_P")
	)
	(segment
		(start 173.3261 137.6324)
		(end 173.3261 137.6324)
		(width 0.127)
		(layer "In3.Cu")
		(net "PCIE_CLK_P")
	)
	(segment
		(start 173.11581 138.14081)
		(end 173.11581 138.14011)
		(width 0.127)
		(layer "In3.Cu")
		(net "PCIE_CLK_P")
	)
	(segment
		(start 122.3658 148.71758)
		(end 122.3658 146.16004)
		(width 0.127)
		(layer "In3.Cu")
		(net "PCIE_CLK_P")
	)
	(segment
		(start 120.4728 151.77703)
		(end 121.541 150.70883)
		(width 0.127)
		(layer "In3.Cu")
		(net "PCIE_CLK_P")
	)
	(segment
		(start 173.3261 137.6324)
		(end 173.3261 137.6324)
		(width 0.127)
		(layer "In3.Cu")
		(net "PCIE_CLK_P")
	)
	(segment
		(start 116.01451 150.66891)
		(end 116.5728 151.2272)
		(width 0.127)
		(layer "In3.Cu")
		(net "PCIE_CLK_P")
	)
	(segment
		(start 171.17946 140.29739)
		(end 172.96007 138.51678)
		(width 0.127)
		(layer "In3.Cu")
		(net "PCIE_CLK_P")
	)
	(segment
		(start 115.9364 150.48033)
		(end 115.9364 150.42247)
		(width 0.127)
		(layer "In3.Cu")
		(net "PCIE_CLK_P")
	)
	(arc
		(start 115.899203 150.332667)
		(mid 115.926733 150.373869)
		(end 115.936401 150.42247)
		(width 0.127)
		(layer "In3.Cu")
		(net "PCIE_CLK_P")
	)
	(arc
		(start 115.8094 150.29547)
		(mid 115.858001 150.305137)
		(end 115.899203 150.332667)
		(width 0.127)
		(layer "In3.Cu")
		(net "PCIE_CLK_P")
	)
	(arc
		(start 173.1158 138.14011)
		(mid 173.170455 137.865341)
		(end 173.326098 137.632403)
		(width 0.127)
		(layer "In3.Cu")
		(net "PCIE_CLK_P")
	)
	(arc
		(start 173.1158 138.140816)
		(mid 173.075325 138.344289)
		(end 172.960066 138.516786)
		(width 0.127)
		(layer "In3.Cu")
		(net "PCIE_CLK_P")
	)
	(arc
		(start 120.4728 151.77703)
		(mid 120.383113 151.836957)
		(end 120.27732 151.858)
		(width 0.127)
		(layer "In3.Cu")
		(net "PCIE_CLK_P")
	)
	(arc
		(start 171.179462 140.297392)
		(mid 170.265863 140.907839)
		(end 169.1882 141.1222)
		(width 0.127)
		(layer "In3.Cu")
		(net "PCIE_CLK_P")
	)
	(arc
		(start 118.09567 151.858)
		(mid 117.271496 151.694062)
		(end 116.572795 151.227205)
		(width 0.127)
		(layer "In3.Cu")
		(net "PCIE_CLK_P")
	)
	(arc
		(start 122.36581 148.71758)
		(mid 122.15145 149.79524)
		(end 121.541005 150.708835)
		(width 0.127)
		(layer "In3.Cu")
		(net "PCIE_CLK_P")
	)
	(arc
		(start 115.61682 150.29547)
		(mid 115.594781 150.291086)
		(end 115.576098 150.278602)
		(width 0.127)
		(layer "In3.Cu")
		(net "PCIE_CLK_P")
	)
	(arc
		(start 116.014512 150.668908)
		(mid 115.956701 150.582388)
		(end 115.9364 150.48033)
		(width 0.127)
		(layer "In3.Cu")
		(net "PCIE_CLK_P")
	)
	(arc
		(start 126.074349 141.866149)
		(mid 126.898384 141.315546)
		(end 127.8704 141.1222)
		(width 0.127)
		(layer "In3.Cu")
		(net "PCIE_CLK_P")
	)
	(arc
		(start 122.3658 146.160037)
		(mid 122.47337 145.61925)
		(end 122.779702 145.160792)
		(width 0.127)
		(layer "In3.Cu")
		(net "PCIE_CLK_P")
	)
	(segment
		(start 172.83823 137.11646)
		(end 173.1261 136.8286)
		(width 0.127)
		(layer "F.Cu")
		(net "PCIE_CLK_N")
	)
	(segment
		(start 173.33596 136.32195)
		(end 173.33596 135.50523)
		(width 0.127)
		(layer "F.Cu")
		(net "PCIE_CLK_N")
	)
	(via
		(at 116.5761 150.2786)
		(size 0.4064)
		(drill 0.2032)
		(layers "F.Cu" "B.Cu")
		(tenting
			(front yes)
			(back yes)
		)
		(net "PCIE_CLK_N")
	)
	(via
		(at 172.6261 137.6286)
		(size 0.4064)
		(drill 0.2032)
		(layers "F.Cu" "B.Cu")
		(tenting
			(front yes)
			(back yes)
		)
		(net "PCIE_CLK_N")
	)
	(arc
		(start 172.6261 137.6286)
		(mid 172.681232 137.351434)
		(end 172.838234 137.116464)
		(width 0.127)
		(layer "F.Cu")
		(net "PCIE_CLK_N")
	)
	(arc
		(start 173.33597 136.32195)
		(mid 173.281428 136.59615)
		(end 173.126106 136.828606)
		(width 0.127)
		(layer "F.Cu")
		(net "PCIE_CLK_N")
	)
	(segment
		(start 116.5761 151.3566)
		(end 116.5761 150.2786)
		(width 0.127)
		(layer "B.Cu")
		(net "PCIE_CLK_N")
	)
	(segment
		(start 116.5761 151.3566)
		(end 116.5781 151.3586)
		(width 0.127)
		(layer "B.Cu")
		(net "PCIE_CLK_N")
	)
	(segment
		(start 117.5477 151.42741)
		(end 117.5477 151.42741)
		(width 0.127)
		(layer "In3.Cu")
		(net "PCIE_CLK_N")
	)
	(segment
		(start 117.1396 151.31562)
		(end 117.5477 151.42741)
		(width 0.127)
		(layer "In3.Cu")
		(net "PCIE_CLK_N")
	)
	(segment
		(start 172.6261 137.63239)
		(end 172.6261 137.6286)
		(width 0.127)
		(layer "In3.Cu")
		(net "PCIE_CLK_N")
	)
	(segment
		(start 118.80454 151.5786)
		(end 118.80455 151.5786)
		(width 0.127)
		(layer "In3.Cu")
		(net "PCIE_CLK_N")
	)
	(segment
		(start 122.58129 144.96408)
		(end 125.87776 141.66761)
		(width 0.127)
		(layer "In3.Cu")
		(net "PCIE_CLK_N")
	)
	(segment
		(start 118.36003 151.5786)
		(end 118.80454 151.5786)
		(width 0.127)
		(layer "In3.Cu")
		(net "PCIE_CLK_N")
	)
	(segment
		(start 122.0864 148.71619)
		(end 122.0864 146.15885)
		(width 0.127)
		(layer "In3.Cu")
		(net "PCIE_CLK_N")
	)
	(segment
		(start 120.2761 151.5786)
		(end 121.34245 150.51224)
		(width 0.127)
		(layer "In3.Cu")
		(net "PCIE_CLK_N")
	)
	(segment
		(start 118.16953 151.3881)
		(end 118.16953 151.12243)
		(width 0.127)
		(layer "In3.Cu")
		(net "PCIE_CLK_N")
	)
	(segment
		(start 127.86902 140.8428)
		(end 169.18682 140.8428)
		(width 0.127)
		(layer "In3.Cu")
		(net "PCIE_CLK_N")
	)
	(segment
		(start 170.98287 140.09885)
		(end 172.76201 138.31971)
		(width 0.127)
		(layer "In3.Cu")
		(net "PCIE_CLK_N")
	)
	(segment
		(start 117.78853 151.24368)
		(end 117.78853 151.12243)
		(width 0.127)
		(layer "In3.Cu")
		(net "PCIE_CLK_N")
	)
	(segment
		(start 116.2158 150.42247)
		(end 116.2158 150.42247)
		(width 0.127)
		(layer "In3.Cu")
		(net "PCIE_CLK_N")
	)
	(segment
		(start 117.0761 151.27629)
		(end 117.07611 151.27629)
		(width 0.127)
		(layer "In3.Cu")
		(net "PCIE_CLK_N")
	)
	(segment
		(start 116.34281 150.29547)
		(end 116.53538 150.29547)
		(width 0.127)
		(layer "In3.Cu")
		(net "PCIE_CLK_N")
	)
	(segment
		(start 118.80454 151.5786)
		(end 120.2761 151.5786)
		(width 0.127)
		(layer "In3.Cu")
		(net "PCIE_CLK_N")
	)
	(segment
		(start 116.253 150.51227)
		(end 116.76756 151.02684)
		(width 0.127)
		(layer "In3.Cu")
		(net "PCIE_CLK_N")
	)
	(arc
		(start 125.877765 141.667605)
		(mid 126.791361 141.05716)
		(end 127.86902 140.8428)
		(width 0.127)
		(layer "In3.Cu")
		(net "PCIE_CLK_N")
	)
	(arc
		(start 122.0864 146.15885)
		(mid 122.215018 145.512241)
		(end 122.581293 144.964073)
		(width 0.127)
		(layer "In3.Cu")
		(net "PCIE_CLK_N")
	)
	(arc
		(start 122.0864 148.71619)
		(mid 121.893054 149.688206)
		(end 121.342451 150.512241)
		(width 0.127)
		(layer "In3.Cu")
		(net "PCIE_CLK_N")
	)
	(arc
		(start 117.78853 151.12243)
		(mid 117.97903 150.93193)
		(end 118.16953 151.12243)
		(width 0.127)
		(layer "In3.Cu")
		(net "PCIE_CLK_N")
	)
	(arc
		(start 116.252987 150.512273)
		(mid 116.225457 150.471071)
		(end 116.215789 150.42247)
		(width 0.127)
		(layer "In3.Cu")
		(net "PCIE_CLK_N")
	)
	(arc
		(start 118.36003 151.5786)
		(mid 118.225326 151.522804)
		(end 118.16953 151.3881)
		(width 0.127)
		(layer "In3.Cu")
		(net "PCIE_CLK_N")
	)
	(arc
		(start 172.626107 137.632393)
		(mid 172.781754 137.865336)
		(end 172.83641 138.14011)
		(width 0.127)
		(layer "In3.Cu")
		(net "PCIE_CLK_N")
	)
	(arc
		(start 116.253 150.33267)
		(mid 116.294205 150.305138)
		(end 116.34281 150.295469)
		(width 0.127)
		(layer "In3.Cu")
		(net "PCIE_CLK_N")
	)
	(arc
		(start 170.982871 140.098851)
		(mid 170.158836 140.649454)
		(end 169.18682 140.8428)
		(width 0.127)
		(layer "In3.Cu")
		(net "PCIE_CLK_N")
	)
	(arc
		(start 117.076098 151.276288)
		(mid 116.915244 151.159709)
		(end 116.767561 151.026839)
		(width 0.127)
		(layer "In3.Cu")
		(net "PCIE_CLK_N")
	)
	(arc
		(start 117.139607 151.315625)
		(mid 117.107661 151.296273)
		(end 117.076105 151.276292)
		(width 0.127)
		(layer "In3.Cu")
		(net "PCIE_CLK_N")
	)
	(arc
		(start 172.83641 138.14011)
		(mid 172.817075 138.237312)
		(end 172.762015 138.319715)
		(width 0.127)
		(layer "In3.Cu")
		(net "PCIE_CLK_N")
	)
	(arc
		(start 116.576102 150.278602)
		(mid 116.557419 150.291086)
		(end 116.53538 150.29547)
		(width 0.127)
		(layer "In3.Cu")
		(net "PCIE_CLK_N")
	)
	(arc
		(start 116.2158 150.42247)
		(mid 116.225467 150.373873)
		(end 116.252995 150.332675)
		(width 0.127)
		(layer "In3.Cu")
		(net "PCIE_CLK_N")
	)
	(arc
		(start 117.78853 151.24368)
		(mid 117.713577 151.395137)
		(end 117.547698 151.427411)
		(width 0.127)
		(layer "In3.Cu")
		(net "PCIE_CLK_N")
	)
	(segment
		(start 104.9261 143.9162)
		(end 106.5261 145.5162)
		(width 0.2032)
		(layer "F.Cu")
		(net "PCIE_PERST")
	)
	(segment
		(start 92.6261 122.0786)
		(end 92.6261 122.0786)
		(width 0.2032)
		(layer "F.Cu")
		(net "PCIE_PERST")
	)
	(segment
		(start 106.5261 150.4162)
		(end 107.8261 151.7162)
		(width 0.2032)
		(layer "F.Cu")
		(net "PCIE_PERST")
	)
	(segment
		(start 106.5261 150.4162)
		(end 106.5261 145.5162)
		(width 0.2032)
		(layer "F.Cu")
		(net "PCIE_PERST")
	)
	(segment
		(start 92.6261 122.0786)
		(end 93.8761 122.0786)
		(width 0.2032)
		(layer "F.Cu")
		(net "PCIE_PERST")
	)
	(segment
		(start 107.8261 151.7162)
		(end 109.9261 151.7162)
		(width 0.2032)
		(layer "F.Cu")
		(net "PCIE_PERST")
	)
	(segment
		(start 109.9261 151.7162)
		(end 110.6637 150.9786)
		(width 0.2032)
		(layer "F.Cu")
		(net "PCIE_PERST")
	)
	(segment
		(start 154.0084 119.31646)
		(end 154.06614 119.3742)
		(width 0.2032)
		(layer "F.Cu")
		(net "PCIE_PERST")
	)
	(segment
		(start 151.75808 119.31646)
		(end 154.0084 119.31646)
		(width 0.2032)
		(layer "F.Cu")
		(net "PCIE_PERST")
	)
	(segment
		(start 92.6261 133.4162)
		(end 92.6261 122.0786)
		(width 0.2032)
		(layer "F.Cu")
		(net "PCIE_PERST")
	)
	(segment
		(start 154.06614 119.3742)
		(end 154.61801 119.3742)
		(width 0.2032)
		(layer "F.Cu")
		(net "PCIE_PERST")
	)
	(segment
		(start 87.4261 138.6162)
		(end 92.6261 133.4162)
		(width 0.2032)
		(layer "F.Cu")
		(net "PCIE_PERST")
	)
	(segment
		(start 110.6637 150.9786)
		(end 111.4761 150.9786)
		(width 0.2032)
		(layer "F.Cu")
		(net "PCIE_PERST")
	)
	(segment
		(start 151.75053 119.30892)
		(end 151.75808 119.31646)
		(width 0.2032)
		(layer "F.Cu")
		(net "PCIE_PERST")
	)
	(segment
		(start 87.4261 142.0162)
		(end 89.3261 143.9162)
		(width 0.2032)
		(layer "F.Cu")
		(net "PCIE_PERST")
	)
	(segment
		(start 87.4261 142.0162)
		(end 87.4261 138.6162)
		(width 0.2032)
		(layer "F.Cu")
		(net "PCIE_PERST")
	)
	(segment
		(start 89.3261 143.9162)
		(end 104.9261 143.9162)
		(width 0.2032)
		(layer "F.Cu")
		(net "PCIE_PERST")
	)
	(via
		(at 93.8761 122.0786)
		(size 0.4064)
		(drill 0.2032)
		(layers "F.Cu" "B.Cu")
		(tenting
			(front yes)
			(back yes)
		)
		(net "PCIE_PERST")
	)
	(via
		(at 111.4761 150.9786)
		(size 0.4064)
		(drill 0.2032)
		(layers "F.Cu" "B.Cu")
		(tenting
			(front yes)
			(back yes)
		)
		(net "PCIE_PERST")
	)
	(via
		(at 154.61801 119.3742)
		(size 0.4064)
		(drill 0.2032)
		(layers "F.Cu" "B.Cu")
		(tenting
			(front yes)
			(back yes)
		)
		(net "PCIE_PERST")
	)
	(segment
		(start 111.4761 157.02859)
		(end 111.52611 157.0786)
		(width 0.2032)
		(layer "B.Cu")
		(net "PCIE_PERST")
	)
	(segment
		(start 111.4761 157.02859)
		(end 111.4761 150.9786)
		(width 0.2032)
		(layer "B.Cu")
		(net "PCIE_PERST")
	)
	(segment
		(start 154.56432 119.3742)
		(end 154.61801 119.3742)
		(width 0.2032)
		(layer "In3.Cu")
		(net "PCIE_PERST")
	)
	(segment
		(start 152.85192 121.0866)
		(end 154.56432 119.3742)
		(width 0.2032)
		(layer "In3.Cu")
		(net "PCIE_PERST")
	)
	(segment
		(start 94.8681 121.0866)
		(end 152.85192 121.0866)
		(width 0.2032)
		(layer "In3.Cu")
		(net "PCIE_PERST")
	)
	(segment
		(start 93.8761 122.0786)
		(end 94.8681 121.0866)
		(width 0.2032)
		(layer "In3.Cu")
		(net "PCIE_PERST")
	)
	(segment
		(start 176.33596 132.91874)
		(end 176.33596 131.45545)
		(width 0.127)
		(layer "F.Cu")
		(net "PCIE_RX3_N")
	)
	(segment
		(start 130.3449 157.55643)
		(end 130.54607 157.7576)
		(width 0.127)
		(layer "F.Cu")
		(net "PCIE_RX3_N")
	)
	(segment
		(start 130.52607 157.0786)
		(end 130.52607 153.59923)
		(width 0.127)
		(layer "F.Cu")
		(net "PCIE_RX3_N")
	)
	(via
		(at 130.4761 153.4786)
		(size 0.4064)
		(drill 0.2032)
		(layers "F.Cu" "B.Cu")
		(tenting
			(front yes)
			(back yes)
		)
		(net "PCIE_RX3_N")
	)
	(via
		(at 176.2261 133.0286)
		(size 0.4064)
		(drill 0.2032)
		(layers "F.Cu" "B.Cu")
		(tenting
			(front yes)
			(back yes)
		)
		(net "PCIE_RX3_N")
	)
	(arc
		(start 176.33596 132.91874)
		(mid 176.303783 132.996423)
		(end 176.2261 133.0286)
		(width 0.127)
		(layer "F.Cu")
		(net "PCIE_RX3_N")
	)
	(arc
		(start 130.476102 153.478598)
		(mid 130.513083 153.533944)
		(end 130.526069 153.59923)
		(width 0.127)
		(layer "F.Cu")
		(net "PCIE_RX3_N")
	)
	(arc
		(start 130.52607 157.0786)
		(mid 130.338083 156.797257)
		(end 130.27207 156.46539)
		(width 0.2032)
		(layer "F.Cu")
		(net "PCIE_RX3_N")
	)
	(segment
		(start 129.77262 150.45646)
		(end 129.79298 150.4244)
		(width 0.127)
		(layer "In2.Cu")
		(net "PCIE_RX3_N")
	)
	(segment
		(start 176.2261 133.0324)
		(end 176.2261 133.0286)
		(width 0.127)
		(layer "In2.Cu")
		(net "PCIE_RX3_N")
	)
	(segment
		(start 179.96808 141.24749)
		(end 180.25255 140.96302)
		(width 0.127)
		(layer "In2.Cu")
		(net "PCIE_RX3_N")
	)
	(segment
		(start 179.27725 136.108)
		(end 179.8261 136.108)
		(width 0.127)
		(layer "In2.Cu")
		(net "PCIE_RX3_N")
	)
	(segment
		(start 129.79298 150.4244)
		(end 130.2613 149.95609)
		(width 0.127)
		(layer "In2.Cu")
		(net "PCIE_RX3_N")
	)
	(segment
		(start 176.4364 133.92998)
		(end 176.4364 133.5401)
		(width 0.127)
		(layer "In2.Cu")
		(net "PCIE_RX3_N")
	)
	(segment
		(start 176.79282 134.79045)
		(end 177.28526 135.28289)
		(width 0.127)
		(layer "In2.Cu")
		(net "PCIE_RX3_N")
	)
	(segment
		(start 180.9965 139.16697)
		(end 180.9965 137.63824)
		(width 0.127)
		(layer "In2.Cu")
		(net "PCIE_RX3_N")
	)
	(segment
		(start 130.2981 149.86668)
		(end 130.2981 145.81968)
		(width 0.127)
		(layer "In2.Cu")
		(net "PCIE_RX3_N")
	)
	(segment
		(start 179.8261 136.108)
		(end 179.8261 136.108)
		(width 0.127)
		(layer "In2.Cu")
		(net "PCIE_RX3_N")
	)
	(segment
		(start 130.25979 153.4786)
		(end 130.4761 153.4786)
		(width 0.127)
		(layer "In2.Cu")
		(net "PCIE_RX3_N")
	)
	(segment
		(start 131.374 143.74518)
		(end 173.93958 143.74518)
		(width 0.127)
		(layer "In2.Cu")
		(net "PCIE_RX3_N")
	)
	(segment
		(start 131.08311 143.86862)
		(end 131.08508 143.86663)
		(width 0.127)
		(layer "In2.Cu")
		(net "PCIE_RX3_N")
	)
	(segment
		(start 130.13487 153.57867)
		(end 130.13488 153.57867)
		(width 0.127)
		(layer "In2.Cu")
		(net "PCIE_RX3_N")
	)
	(segment
		(start 129.1761 153.56468)
		(end 129.1761 151.62556)
		(width 0.127)
		(layer "In2.Cu")
		(net "PCIE_RX3_N")
	)
	(arc
		(start 176.792819 134.790451)
		(mid 176.52903 134.395664)
		(end 176.4364 133.92998)
		(width 0.127)
		(layer "In2.Cu")
		(net "PCIE_RX3_N")
	)
	(arc
		(start 129.772622 150.45645)
		(mid 129.758875 150.474524)
		(end 129.742129 150.48986)
		(width 0.127)
		(layer "In2.Cu")
		(net "PCIE_RX3_N")
	)
	(arc
		(start 130.2981 145.81968)
		(mid 130.501256 144.769276)
		(end 131.081422 143.870372)
		(width 0.127)
		(layer "In2.Cu")
		(net "PCIE_RX3_N")
	)
	(arc
		(start 180.9965 139.16697)
		(mid 180.803153 140.138989)
		(end 180.252547 140.963026)
		(width 0.127)
		(layer "In2.Cu")
		(net "PCIE_RX3_N")
	)
	(arc
		(start 179.8261 136.108)
		(mid 180.176619 136.177723)
		(end 180.473774 136.376276)
		(width 0.127)
		(layer "In2.Cu")
		(net "PCIE_RX3_N")
	)
	(arc
		(start 129.180055 153.596127)
		(mid 129.177093 153.580527)
		(end 129.1761 153.56468)
		(width 0.127)
		(layer "In2.Cu")
		(net "PCIE_RX3_N")
	)
	(arc
		(start 176.2261 133.03239)
		(mid 176.381745 133.265329)
		(end 176.4364 133.5401)
		(width 0.127)
		(layer "In2.Cu")
		(net "PCIE_RX3_N")
	)
	(arc
		(start 130.2981 149.86668)
		(mid 130.288538 149.915025)
		(end 130.261293 149.956091)
		(width 0.127)
		(layer "In2.Cu")
		(net "PCIE_RX3_N")
	)
	(arc
		(start 180.473776 136.376274)
		(mid 180.860648 136.955269)
		(end 180.996499 137.63824)
		(width 0.127)
		(layer "In2.Cu")
		(net "PCIE_RX3_N")
	)
	(arc
		(start 131.085079 143.866635)
		(mid 131.21736 143.776936)
		(end 131.373999 143.745181)
		(width 0.127)
		(layer "In2.Cu")
		(net "PCIE_RX3_N")
	)
	(arc
		(start 130.134867 153.578677)
		(mid 129.664368 153.965198)
		(end 129.180055 153.596132)
		(width 0.127)
		(layer "In2.Cu")
		(net "PCIE_RX3_N")
	)
	(arc
		(start 179.968083 141.247493)
		(mid 177.202186 143.095778)
		(end 173.939578 143.745189)
		(width 0.127)
		(layer "In2.Cu")
		(net "PCIE_RX3_N")
	)
	(arc
		(start 130.134877 153.578674)
		(mid 130.179586 153.506483)
		(end 130.259793 153.478602)
		(width 0.127)
		(layer "In2.Cu")
		(net "PCIE_RX3_N")
	)
	(arc
		(start 129.176101 151.62556)
		(mid 129.316066 151.009606)
		(end 129.709337 150.515311)
		(width 0.127)
		(layer "In2.Cu")
		(net "PCIE_RX3_N")
	)
	(arc
		(start 129.709337 150.51531)
		(mid 129.725641 150.50247)
		(end 129.742131 150.489869)
		(width 0.127)
		(layer "In2.Cu")
		(net "PCIE_RX3_N")
	)
	(arc
		(start 179.27725 136.108)
		(mid 178.199193 135.893561)
		(end 177.285259 135.282891)
		(width 0.127)
		(layer "In2.Cu")
		(net "PCIE_RX3_N")
	)
	(segment
		(start 176.83583 132.93833)
		(end 176.83583 131.45545)
		(width 0.127)
		(layer "F.Cu")
		(net "PCIE_RX3_P")
	)
	(segment
		(start 129.52607 157.0786)
		(end 129.52607 153.8408)
		(width 0.127)
		(layer "F.Cu")
		(net "PCIE_RX3_P")
	)
	(segment
		(start 129.54607 157.7576)
		(end 129.7353 157.56837)
		(width 0.127)
		(layer "F.Cu")
		(net "PCIE_RX3_P")
	)
	(via
		(at 129.67566 153.47904)
		(size 0.4064)
		(drill 0.2032)
		(layers "F.Cu" "B.Cu")
		(tenting
			(front yes)
			(back yes)
		)
		(net "PCIE_RX3_P")
	)
	(via
		(at 176.9261 133.0286)
		(size 0.4064)
		(drill 0.2032)
		(layers "F.Cu" "B.Cu")
		(tenting
			(front yes)
			(back yes)
		)
		(net "PCIE_RX3_P")
	)
	(arc
		(start 176.9261 133.0286)
		(mid 176.862269 133.002161)
		(end 176.83583 132.93833)
		(width 0.127)
		(layer "F.Cu")
		(net "PCIE_RX3_P")
	)
	(arc
		(start 129.52607 153.8408)
		(mid 129.564943 153.645064)
		(end 129.675662 153.479036)
		(width 0.127)
		(layer "F.Cu")
		(net "PCIE_RX3_P")
	)
	(segment
		(start 180.16485 141.44586)
		(end 180.45061 141.1601)
		(width 0.127)
		(layer "In2.Cu")
		(net "PCIE_RX3_P")
	)
	(segment
		(start 129.6206 152.21086)
		(end 129.94758 152.21086)
		(width 0.127)
		(layer "In2.Cu")
		(net "PCIE_RX3_P")
	)
	(segment
		(start 129.6206 151.82986)
		(end 129.95828 151.82986)
		(width 0.127)
		(layer "In2.Cu")
		(net "PCIE_RX3_P")
	)
	(segment
		(start 129.4761 153.16337)
		(end 129.4761 152.78236)
		(width 0.127)
		(layer "In2.Cu")
		(net "PCIE_RX3_P")
	)
	(segment
		(start 129.6666 152.59186)
		(end 129.94758 152.59186)
		(width 0.127)
		(layer "In2.Cu")
		(net "PCIE_RX3_P")
	)
	(segment
		(start 131.37405 144.02458)
		(end 173.93816 144.02458)
		(width 0.127)
		(layer "In2.Cu")
		(net "PCIE_RX3_P")
	)
	(segment
		(start 129.95826 151.44886)
		(end 129.95828 151.44886)
		(width 0.127)
		(layer "In2.Cu")
		(net "PCIE_RX3_P")
	)
	(segment
		(start 179.2782 135.8286)
		(end 179.82732 135.8286)
		(width 0.127)
		(layer "In2.Cu")
		(net "PCIE_RX3_P")
	)
	(segment
		(start 129.4761 153.16337)
		(end 129.4761 153.22687)
		(width 0.127)
		(layer "In2.Cu")
		(net "PCIE_RX3_P")
	)
	(segment
		(start 176.9261 133.0324)
		(end 176.9261 133.0286)
		(width 0.127)
		(layer "In2.Cu")
		(net "PCIE_RX3_P")
	)
	(segment
		(start 130.09259 150.52009)
		(end 130.09279 150.51973)
		(width 0.127)
		(layer "In2.Cu")
		(net "PCIE_RX3_P")
	)
	(segment
		(start 129.5133 153.31667)
		(end 129.67566 153.47904)
		(width 0.127)
		(layer "In2.Cu")
		(net "PCIE_RX3_P")
	)
	(segment
		(start 129.76776 150.9662)
		(end 129.76776 150.89735)
		(width 0.127)
		(layer "In2.Cu")
		(net "PCIE_RX3_P")
	)
	(segment
		(start 173.93849 144.02458)
		(end 173.94076 144.02458)
		(width 0.127)
		(layer "In2.Cu")
		(net "PCIE_RX3_P")
	)
	(segment
		(start 176.99136 134.59386)
		(end 177.48215 135.08465)
		(width 0.127)
		(layer "In2.Cu")
		(net "PCIE_RX3_P")
	)
	(segment
		(start 130.08494 150.53873)
		(end 130.08495 150.53873)
		(width 0.127)
		(layer "In2.Cu")
		(net "PCIE_RX3_P")
	)
	(segment
		(start 131.28425 144.06257)
		(end 131.28426 144.06257)
		(width 0.127)
		(layer "In2.Cu")
		(net "PCIE_RX3_P")
	)
	(segment
		(start 176.7158 133.9286)
		(end 176.7158 133.5401)
		(width 0.127)
		(layer "In2.Cu")
		(net "PCIE_RX3_P")
	)
	(segment
		(start 130.5775 149.86668)
		(end 130.5775 145.82063)
		(width 0.127)
		(layer "In2.Cu")
		(net "PCIE_RX3_P")
	)
	(segment
		(start 129.76776 151.25836)
		(end 129.76776 150.9662)
		(width 0.127)
		(layer "In2.Cu")
		(net "PCIE_RX3_P")
	)
	(segment
		(start 129.80495 150.80755)
		(end 130.45939 150.15312)
		(width 0.127)
		(layer "In2.Cu")
		(net "PCIE_RX3_P")
	)
	(segment
		(start 180.67048 136.17785)
		(end 180.67435 136.18172)
		(width 0.127)
		(layer "In2.Cu")
		(net "PCIE_RX3_P")
	)
	(segment
		(start 181.2759 139.16766)
		(end 181.2759 137.634)
		(width 0.127)
		(layer "In2.Cu")
		(net "PCIE_RX3_P")
	)
	(arc
		(start 129.513297 153.316673)
		(mid 129.485768 153.275473)
		(end 129.476099 153.226875)
		(width 0.127)
		(layer "In2.Cu")
		(net "PCIE_RX3_P")
	)
	(arc
		(start 129.76776 150.89735)
		(mid 129.777427 150.84875)
		(end 129.804956 150.807549)
		(width 0.127)
		(layer "In2.Cu")
		(net "PCIE_RX3_P")
	)
	(arc
		(start 130.084941 150.538732)
		(mid 130.088397 150.52926)
		(end 130.092594 150.520093)
		(width 0.127)
		(layer "In2.Cu")
		(net "PCIE_RX3_P")
	)
	(arc
		(start 129.94758 152.21086)
		(mid 130.13808 152.40136)
		(end 129.94758 152.59186)
		(width 0.127)
		(layer "In2.Cu")
		(net "PCIE_RX3_P")
	)
	(arc
		(start 180.164858 141.445865)
		(mid 177.309224 143.354118)
		(end 173.940761 144.02459)
		(width 0.127)
		(layer "In2.Cu")
		(net "PCIE_RX3_P")
	)
	(arc
		(start 176.7158 133.5401)
		(mid 176.770455 133.265331)
		(end 176.926098 133.032392)
		(width 0.127)
		(layer "In2.Cu")
		(net "PCIE_RX3_P")
	)
	(arc
		(start 131.190133 144.166285)
		(mid 131.236476 144.113776)
		(end 131.284249 144.062565)
		(width 0.127)
		(layer "In2.Cu")
		(net "PCIE_RX3_P")
	)
	(arc
		(start 179.2782 135.8286)
		(mid 178.306184 135.635254)
		(end 177.482149 135.084651)
		(width 0.127)
		(layer "In2.Cu")
		(net "PCIE_RX3_P")
	)
	(arc
		(start 179.82732 135.8286)
		(mid 180.283632 135.919366)
		(end 180.670474 136.177846)
		(width 0.127)
		(layer "In2.Cu")
		(net "PCIE_RX3_P")
	)
	(arc
		(start 180.674345 136.18172)
		(mid 181.119561 136.848031)
		(end 181.275901 137.634)
		(width 0.127)
		(layer "In2.Cu")
		(net "PCIE_RX3_P")
	)
	(arc
		(start 131.284257 144.062575)
		(mid 131.32536 144.03462)
		(end 131.374044 144.024583)
		(width 0.127)
		(layer "In2.Cu")
		(net "PCIE_RX3_P")
	)
	(arc
		(start 130.5775 145.82063)
		(mid 130.735577 144.938562)
		(end 131.190133 144.166285)
		(width 0.127)
		(layer "In2.Cu")
		(net "PCIE_RX3_P")
	)
	(arc
		(start 176.99136 134.59386)
		(mid 176.787416 134.288636)
		(end 176.7158 133.9286)
		(width 0.127)
		(layer "In2.Cu")
		(net "PCIE_RX3_P")
	)
	(arc
		(start 130.5775 149.86668)
		(mid 130.546814 150.021599)
		(end 130.45939 150.153123)
		(width 0.127)
		(layer "In2.Cu")
		(net "PCIE_RX3_P")
	)
	(arc
		(start 129.4761 152.78236)
		(mid 129.531896 152.647656)
		(end 129.6666 152.59186)
		(width 0.127)
		(layer "In2.Cu")
		(net "PCIE_RX3_P")
	)
	(arc
		(start 129.6206 152.21086)
		(mid 129.4301 152.02036)
		(end 129.6206 151.82986)
		(width 0.127)
		(layer "In2.Cu")
		(net "PCIE_RX3_P")
	)
	(arc
		(start 129.95828 151.44886)
		(mid 130.14878 151.63936)
		(end 129.95828 151.82986)
		(width 0.127)
		(layer "In2.Cu")
		(net "PCIE_RX3_P")
	)
	(arc
		(start 173.93816 144.02458)
		(mid 173.938325 144.02458)
		(end 173.93849 144.02458)
		(width 0.127)
		(layer "In2.Cu")
		(net "PCIE_RX3_P")
	)
	(arc
		(start 129.95826 151.44886)
		(mid 129.823556 151.393064)
		(end 129.76776 151.25836)
		(width 0.127)
		(layer "In2.Cu")
		(net "PCIE_RX3_P")
	)
	(arc
		(start 181.2759 139.16766)
		(mid 181.061415 140.245954)
		(end 180.450613 141.160089)
		(width 0.127)
		(layer "In2.Cu")
		(net "PCIE_RX3_P")
	)
	(segment
		(start 126.52608 157.0786)
		(end 126.52608 153.59925)
		(width 0.127)
		(layer "F.Cu")
		(net "PCIE_RX2_N")
	)
	(segment
		(start 177.83583 137.3637)
		(end 177.83583 135.50523)
		(width 0.127)
		(layer "F.Cu")
		(net "PCIE_RX2_N")
	)
	(via
		(at 177.7261 137.6286)
		(size 0.4064)
		(drill 0.2032)
		(layers "F.Cu" "B.Cu")
		(tenting
			(front yes)
			(back yes)
		)
		(net "PCIE_RX2_N")
	)
	(via
		(at 126.4761 153.4786)
		(size 0.4064)
		(drill 0.2032)
		(layers "F.Cu" "B.Cu")
		(tenting
			(front yes)
			(back yes)
		)
		(net "PCIE_RX2_N")
	)
	(arc
		(start 126.546076 157.757603)
		(mid 126.537804 157.745223)
		(end 126.5349 157.73062)
		(width 0.127)
		(layer "F.Cu")
		(net "PCIE_RX2_N")
	)
	(arc
		(start 177.83583 137.3637)
		(mid 177.807313 137.507065)
		(end 177.726103 137.628603)
		(width 0.127)
		(layer "F.Cu")
		(net "PCIE_RX2_N")
	)
	(arc
		(start 126.476104 153.478596)
		(mid 126.513092 153.533953)
		(end 126.526081 153.59925)
		(width 0.127)
		(layer "F.Cu")
		(net "PCIE_RX2_N")
	)
	(arc
		(start 126.546077 157.757603)
		(mid 126.368616 157.492014)
		(end 126.3063 157.17873)
		(width 0.127)
		(layer "F.Cu")
		(net "PCIE_RX2_N")
	)
	(segment
		(start 125.40648 153.78627)
		(end 125.40717 153.78697)
		(width 0.127)
		(layer "In2.Cu")
		(net "PCIE_RX2_N")
	)
	(segment
		(start 177.7261 137.63239)
		(end 177.7261 137.6286)
		(width 0.127)
		(layer "In2.Cu")
		(net "PCIE_RX2_N")
	)
	(segment
		(start 131.04402 142.5192)
		(end 174.5596 142.5192)
		(width 0.127)
		(layer "In2.Cu")
		(net "PCIE_RX2_N")
	)
	(segment
		(start 127.60935 144.78742)
		(end 129.05276 143.34401)
		(width 0.127)
		(layer "In2.Cu")
		(net "PCIE_RX2_N")
	)
	(segment
		(start 127.2501 147.1928)
		(end 127.2501 145.65473)
		(width 0.127)
		(layer "In2.Cu")
		(net "PCIE_RX2_N")
	)
	(segment
		(start 127.1864 148.24663)
		(end 127.1864 147.34659)
		(width 0.127)
		(layer "In2.Cu")
		(net "PCIE_RX2_N")
	)
	(segment
		(start 125.41885 150.73585)
		(end 126.6761 149.47859)
		(width 0.127)
		(layer "In2.Cu")
		(net "PCIE_RX2_N")
	)
	(segment
		(start 176.35565 141.77525)
		(end 177.19245 140.93845)
		(width 0.127)
		(layer "In2.Cu")
		(net "PCIE_RX2_N")
	)
	(segment
		(start 177.9364 139.1424)
		(end 177.9364 138.14011)
		(width 0.127)
		(layer "In2.Cu")
		(net "PCIE_RX2_N")
	)
	(segment
		(start 126.26014 153.4786)
		(end 126.4761 153.4786)
		(width 0.127)
		(layer "In2.Cu")
		(net "PCIE_RX2_N")
	)
	(arc
		(start 129.052765 143.344005)
		(mid 129.966361 142.73356)
		(end 131.04402 142.5192)
		(width 0.127)
		(layer "In2.Cu")
		(net "PCIE_RX2_N")
	)
	(arc
		(start 176.355651 141.775251)
		(mid 175.531616 142.325854)
		(end 174.5596 142.5192)
		(width 0.127)
		(layer "In2.Cu")
		(net "PCIE_RX2_N")
	)
	(arc
		(start 177.726107 137.632393)
		(mid 177.881754 137.865336)
		(end 177.93641 138.14011)
		(width 0.127)
		(layer "In2.Cu")
		(net "PCIE_RX2_N")
	)
	(arc
		(start 127.1864 147.34659)
		(mid 127.202956 147.263356)
		(end 127.250104 147.192794)
		(width 0.127)
		(layer "In2.Cu")
		(net "PCIE_RX2_N")
	)
	(arc
		(start 126.135238 153.57858)
		(mid 126.179964 153.506454)
		(end 126.260133 153.478603)
		(width 0.127)
		(layer "In2.Cu")
		(net "PCIE_RX2_N")
	)
	(arc
		(start 177.9364 139.1424)
		(mid 177.743054 140.114416)
		(end 177.192451 140.938451)
		(width 0.127)
		(layer "In2.Cu")
		(net "PCIE_RX2_N")
	)
	(arc
		(start 125.40649 153.786265)
		(mid 124.948222 153.082774)
		(end 124.787271 152.258758)
		(width 0.127)
		(layer "In2.Cu")
		(net "PCIE_RX2_N")
	)
	(arc
		(start 127.25011 145.65473)
		(mid 127.343476 145.18535)
		(end 127.609358 144.787428)
		(width 0.127)
		(layer "In2.Cu")
		(net "PCIE_RX2_N")
	)
	(arc
		(start 124.78726 152.258762)
		(mid 124.951603 151.434496)
		(end 125.418845 150.735849)
		(width 0.127)
		(layer "In2.Cu")
		(net "PCIE_RX2_N")
	)
	(arc
		(start 127.1864 148.24663)
		(mid 127.053778 148.913368)
		(end 126.676101 149.478601)
		(width 0.127)
		(layer "In2.Cu")
		(net "PCIE_RX2_N")
	)
	(arc
		(start 126.135242 153.57858)
		(mid 125.833499 153.900415)
		(end 125.407169 153.786972)
		(width 0.127)
		(layer "In2.Cu")
		(net "PCIE_RX2_N")
	)
	(segment
		(start 125.52608 157.0786)
		(end 125.52608 153.84078)
		(width 0.127)
		(layer "F.Cu")
		(net "PCIE_RX2_P")
	)
	(segment
		(start 125.4935 157.70502)
		(end 125.54608 157.7576)
		(width 0.127)
		(layer "F.Cu")
		(net "PCIE_RX2_P")
	)
	(segment
		(start 178.33595 137.41096)
		(end 178.33595 135.50523)
		(width 0.127)
		(layer "F.Cu")
		(net "PCIE_RX2_P")
	)
	(segment
		(start 125.54608 157.7576)
		(end 125.6205 157.68318)
		(width 0.127)
		(layer "F.Cu")
		(net "PCIE_RX2_P")
	)
	(segment
		(start 125.6677 153.47477)
		(end 125.6845 153.43091)
		(width 0.127)
		(layer "F.Cu")
		(net "PCIE_RX2_P")
	)
	(segment
		(start 125.69583 153.40817)
		(end 125.69613 153.40787)
		(width 0.127)
		(layer "F.Cu")
		(net "PCIE_RX2_P")
	)
	(segment
		(start 125.64629 153.51109)
		(end 125.64677 153.51052)
		(width 0.127)
		(layer "F.Cu")
		(net "PCIE_RX2_P")
	)
	(segment
		(start 125.69339 153.41236)
		(end 125.69583 153.40817)
		(width 0.127)
		(layer "F.Cu")
		(net "PCIE_RX2_P")
	)
	(via
		(at 125.69613 153.40787)
		(size 0.4064)
		(drill 0.2032)
		(layers "F.Cu" "B.Cu")
		(tenting
			(front yes)
			(back yes)
		)
		(net "PCIE_RX2_P")
	)
	(via
		(at 178.4261 137.6286)
		(size 0.4064)
		(drill 0.2032)
		(layers "F.Cu" "B.Cu")
		(tenting
			(front yes)
			(back yes)
		)
		(net "PCIE_RX2_P")
	)
	(arc
		(start 125.684502 153.430905)
		(mid 125.688569 153.421452)
		(end 125.693388 153.41236)
		(width 0.127)
		(layer "F.Cu")
		(net "PCIE_RX2_P")
	)
	(arc
		(start 178.4261 137.6286)
		(mid 178.35938 137.528746)
		(end 178.335951 137.41096)
		(width 0.127)
		(layer "F.Cu")
		(net "PCIE_RX2_P")
	)
	(arc
		(start 125.52608 153.84078)
		(mid 125.557071 153.665316)
		(end 125.646294 153.511085)
		(width 0.127)
		(layer "F.Cu")
		(net "PCIE_RX2_P")
	)
	(arc
		(start 125.667698 153.474767)
		(mid 125.658702 153.4935)
		(end 125.646772 153.510515)
		(width 0.127)
		(layer "F.Cu")
		(net "PCIE_RX2_P")
	)
	(segment
		(start 125.69612 153.40787)
		(end 125.69613 153.40787)
		(width 0.127)
		(layer "In2.Cu")
		(net "PCIE_RX2_P")
	)
	(segment
		(start 125.67622 153.16517)
		(end 125.67626 153.06998)
		(width 0.127)
		(layer "In2.Cu")
		(net "PCIE_RX2_P")
	)
	(segment
		(start 125.31754 152.49841)
		(end 125.73999 152.49841)
		(width 0.127)
		(layer "In2.Cu")
		(net "PCIE_RX2_P")
	)
	(segment
		(start 125.67686 151.54598)
		(end 125.67686 151.54598)
		(width 0.127)
		(layer "In2.Cu")
		(net "PCIE_RX2_P")
	)
	(segment
		(start 125.67709 150.98878)
		(end 125.67711 150.92528)
		(width 0.127)
		(layer "In2.Cu")
		(net "PCIE_RX2_P")
	)
	(segment
		(start 127.8089 144.983)
		(end 129.24935 143.54255)
		(width 0.127)
		(layer "In2.Cu")
		(net "PCIE_RX2_P")
	)
	(segment
		(start 178.4261 137.6324)
		(end 178.4261 137.6286)
		(width 0.127)
		(layer "In2.Cu")
		(net "PCIE_RX2_P")
	)
	(segment
		(start 127.5295 147.26349)
		(end 127.5295 145.65753)
		(width 0.127)
		(layer "In2.Cu")
		(net "PCIE_RX2_P")
	)
	(segment
		(start 125.67615 153.33945)
		(end 125.67615 153.33945)
		(width 0.127)
		(layer "In2.Cu")
		(net "PCIE_RX2_P")
	)
	(segment
		(start 125.31754 152.87941)
		(end 125.48576 152.87941)
		(width 0.127)
		(layer "In2.Cu")
		(net "PCIE_RX2_P")
	)
	(segment
		(start 178.21581 139.14378)
		(end 178.21581 138.14011)
		(width 0.127)
		(layer "In2.Cu")
		(net "PCIE_RX2_P")
	)
	(segment
		(start 125.71431 150.83552)
		(end 126.87453 149.6753)
		(width 0.127)
		(layer "In2.Cu")
		(net "PCIE_RX2_P")
	)
	(segment
		(start 127.4658 148.24785)
		(end 127.4658 147.41728)
		(width 0.127)
		(layer "In2.Cu")
		(net "PCIE_RX2_P")
	)
	(segment
		(start 125.31784 151.73641)
		(end 125.48636 151.73641)
		(width 0.127)
		(layer "In2.Cu")
		(net "PCIE_RX2_P")
	)
	(segment
		(start 176.55224 141.97379)
		(end 177.391 141.13504)
		(width 0.127)
		(layer "In2.Cu")
		(net "PCIE_RX2_P")
	)
	(segment
		(start 125.67615 153.33945)
		(end 125.6762 153.22867)
		(width 0.127)
		(layer "In2.Cu")
		(net "PCIE_RX2_P")
	)
	(segment
		(start 125.67626 153.06998)
		(end 125.67626 153.06998)
		(width 0.127)
		(layer "In2.Cu")
		(net "PCIE_RX2_P")
	)
	(segment
		(start 131.0454 142.7986)
		(end 174.56098 142.7986)
		(width 0.127)
		(layer "In2.Cu")
		(net "PCIE_RX2_P")
	)
	(segment
		(start 125.67711 150.92528)
		(end 125.67711 150.92527)
		(width 0.127)
		(layer "In2.Cu")
		(net "PCIE_RX2_P")
	)
	(segment
		(start 125.6762 153.22867)
		(end 125.67622 153.16517)
		(width 0.127)
		(layer "In2.Cu")
		(net "PCIE_RX2_P")
	)
	(segment
		(start 125.67686 151.54598)
		(end 125.67709 150.98878)
		(width 0.127)
		(layer "In2.Cu")
		(net "PCIE_RX2_P")
	)
	(segment
		(start 125.31784 152.11741)
		(end 125.73999 152.11741)
		(width 0.127)
		(layer "In2.Cu")
		(net "PCIE_RX2_P")
	)
	(arc
		(start 127.4658 148.24785)
		(mid 127.312135 149.020377)
		(end 126.874534 149.675294)
		(width 0.127)
		(layer "In2.Cu")
		(net "PCIE_RX2_P")
	)
	(arc
		(start 127.5295 145.65753)
		(mid 127.602114 145.292477)
		(end 127.8089 144.983)
		(width 0.127)
		(layer "In2.Cu")
		(net "PCIE_RX2_P")
	)
	(arc
		(start 129.249349 143.542549)
		(mid 130.073384 142.991946)
		(end 131.0454 142.7986)
		(width 0.127)
		(layer "In2.Cu")
		(net "PCIE_RX2_P")
	)
	(arc
		(start 125.73999 152.11741)
		(mid 125.93049 152.30791)
		(end 125.73999 152.49841)
		(width 0.127)
		(layer "In2.Cu")
		(net "PCIE_RX2_P")
	)
	(arc
		(start 125.67711 150.925272)
		(mid 125.686786 150.876697)
		(end 125.714307 150.835518)
		(width 0.127)
		(layer "In2.Cu")
		(net "PCIE_RX2_P")
	)
	(arc
		(start 178.2158 139.143783)
		(mid 178.00144 140.221441)
		(end 177.390995 141.135035)
		(width 0.127)
		(layer "In2.Cu")
		(net "PCIE_RX2_P")
	)
	(arc
		(start 127.4658 147.41728)
		(mid 127.474078 147.375663)
		(end 127.497652 147.340382)
		(width 0.127)
		(layer "In2.Cu")
		(net "PCIE_RX2_P")
	)
	(arc
		(start 125.31784 152.11741)
		(mid 125.12734 151.92691)
		(end 125.31784 151.73641)
		(width 0.127)
		(layer "In2.Cu")
		(net "PCIE_RX2_P")
	)
	(arc
		(start 125.696121 153.407864)
		(mid 125.681239 153.375088)
		(end 125.676151 153.339452)
		(width 0.127)
		(layer "In2.Cu")
		(net "PCIE_RX2_P")
	)
	(arc
		(start 176.552242 141.973792)
		(mid 175.638643 142.584239)
		(end 174.56098 142.7986)
		(width 0.127)
		(layer "In2.Cu")
		(net "PCIE_RX2_P")
	)
	(arc
		(start 125.48576 152.87941)
		(mid 125.62049 152.935232)
		(end 125.67626 153.069984)
		(width 0.127)
		(layer "In2.Cu")
		(net "PCIE_RX2_P")
	)
	(arc
		(start 125.67686 151.545986)
		(mid 125.621037 151.680641)
		(end 125.48636 151.73641)
		(width 0.127)
		(layer "In2.Cu")
		(net "PCIE_RX2_P")
	)
	(arc
		(start 178.2158 138.14011)
		(mid 178.270455 137.865341)
		(end 178.426098 137.632402)
		(width 0.127)
		(layer "In2.Cu")
		(net "PCIE_RX2_P")
	)
	(arc
		(start 125.31754 152.87941)
		(mid 125.12704 152.68891)
		(end 125.31754 152.49841)
		(width 0.127)
		(layer "In2.Cu")
		(net "PCIE_RX2_P")
	)
	(arc
		(start 127.52951 147.26349)
		(mid 127.521232 147.305107)
		(end 127.497658 147.340388)
		(width 0.127)
		(layer "In2.Cu")
		(net "PCIE_RX2_P")
	)
	(segment
		(start 174.67965 136.77505)
		(end 174.7261 136.7286)
		(width 0.127)
		(layer "F.Cu")
		(net "PCIE_RX1_N")
	)
	(segment
		(start 122.1761 153.99576)
		(end 122.1761 153.4786)
		(width 0.127)
		(layer "F.Cu")
		(net "PCIE_RX1_N")
	)
	(segment
		(start 122.52608 157.0786)
		(end 122.52608 154.84069)
		(width 0.127)
		(layer "F.Cu")
		(net "PCIE_RX1_N")
	)
	(segment
		(start 174.83583 136.46369)
		(end 174.83583 135.50523)
		(width 0.127)
		(layer "F.Cu")
		(net "PCIE_RX1_N")
	)
	(segment
		(start 174.67942 136.77528)
		(end 174.67965 136.77505)
		(width 0.127)
		(layer "F.Cu")
		(net "PCIE_RX1_N")
	)
	(via
		(at 122.1761 153.4786)
		(size 0.4064)
		(drill 0.2032)
		(layers "F.Cu" "B.Cu")
		(tenting
			(front yes)
			(back yes)
		)
		(net "PCIE_RX1_N")
	)
	(via
		(at 174.3261 137.6286)
		(size 0.4064)
		(drill 0.2032)
		(layers "F.Cu" "B.Cu")
		(tenting
			(front yes)
			(back yes)
		)
		(net "PCIE_RX1_N")
	)
	(arc
		(start 122.376099 154.478601)
		(mid 122.228078 154.257072)
		(end 122.1761 153.99576)
		(width 0.127)
		(layer "F.Cu")
		(net "PCIE_RX1_N")
	)
	(arc
		(start 122.546083 157.757597)
		(mid 122.321251 157.421112)
		(end 122.2423 157.0242)
		(width 0.127)
		(layer "F.Cu")
		(net "PCIE_RX1_N")
	)
	(arc
		(start 122.376105 154.478595)
		(mid 122.48711 154.644726)
		(end 122.52609 154.84069)
		(width 0.127)
		(layer "F.Cu")
		(net "PCIE_RX1_N")
	)
	(arc
		(start 174.32609 137.6286)
		(mid 174.417913 137.166812)
		(end 174.679411 136.775278)
		(width 0.127)
		(layer "F.Cu")
		(net "PCIE_RX1_N")
	)
	(arc
		(start 174.83583 136.46369)
		(mid 174.807312 136.607059)
		(end 174.7261 136.7286)
		(width 0.127)
		(layer "F.Cu")
		(net "PCIE_RX1_N")
	)
	(segment
		(start 122.13216 148.96642)
		(end 122.13216 148.96642)
		(width 0.127)
		(layer "In2.Cu")
		(net "PCIE_RX1_N")
	)
	(segment
		(start 122.03396 153.4786)
		(end 122.1761 153.4786)
		(width 0.127)
		(layer "In2.Cu")
		(net "PCIE_RX1_N")
	)
	(segment
		(start 121.66365 152.26971)
		(end 121.66366 150.30604)
		(width 0.127)
		(layer "In2.Cu")
		(net "PCIE_RX1_N")
	)
	(segment
		(start 121.91774 153.49702)
		(end 121.91774 153.49702)
		(width 0.127)
		(layer "In2.Cu")
		(net "PCIE_RX1_N")
	)
	(segment
		(start 174.3261 137.6324)
		(end 174.3261 137.6286)
		(width 0.127)
		(layer "In2.Cu")
		(net "PCIE_RX1_N")
	)
	(segment
		(start 128.60562 141.4016)
		(end 172.2482 141.4016)
		(width 0.127)
		(layer "In2.Cu")
		(net "PCIE_RX1_N")
	)
	(segment
		(start 121.66406 150.29604)
		(end 121.66406 150.29604)
		(width 0.127)
		(layer "In2.Cu")
		(net "PCIE_RX1_N")
	)
	(segment
		(start 121.33775 153.01027)
		(end 121.33775 153.01027)
		(width 0.127)
		(layer "In2.Cu")
		(net "PCIE_RX1_N")
	)
	(segment
		(start 124.53566 144.30511)
		(end 126.61436 142.22641)
		(width 0.127)
		(layer "In2.Cu")
		(net "PCIE_RX1_N")
	)
	(segment
		(start 122.57386 148.38084)
		(end 123.04245 147.91225)
		(width 0.127)
		(layer "In2.Cu")
		(net "PCIE_RX1_N")
	)
	(segment
		(start 121.51163 152.81799)
		(end 121.60942 152.43171)
		(width 0.127)
		(layer "In2.Cu")
		(net "PCIE_RX1_N")
	)
	(segment
		(start 174.00253 140.69652)
		(end 174.36836 140.33069)
		(width 0.127)
		(layer "In2.Cu")
		(net "PCIE_RX1_N")
	)
	(segment
		(start 121.60942 152.43171)
		(end 121.60947 152.43151)
		(width 0.127)
		(layer "In2.Cu")
		(net "PCIE_RX1_N")
	)
	(segment
		(start 174.5364 139.92501)
		(end 174.5364 138.14011)
		(width 0.127)
		(layer "In2.Cu")
		(net "PCIE_RX1_N")
	)
	(segment
		(start 121.8329 153.58878)
		(end 121.8334 153.58675)
		(width 0.127)
		(layer "In2.Cu")
		(net "PCIE_RX1_N")
	)
	(segment
		(start 123.7864 146.1162)
		(end 123.7864 146.11398)
		(width 0.127)
		(layer "In2.Cu")
		(net "PCIE_RX1_N")
	)
	(segment
		(start 173.99969 140.69652)
		(end 174.00253 140.69652)
		(width 0.127)
		(layer "In2.Cu")
		(net "PCIE_RX1_N")
	)
	(arc
		(start 121.437576 152.946823)
		(mid 121.395497 152.990877)
		(end 121.337743 153.010266)
		(width 0.127)
		(layer "In2.Cu")
		(net "PCIE_RX1_N")
	)
	(arc
		(start 173.78336 140.885182)
		(mid 173.058046 141.269036)
		(end 172.2482 141.4016)
		(width 0.127)
		(layer "In2.Cu")
		(net "PCIE_RX1_N")
	)
	(arc
		(start 121.833394 153.586754)
		(mid 121.86396 153.530982)
		(end 121.917733 153.497022)
		(width 0.127)
		(layer "In2.Cu")
		(net "PCIE_RX1_N")
	)
	(arc
		(start 174.3261 137.6324)
		(mid 174.481745 137.865339)
		(end 174.5364 138.14011)
		(width 0.127)
		(layer "In2.Cu")
		(net "PCIE_RX1_N")
	)
	(arc
		(start 121.66366 150.306039)
		(mid 121.663759 150.301034)
		(end 121.664055 150.296037)
		(width 0.127)
		(layer "In2.Cu")
		(net "PCIE_RX1_N")
	)
	(arc
		(start 123.7864 146.1162)
		(mid 123.593054 147.088216)
		(end 123.042451 147.912251)
		(width 0.127)
		(layer "In2.Cu")
		(net "PCIE_RX1_N")
	)
	(arc
		(start 121.66406 150.29604)
		(mid 121.811311 149.600674)
		(end 122.132157 148.966423)
		(width 0.127)
		(layer "In2.Cu")
		(net "PCIE_RX1_N")
	)
	(arc
		(start 173.999691 140.696515)
		(mid 173.894749 140.794534)
		(end 173.783371 140.885174)
		(width 0.127)
		(layer "In2.Cu")
		(net "PCIE_RX1_N")
	)
	(arc
		(start 121.511627 152.817986)
		(mid 121.50401 152.839899)
		(end 121.492535 152.860061)
		(width 0.127)
		(layer "In2.Cu")
		(net "PCIE_RX1_N")
	)
	(arc
		(start 122.132167 148.96641)
		(mid 122.332608 148.658233)
		(end 122.573858 148.380838)
		(width 0.127)
		(layer "In2.Cu")
		(net "PCIE_RX1_N")
	)
	(arc
		(start 123.7864 146.11398)
		(mid 123.981125 145.13503)
		(end 124.535656 144.305116)
		(width 0.127)
		(layer "In2.Cu")
		(net "PCIE_RX1_N")
	)
	(arc
		(start 121.609471 152.431508)
		(mid 121.625934 152.379301)
		(end 121.648689 152.329514)
		(width 0.127)
		(layer "In2.Cu")
		(net "PCIE_RX1_N")
	)
	(arc
		(start 121.917739 153.497017)
		(mid 121.975124 153.483233)
		(end 122.03396 153.4786)
		(width 0.127)
		(layer "In2.Cu")
		(net "PCIE_RX1_N")
	)
	(arc
		(start 121.66365 152.269713)
		(mid 121.659852 152.300537)
		(end 121.648686 152.329517)
		(width 0.127)
		(layer "In2.Cu")
		(net "PCIE_RX1_N")
	)
	(arc
		(start 121.832899 153.588785)
		(mid 121.019107 153.784152)
		(end 121.337743 153.010268)
		(width 0.127)
		(layer "In2.Cu")
		(net "PCIE_RX1_N")
	)
	(arc
		(start 121.43758 152.946824)
		(mid 121.464094 152.902833)
		(end 121.492531 152.86006)
		(width 0.127)
		(layer "In2.Cu")
		(net "PCIE_RX1_N")
	)
	(arc
		(start 174.5364 139.92501)
		(mid 174.492727 140.144567)
		(end 174.368358 140.330698)
		(width 0.127)
		(layer "In2.Cu")
		(net "PCIE_RX1_N")
	)
	(arc
		(start 126.614365 142.226405)
		(mid 127.527961 141.61596)
		(end 128.60562 141.4016)
		(width 0.127)
		(layer "In2.Cu")
		(net "PCIE_RX1_N")
	)
	(segment
		(start 175.33596 136.46338)
		(end 175.33596 135.50523)
		(width 0.127)
		(layer "F.Cu")
		(net "PCIE_RX1_P")
	)
	(segment
		(start 121.52609 157.0786)
		(end 121.52609 153.84069)
		(width 0.127)
		(layer "F.Cu")
		(net "PCIE_RX1_P")
	)
	(segment
		(start 175.0261 137.6286)
		(end 175.0261 137.21144)
		(width 0.127)
		(layer "F.Cu")
		(net "PCIE_RX1_P")
	)
	(via
		(at 121.3761 153.4786)
		(size 0.4064)
		(drill 0.2032)
		(layers "F.Cu" "B.Cu")
		(tenting
			(front yes)
			(back yes)
		)
		(net "PCIE_RX1_P")
	)
	(via
		(at 175.0261 137.6286)
		(size 0.4064)
		(drill 0.2032)
		(layers "F.Cu" "B.Cu")
		(tenting
			(front yes)
			(back yes)
		)
		(net "PCIE_RX1_P")
	)
	(arc
		(start 175.33596 136.46338)
		(mid 175.307409 136.606917)
		(end 175.226102 136.728602)
		(width 0.127)
		(layer "F.Cu")
		(net "PCIE_RX1_P")
	)
	(arc
		(start 121.376105 153.478595)
		(mid 121.48711 153.644726)
		(end 121.52609 153.84069)
		(width 0.127)
		(layer "F.Cu")
		(net "PCIE_RX1_P")
	)
	(arc
		(start 121.546085 157.757595)
		(mid 121.365806 157.487788)
		(end 121.302501 157.16953)
		(width 0.127)
		(layer "F.Cu")
		(net "PCIE_RX1_P")
	)
	(arc
		(start 175.0261 137.21144)
		(mid 175.078078 136.950128)
		(end 175.226099 136.728599)
		(width 0.127)
		(layer "F.Cu")
		(net "PCIE_RX1_P")
	)
	(segment
		(start 128.607 141.681)
		(end 172.24958 141.681)
		(width 0.127)
		(layer "In2.Cu")
		(net "PCIE_RX1_P")
	)
	(segment
		(start 174.8624 138.029)
		(end 174.8624 139.87054)
		(width 0.127)
		(layer "In2.Cu")
		(net "PCIE_RX1_P")
	)
	(segment
		(start 121.9761 150.6786)
		(end 121.9761 150.6786)
		(width 0.127)
		(layer "In2.Cu")
		(net "PCIE_RX1_P")
	)
	(segment
		(start 121.9761 150.6786)
		(end 121.9761 150.49942)
		(width 0.127)
		(layer "In2.Cu")
		(net "PCIE_RX1_P")
	)
	(segment
		(start 121.97609 151.01483)
		(end 121.97609 150.7421)
		(width 0.127)
		(layer "In2.Cu")
		(net "PCIE_RX1_P")
	)
	(segment
		(start 121.72374 153.0151)
		(end 121.85615 152.49208)
		(width 0.127)
		(layer "In2.Cu")
		(net "PCIE_RX1_P")
	)
	(segment
		(start 121.97609 150.7421)
		(end 121.9761 150.6786)
		(width 0.127)
		(layer "In2.Cu")
		(net "PCIE_RX1_P")
	)
	(segment
		(start 122.77367 148.57616)
		(end 122.77367 148.57616)
		(width 0.127)
		(layer "In2.Cu")
		(net "PCIE_RX1_P")
	)
	(segment
		(start 122.04082 152.34833)
		(end 122.41719 152.34833)
		(width 0.127)
		(layer "In2.Cu")
		(net "PCIE_RX1_P")
	)
	(segment
		(start 121.85614 152.49208)
		(end 121.85615 152.49208)
		(width 0.127)
		(layer "In2.Cu")
		(net "PCIE_RX1_P")
	)
	(segment
		(start 175.0261 137.6286)
		(end 175.0261 137.6286)
		(width 0.127)
		(layer "In2.Cu")
		(net "PCIE_RX1_P")
	)
	(segment
		(start 174.24084 140.85334)
		(end 174.60697 140.48721)
		(width 0.127)
		(layer "In2.Cu")
		(net "PCIE_RX1_P")
	)
	(segment
		(start 124.73578 144.50013)
		(end 126.81095 142.42495)
		(width 0.127)
		(layer "In2.Cu")
		(net "PCIE_RX1_P")
	)
	(segment
		(start 122.10817 151.58633)
		(end 122.3248 151.58633)
		(width 0.127)
		(layer "In2.Cu")
		(net "PCIE_RX1_P")
	)
	(segment
		(start 122.10817 151.96733)
		(end 122.41719 151.96733)
		(width 0.127)
		(layer "In2.Cu")
		(net "PCIE_RX1_P")
	)
	(segment
		(start 122.77367 148.57616)
		(end 123.241 148.10884)
		(width 0.127)
		(layer "In2.Cu")
		(net "PCIE_RX1_P")
	)
	(segment
		(start 174.24084 140.85619)
		(end 174.24084 140.85334)
		(width 0.127)
		(layer "In2.Cu")
		(net "PCIE_RX1_P")
	)
	(segment
		(start 122.16659 151.20533)
		(end 122.3248 151.20533)
		(width 0.127)
		(layer "In2.Cu")
		(net "PCIE_RX1_P")
	)
	(arc
		(start 122.3248 151.20533)
		(mid 122.5153 151.39583)
		(end 122.3248 151.58633)
		(width 0.127)
		(layer "In2.Cu")
		(net "PCIE_RX1_P")
	)
	(arc
		(start 121.723736 153.015098)
		(mid 121.705863 153.04701)
		(end 121.687422 153.078598)
		(width 0.127)
		(layer "In2.Cu")
		(net "PCIE_RX1_P")
	)
	(arc
		(start 121.976101 150.499412)
		(mid 122.183809 149.458548)
		(end 122.773667 148.576159)
		(width 0.127)
		(layer "In2.Cu")
		(net "PCIE_RX1_P")
	)
	(arc
		(start 124.06579 146.117584)
		(mid 124.239912 145.242222)
		(end 124.735766 144.500126)
		(width 0.127)
		(layer "In2.Cu")
		(net "PCIE_RX1_P")
	)
	(arc
		(start 122.16659 151.20533)
		(mid 122.031885 151.149533)
		(end 121.97609 151.014827)
		(width 0.127)
		(layer "In2.Cu")
		(net "PCIE_RX1_P")
	)
	(arc
		(start 122.41719 151.96733)
		(mid 122.60769 152.15783)
		(end 122.41719 152.34833)
		(width 0.127)
		(layer "In2.Cu")
		(net "PCIE_RX1_P")
	)
	(arc
		(start 174.862402 138.028999)
		(mid 174.900945 137.823647)
		(end 175.012209 137.646799)
		(width 0.127)
		(layer "In2.Cu")
		(net "PCIE_RX1_P")
	)
	(arc
		(start 174.8624 139.87054)
		(mid 174.796015 140.204282)
		(end 174.606965 140.487215)
		(width 0.127)
		(layer "In2.Cu")
		(net "PCIE_RX1_P")
	)
	(arc
		(start 122.10817 151.96733)
		(mid 121.91767 151.77683)
		(end 122.10817 151.58633)
		(width 0.127)
		(layer "In2.Cu")
		(net "PCIE_RX1_P")
	)
	(arc
		(start 126.810949 142.424949)
		(mid 127.634984 141.874346)
		(end 128.607 141.681)
		(width 0.127)
		(layer "In2.Cu")
		(net "PCIE_RX1_P")
	)
	(arc
		(start 124.0658 146.117583)
		(mid 123.85144 147.195241)
		(end 123.240995 148.108835)
		(width 0.127)
		(layer "In2.Cu")
		(net "PCIE_RX1_P")
	)
	(arc
		(start 175.026102 137.628602)
		(mid 175.019565 137.638011)
		(end 175.012206 137.646793)
		(width 0.127)
		(layer "In2.Cu")
		(net "PCIE_RX1_P")
	)
	(arc
		(start 121.687422 153.078598)
		(mid 121.54418 153.288265)
		(end 121.3761 153.478599)
		(width 0.127)
		(layer "In2.Cu")
		(net "PCIE_RX1_P")
	)
	(arc
		(start 121.856146 152.492079)
		(mid 121.923807 152.388503)
		(end 122.04082 152.34833)
		(width 0.127)
		(layer "In2.Cu")
		(net "PCIE_RX1_P")
	)
	(arc
		(start 174.240842 140.856192)
		(mid 173.327243 141.466639)
		(end 172.24958 141.681)
		(width 0.127)
		(layer "In2.Cu")
		(net "PCIE_RX1_P")
	)
	(segment
		(start 173.33596 132.91874)
		(end 173.33596 131.45545)
		(width 0.127)
		(layer "F.Cu")
		(net "PCIE_RX0_N")
	)
	(segment
		(start 117.52609 157.0786)
		(end 117.52609 154.56501)
		(width 0.127)
		(layer "F.Cu")
		(net "PCIE_RX0_N")
	)
	(via
		(at 173.2261 133.0286)
		(size 0.4064)
		(drill 0.2032)
		(layers "F.Cu" "B.Cu")
		(tenting
			(front yes)
			(back yes)
		)
		(net "PCIE_RX0_N")
	)
	(via
		(at 117.9761 153.4786)
		(size 0.4064)
		(drill 0.2032)
		(layers "F.Cu" "B.Cu")
		(tenting
			(front yes)
			(back yes)
		)
		(net "PCIE_RX0_N")
	)
	(arc
		(start 117.52609 154.56501)
		(mid 117.643043 153.977048)
		(end 117.976097 153.478597)
		(width 0.127)
		(layer "F.Cu")
		(net "PCIE_RX0_N")
	)
	(arc
		(start 173.33596 132.91874)
		(mid 173.303783 132.996423)
		(end 173.2261 133.0286)
		(width 0.127)
		(layer "F.Cu")
		(net "PCIE_RX0_N")
	)
	(arc
		(start 117.546094 157.757596)
		(mid 117.374837 157.501292)
		(end 117.314699 157.19896)
		(width 0.127)
		(layer "F.Cu")
		(net "PCIE_RX0_N")
	)
	(segment
		(start 118.3761 153.0786)
		(end 118.42101 153.03369)
		(width 0.127)
		(layer "In2.Cu")
		(net "PCIE_RX0_N")
	)
	(segment
		(start 127.48802 140.8428)
		(end 169.07319 140.8428)
		(width 0.127)
		(layer "In2.Cu")
		(net "PCIE_RX0_N")
	)
	(segment
		(start 119.76802 151.41722)
		(end 119.76805 151.41724)
		(width 0.127)
		(layer "In2.Cu")
		(net "PCIE_RX0_N")
	)
	(segment
		(start 170.86925 140.09885)
		(end 170.9381 140.03)
		(width 0.127)
		(layer "In2.Cu")
		(net "PCIE_RX0_N")
	)
	(segment
		(start 117.9761 153.4786)
		(end 118.3761 153.0786)
		(width 0.127)
		(layer "In2.Cu")
		(net "PCIE_RX0_N")
	)
	(segment
		(start 118.60672 152.41117)
		(end 118.69041 152.49487)
		(width 0.127)
		(layer "In2.Cu")
		(net "PCIE_RX0_N")
	)
	(segment
		(start 119.76805 151.41725)
		(end 119.76805 151.41724)
		(width 0.127)
		(layer "In2.Cu")
		(net "PCIE_RX0_N")
	)
	(segment
		(start 121.56566 145.59871)
		(end 125.49676 141.66761)
		(width 0.127)
		(layer "In2.Cu")
		(net "PCIE_RX0_N")
	)
	(segment
		(start 118.33731 152.68058)
		(end 118.42101 152.76428)
		(width 0.127)
		(layer "In2.Cu")
		(net "PCIE_RX0_N")
	)
	(segment
		(start 171.9256 136.52909)
		(end 172.69245 135.76224)
		(width 0.127)
		(layer "In2.Cu")
		(net "PCIE_RX0_N")
	)
	(segment
		(start 120.48333 150.97137)
		(end 120.64219 150.81251)
		(width 0.127)
		(layer "In2.Cu")
		(net "PCIE_RX0_N")
	)
	(segment
		(start 171.5467 138.56072)
		(end 171.5467 137.44385)
		(width 0.127)
		(layer "In2.Cu")
		(net "PCIE_RX0_N")
	)
	(segment
		(start 119.16654 151.89337)
		(end 119.22923 151.95605)
		(width 0.127)
		(layer "In2.Cu")
		(net "PCIE_RX0_N")
	)
	(segment
		(start 120.03746 151.41724)
		(end 120.48333 150.97137)
		(width 0.127)
		(layer "In2.Cu")
		(net "PCIE_RX0_N")
	)
	(segment
		(start 120.64219 150.81251)
		(end 120.74056 150.71414)
		(width 0.127)
		(layer "In2.Cu")
		(net "PCIE_RX0_N")
	)
	(segment
		(start 120.74056 147.80497)
		(end 120.74056 147.5907)
		(width 0.127)
		(layer "In2.Cu")
		(net "PCIE_RX0_N")
	)
	(segment
		(start 120.74056 150.71414)
		(end 120.74056 147.80497)
		(width 0.127)
		(layer "In2.Cu")
		(net "PCIE_RX0_N")
	)
	(segment
		(start 173.4364 133.96619)
		(end 173.4364 133.54011)
		(width 0.127)
		(layer "In2.Cu")
		(net "PCIE_RX0_N")
	)
	(segment
		(start 118.89713 152.16277)
		(end 118.95982 152.22546)
		(width 0.127)
		(layer "In2.Cu")
		(net "PCIE_RX0_N")
	)
	(segment
		(start 173.2261 133.03239)
		(end 173.2261 133.0286)
		(width 0.127)
		(layer "In2.Cu")
		(net "PCIE_RX0_N")
	)
	(segment
		(start 119.49862 151.68663)
		(end 119.49864 151.68665)
		(width 0.127)
		(layer "In2.Cu")
		(net "PCIE_RX0_N")
	)
	(arc
		(start 120.037454 151.417244)
		(mid 119.90275 151.47304)
		(end 119.768046 151.417244)
		(width 0.127)
		(layer "In2.Cu")
		(net "PCIE_RX0_N")
	)
	(arc
		(start 118.959824 152.225466)
		(mid 119.01562 152.36017)
		(end 118.959824 152.494874)
		(width 0.127)
		(layer "In2.Cu")
		(net "PCIE_RX0_N")
	)
	(arc
		(start 171.5467 138.56072)
		(mid 171.388531 139.35589)
		(end 170.938103 140.030003)
		(width 0.127)
		(layer "In2.Cu")
		(net "PCIE_RX0_N")
	)
	(arc
		(start 118.337306 152.411176)
		(mid 118.47201 152.35538)
		(end 118.606714 152.411176)
		(width 0.127)
		(layer "In2.Cu")
		(net "PCIE_RX0_N")
	)
	(arc
		(start 119.498616 151.417216)
		(mid 119.63332 151.36142)
		(end 119.768024 151.417216)
		(width 0.127)
		(layer "In2.Cu")
		(net "PCIE_RX0_N")
	)
	(arc
		(start 118.421014 152.764286)
		(mid 118.47681 152.89899)
		(end 118.421014 153.033694)
		(width 0.127)
		(layer "In2.Cu")
		(net "PCIE_RX0_N")
	)
	(arc
		(start 170.869241 140.098851)
		(mid 170.045206 140.649454)
		(end 169.07319 140.8428)
		(width 0.127)
		(layer "In2.Cu")
		(net "PCIE_RX0_N")
	)
	(arc
		(start 118.337316 152.680584)
		(mid 118.28152 152.545882)
		(end 118.337313 152.411179)
		(width 0.127)
		(layer "In2.Cu")
		(net "PCIE_RX0_N")
	)
	(arc
		(start 173.226107 133.032393)
		(mid 173.381754 133.265336)
		(end 173.43641 133.54011)
		(width 0.127)
		(layer "In2.Cu")
		(net "PCIE_RX0_N")
	)
	(arc
		(start 125.496765 141.667605)
		(mid 126.410361 141.05716)
		(end 127.48802 140.8428)
		(width 0.127)
		(layer "In2.Cu")
		(net "PCIE_RX0_N")
	)
	(arc
		(start 119.498616 151.686624)
		(mid 119.44282 151.551922)
		(end 119.498613 151.417219)
		(width 0.127)
		(layer "In2.Cu")
		(net "PCIE_RX0_N")
	)
	(arc
		(start 119.498634 151.686646)
		(mid 119.55443 151.82135)
		(end 119.498634 151.956054)
		(width 0.127)
		(layer "In2.Cu")
		(net "PCIE_RX0_N")
	)
	(arc
		(start 118.959821 152.494866)
		(mid 118.825119 152.55066)
		(end 118.690417 152.494864)
		(width 0.127)
		(layer "In2.Cu")
		(net "PCIE_RX0_N")
	)
	(arc
		(start 118.897136 151.893366)
		(mid 119.03184 151.83757)
		(end 119.166544 151.893366)
		(width 0.127)
		(layer "In2.Cu")
		(net "PCIE_RX0_N")
	)
	(arc
		(start 173.4364 133.96619)
		(mid 173.243054 134.938206)
		(end 172.692451 135.762241)
		(width 0.127)
		(layer "In2.Cu")
		(net "PCIE_RX0_N")
	)
	(arc
		(start 118.897136 152.162774)
		(mid 118.84134 152.028072)
		(end 118.897133 151.893369)
		(width 0.127)
		(layer "In2.Cu")
		(net "PCIE_RX0_N")
	)
	(arc
		(start 120.74056 147.5907)
		(mid 120.954999 146.512643)
		(end 121.565669 145.598709)
		(width 0.127)
		(layer "In2.Cu")
		(net "PCIE_RX0_N")
	)
	(arc
		(start 119.498631 151.956056)
		(mid 119.363929 152.01185)
		(end 119.229227 151.956054)
		(width 0.127)
		(layer "In2.Cu")
		(net "PCIE_RX0_N")
	)
	(arc
		(start 171.5467 137.44385)
		(mid 171.645174 136.948788)
		(end 171.925604 136.529094)
		(width 0.127)
		(layer "In2.Cu")
		(net "PCIE_RX0_N")
	)
	(segment
		(start 173.83583 132.93833)
		(end 173.83583 131.45545)
		(width 0.127)
		(layer "F.Cu")
		(net "PCIE_RX0_P")
	)
	(segment
		(start 116.5261 157.0786)
		(end 116.5261 155.04785)
		(width 0.127)
		(layer "F.Cu")
		(net "PCIE_RX0_P")
	)
	(via
		(at 117.1761 153.4786)
		(size 0.4064)
		(drill 0.2032)
		(layers "F.Cu" "B.Cu")
		(tenting
			(front yes)
			(back yes)
		)
		(net "PCIE_RX0_P")
	)
	(via
		(at 173.9261 133.0286)
		(size 0.4064)
		(drill 0.2032)
		(layers "F.Cu" "B.Cu")
		(tenting
			(front yes)
			(back yes)
		)
		(net "PCIE_RX0_P")
	)
	(arc
		(start 173.9261 133.0286)
		(mid 173.862269 133.002161)
		(end 173.83583 132.93833)
		(width 0.127)
		(layer "F.Cu")
		(net "PCIE_RX0_P")
	)
	(arc
		(start 116.5261 155.04785)
		(mid 116.69503 154.19858)
		(end 117.176103 153.478603)
		(width 0.127)
		(layer "F.Cu")
		(net "PCIE_RX0_P")
	)
	(segment
		(start 121.7639 145.7956)
		(end 125.69335 141.86615)
		(width 0.127)
		(layer "In2.Cu")
		(net "PCIE_RX0_P")
	)
	(segment
		(start 172.12367 136.72616)
		(end 172.891 135.95883)
		(width 0.127)
		(layer "In2.Cu")
		(net "PCIE_RX0_P")
	)
	(segment
		(start 173.7158 133.96758)
		(end 173.7158 133.5401)
		(width 0.127)
		(layer "In2.Cu")
		(net "PCIE_RX0_P")
	)
	(segment
		(start 171.8261 138.56267)
		(end 171.8261 137.44379)
		(width 0.127)
		(layer "In2.Cu")
		(net "PCIE_RX0_P")
	)
	(segment
		(start 118.4734 153.3533)
		(end 121.0142 150.81251)
		(width 0.127)
		(layer "In2.Cu")
		(net "PCIE_RX0_P")
	)
	(segment
		(start 173.9261 133.0324)
		(end 173.9261 133.0286)
		(width 0.127)
		(layer "In2.Cu")
		(net "PCIE_RX0_P")
	)
	(segment
		(start 171.06632 140.29692)
		(end 171.13705 140.22618)
		(width 0.127)
		(layer "In2.Cu")
		(net "PCIE_RX0_P")
	)
	(segment
		(start 117.39206 153.4786)
		(end 117.39206 153.4786)
		(width 0.127)
		(layer "In2.Cu")
		(net "PCIE_RX0_P")
	)
	(segment
		(start 127.4894 141.1222)
		(end 169.0739 141.1222)
		(width 0.127)
		(layer "In2.Cu")
		(net "PCIE_RX0_P")
	)
	(segment
		(start 121.0142 147.80497)
		(end 121.0142 147.60556)
		(width 0.127)
		(layer "In2.Cu")
		(net "PCIE_RX0_P")
	)
	(segment
		(start 121.0142 150.81251)
		(end 121.0142 147.80497)
		(width 0.127)
		(layer "In2.Cu")
		(net "PCIE_RX0_P")
	)
	(segment
		(start 117.1761 153.4786)
		(end 117.39206 153.4786)
		(width 0.127)
		(layer "In2.Cu")
		(net "PCIE_RX0_P")
	)
	(segment
		(start 172.12367 136.72616)
		(end 172.12367 136.72616)
		(width 0.127)
		(layer "In2.Cu")
		(net "PCIE_RX0_P")
	)
	(arc
		(start 118.308368 153.810871)
		(mid 117.84376 153.929479)
		(end 117.51696 153.578581)
		(width 0.127)
		(layer "In2.Cu")
		(net "PCIE_RX0_P")
	)
	(arc
		(start 171.8261 137.443796)
		(mid 171.903579 137.055415)
		(end 172.123664 136.726165)
		(width 0.127)
		(layer "In2.Cu")
		(net "PCIE_RX0_P")
	)
	(arc
		(start 171.8261 138.562673)
		(mid 171.647021 139.462961)
		(end 171.137048 140.226188)
		(width 0.127)
		(layer "In2.Cu")
		(net "PCIE_RX0_P")
	)
	(arc
		(start 173.7158 133.96758)
		(mid 173.50144 135.04524)
		(end 172.890995 135.958835)
		(width 0.127)
		(layer "In2.Cu")
		(net "PCIE_RX0_P")
	)
	(arc
		(start 125.693349 141.866149)
		(mid 126.517384 141.315546)
		(end 127.4894 141.1222)
		(width 0.127)
		(layer "In2.Cu")
		(net "PCIE_RX0_P")
	)
	(arc
		(start 173.7158 133.5401)
		(mid 173.770455 133.265331)
		(end 173.926098 133.032393)
		(width 0.127)
		(layer "In2.Cu")
		(net "PCIE_RX0_P")
	)
	(arc
		(start 117.392067 153.478603)
		(mid 117.472235 153.506453)
		(end 117.516961 153.578578)
		(width 0.127)
		(layer "In2.Cu")
		(net "PCIE_RX0_P")
	)
	(arc
		(start 121.01419 147.60556)
		(mid 121.209034 146.626016)
		(end 121.763901 145.795599)
		(width 0.127)
		(layer "In2.Cu")
		(net "PCIE_RX0_P")
	)
	(arc
		(start 171.066323 140.296915)
		(mid 170.152191 140.907716)
		(end 169.0739 141.1222)
		(width 0.127)
		(layer "In2.Cu")
		(net "PCIE_RX0_P")
	)
	(arc
		(start 118.473404 153.353305)
		(mid 118.441959 153.600505)
		(end 118.308376 153.810868)
		(width 0.127)
		(layer "In2.Cu")
		(net "PCIE_RX0_P")
	)
	(segment
		(start 69.8559 56.3114)
		(end 69.8761 56.2912)
		(width 0.2032)
		(layer "F.Cu")
		(net "LED1")
	)
	(segment
		(start 195.31345 123.81347)
		(end 195.31363 123.8133)
		(width 0.2032)
		(layer "F.Cu")
		(net "LED1")
	)
	(segment
		(start 193.34123 123.81347)
		(end 195.31345 123.81347)
		(width 0.2032)
		(layer "F.Cu")
		(net "LED1")
	)
	(segment
		(start 69.8559 57.4)
		(end 69.8559 56.3114)
		(width 0.2032)
		(layer "F.Cu")
		(net "LED1")
	)
	(segment
		(start 193.34105 123.81365)
		(end 193.34123 123.81347)
		(width 0.2032)
		(layer "F.Cu")
		(net "LED1")
	)
	(via
		(at 193.34105 123.81365)
		(size 0.4064)
		(drill 0.2032)
		(layers "F.Cu" "B.Cu")
		(tenting
			(front yes)
			(back yes)
		)
		(net "LED1")
	)
	(via
		(at 69.8559 57.4)
		(size 0.4064)
		(drill 0.2032)
		(layers "F.Cu" "B.Cu")
		(tenting
			(front yes)
			(back yes)
		)
		(net "LED1")
	)
	(segment
		(start 69.8559 80.24691)
		(end 69.8559 57.4)
		(width 0.2032)
		(layer "In2.Cu")
		(net "LED1")
	)
	(segment
		(start 189.1759 127.9788)
		(end 193.34105 123.81365)
		(width 0.2032)
		(layer "In2.Cu")
		(net "LED1")
	)
	(segment
		(start 89.6761 115.6786)
		(end 89.6761 100.06711)
		(width 0.2032)
		(layer "In2.Cu")
		(net "LED1")
	)
	(segment
		(start 89.6761 115.6786)
		(end 103.3137 129.3162)
		(width 0.2032)
		(layer "In2.Cu")
		(net "LED1")
	)
	(segment
		(start 155.3759 127.9788)
		(end 189.1759 127.9788)
		(width 0.2032)
		(layer "In2.Cu")
		(net "LED1")
	)
	(segment
		(start 69.8559 80.24691)
		(end 89.6761 100.06711)
		(width 0.2032)
		(layer "In2.Cu")
		(net "LED1")
	)
	(segment
		(start 103.3137 129.3162)
		(end 154.0385 129.3162)
		(width 0.2032)
		(layer "In2.Cu")
		(net "LED1")
	)
	(segment
		(start 154.0385 129.3162)
		(end 155.3759 127.9788)
		(width 0.2032)
		(layer "In2.Cu")
		(net "LED1")
	)
	(segment
		(start 193.47568 123.31342)
		(end 195.31363 123.31342)
		(width 0.2032)
		(layer "F.Cu")
		(net "LED2")
	)
	(segment
		(start 71.6261 57.3662)
		(end 71.6261 56.2912)
		(width 0.2032)
		(layer "F.Cu")
		(net "LED2")
	)
	(segment
		(start 193.31202 123.20475)
		(end 193.367 123.20475)
		(width 0.2032)
		(layer "F.Cu")
		(net "LED2")
	)
	(segment
		(start 193.367 123.20475)
		(end 193.47568 123.31342)
		(width 0.2032)
		(layer "F.Cu")
		(net "LED2")
	)
	(via
		(at 193.31202 123.20475)
		(size 0.4064)
		(drill 0.2032)
		(layers "F.Cu" "B.Cu")
		(tenting
			(front yes)
			(back yes)
		)
		(net "LED2")
	)
	(via
		(at 71.6261 57.3662)
		(size 0.4064)
		(drill 0.2032)
		(layers "F.Cu" "B.Cu")
		(tenting
			(front yes)
			(back yes)
		)
		(net "LED2")
	)
	(segment
		(start 153.9385 128.8162)
		(end 156.09631 126.65839)
		(width 0.2032)
		(layer "In2.Cu")
		(net "LED2")
	)
	(segment
		(start 103.4137 128.8162)
		(end 153.9385 128.8162)
		(width 0.2032)
		(layer "In2.Cu")
		(net "LED2")
	)
	(segment
		(start 71.6261 81.55014)
		(end 90.0157 99.93974)
		(width 0.2032)
		(layer "In2.Cu")
		(net "LED2")
	)
	(segment
		(start 189.85837 126.65839)
		(end 193.31202 123.20475)
		(width 0.2032)
		(layer "In2.Cu")
		(net "LED2")
	)
	(segment
		(start 71.6261 81.55014)
		(end 71.6261 57.3662)
		(width 0.2032)
		(layer "In2.Cu")
		(net "LED2")
	)
	(segment
		(start 90.0157 115.4182)
		(end 103.4137 128.8162)
		(width 0.2032)
		(layer "In2.Cu")
		(net "LED2")
	)
	(segment
		(start 90.0157 115.4182)
		(end 90.0157 99.93974)
		(width 0.2032)
		(layer "In2.Cu")
		(net "LED2")
	)
	(segment
		(start 156.09631 126.65839)
		(end 189.85837 126.65839)
		(width 0.2032)
		(layer "In2.Cu")
		(net "LED2")
	)
	(segment
		(start 198.18109 119.6242)
		(end 198.46849 119.3368)
		(width 0.2032)
		(layer "F.Cu")
		(net "GND")
	)
	(segment
		(start 177.3011 97.16189)
		(end 177.30249 97.16327)
		(width 0.2032)
		(layer "F.Cu")
		(net "GND")
	)
	(segment
		(start 148.33887 117.31039)
		(end 148.74187 117.31039)
		(width 0.254)
		(layer "F.Cu")
		(net "GND")
	)
	(segment
		(start 198.13375 121.82095)
		(end 199.35575 121.82095)
		(width 0.2032)
		(layer "F.Cu")
		(net "GND")
	)
	(segment
		(start 150.2847 112.3102)
		(end 150.28597 112.30893)
		(width 0.254)
		(layer "F.Cu")
		(net "GND")
	)
	(segment
		(start 92.1261 76.2206)
		(end 92.1261 75.2786)
		(width 0.2032)
		(layer "F.Cu")
		(net "GND")
	)
	(segment
		(start 195.32128 121.82095)
		(end 196.61845 121.82095)
		(width 0.2032)
		(layer "F.Cu")
		(net "GND")
	)
	(segment
		(start 123.52608 157.0786)
		(end 123.52608 154.60118)
		(width 0.508)
		(layer "F.Cu")
		(net "GND")
	)
	(segment
		(start 195.32127 111.82096)
		(end 196.61846 111.82096)
		(width 0.2032)
		(layer "F.Cu")
		(net "GND")
	)
	(segment
		(start 172.32587 93.86847)
		(end 172.34923 93.89184)
		(width 0.2032)
		(layer "F.Cu")
		(net "GND")
	)
	(segment
		(start 225.59931 136.46799)
		(end 225.59931 135.04299)
		(width 0.254)
		(layer "F.Cu")
		(net "GND")
	)
	(segment
		(start 198.13368 109.32103)
		(end 199.35583 109.32103)
		(width 0.2032)
		(layer "F.Cu")
		(net "GND")
	)
	(segment
		(start 179.7931 96.39385)
		(end 179.80941 96.41016)
		(width 0.2032)
		(layer "F.Cu")
		(net "GND")
	)
	(segment
		(start 80.54375 100.66367)
		(end 80.54375 100.60868)
		(width 0.2032)
		(layer "F.Cu")
		(net "GND")
	)
	(segment
		(start 195.1511 85.8536)
		(end 195.1511 84.8536)
		(width 0.2032)
		(layer "F.Cu")
		(net "GND")
	)
	(segment
		(start 186.8761 90.0786)
		(end 187.1261 89.8286)
		(width 0.2032)
		(layer "F.Cu")
		(net "GND")
	)
	(segment
		(start 71.1261 103.3662)
		(end 71.1261 101.8662)
		(width 0.2032)
		(layer "F.Cu")
		(net "GND")
	)
	(segment
		(start 127.9511 154.1786)
		(end 128.43222 154.65972)
		(width 0.508)
		(layer "F.Cu")
		(net "GND")
	)
	(segment
		(start 183.3761 86.5786)
		(end 185.3636 86.5786)
		(width 0.2032)
		(layer "F.Cu")
		(net "GND")
	)
	(segment
		(start 128.43222 156.98475)
		(end 128.43222 154.65972)
		(width 0.508)
		(layer "F.Cu")
		(net "GND")
	)
	(segment
		(start 195.1261 85.8286)
		(end 195.1511 85.8536)
		(width 0.2032)
		(layer "F.Cu")
		(net "GND")
	)
	(segment
		(start 127.44472 156.99725)
		(end 127.44472 154.64722)
		(width 0.508)
		(layer "F.Cu")
		(net "GND")
	)
	(segment
		(start 226.8761 67.8286)
		(end 226.8761 66.6162)
		(width 0.254)
		(layer "F.Cu")
		(net "GND")
	)
	(segment
		(start 124.51973 155.99134)
		(end 124.51973 154.57938)
		(width 0.508)
		(layer "F.Cu")
		(net "GND")
	)
	(segment
		(start 115.2761 154.3286)
		(end 115.50423 154.55673)
		(width 0.508)
		(layer "F.Cu")
		(net "GND")
	)
	(segment
		(start 177.34922 95.20172)
		(end 177.34922 93.89184)
		(width 0.2032)
		(layer "F.Cu")
		(net "GND")
	)
	(segment
		(start 172.9261 129.76984)
		(end 172.9261 129.7286)
		(width 0.254)
		(layer "F.Cu")
		(net "GND")
	)
	(segment
		(start 196.57112 119.6242)
		(end 196.6261 119.6242)
		(width 0.2032)
		(layer "F.Cu")
		(net "GND")
	)
	(segment
		(start 118.03129 154.41678)
		(end 118.34343 154.65301)
		(width 0.508)
		(layer "F.Cu")
		(net "GND")
	)
	(segment
		(start 207.0967 90.7142)
		(end 207.0967 88.7472)
		(width 0.254)
		(layer "F.Cu")
		(net "GND")
	)
	(segment
		(start 124.54608 157.7576)
		(end 124.54608 156.0177)
		(width 0.508)
		(layer "F.Cu")
		(net "GND")
	)
	(segment
		(start 209.4785 107.6662)
		(end 210.55741 107.6662)
		(width 0.2032)
		(layer "F.Cu")
		(net "GND")
	)
	(segment
		(start 198.13374 111.82096)
		(end 199.35576 111.82096)
		(width 0.2032)
		(layer "F.Cu")
		(net "GND")
	)
	(segment
		(start 172.82599 130.83087)
		(end 172.82599 129.86995)
		(width 0.254)
		(layer "F.Cu")
		(net "GND")
	)
	(segment
		(start 174.8091 96.4036)
		(end 174.81742 96.41192)
		(width 0.2032)
		(layer "F.Cu")
		(net "GND")
	)
	(segment
		(start 82.42611 87.6162)
		(end 83.1261 87.6162)
		(width 0.254)
		(layer "F.Cu")
		(net "GND")
	)
	(segment
		(start 147.70279 119.80676)
		(end 148.42598 119.80676)
		(width 0.254)
		(layer "F.Cu")
		(net "GND")
	)
	(segment
		(start 210.63351 107.7423)
		(end 210.6885 107.7423)
		(width 0.2032)
		(layer "F.Cu")
		(net "GND")
	)
	(segment
		(start 179.8761 87.0786)
		(end 180.1261 86.8286)
		(width 0.2032)
		(layer "F.Cu")
		(net "GND")
	)
	(segment
		(start 172.34923 95.19373)
		(end 172.3841 95.2286)
		(width 0.2032)
		(layer "F.Cu")
		(net "GND")
	)
	(segment
		(start 230.39336 136.44894)
		(end 230.39336 135.04894)
		(width 0.254)
		(layer "F.Cu")
		(net "GND")
	)
	(segment
		(start 120.53059 157.74211)
		(end 120.53059 154.37508)
		(width 0.508)
		(layer "F.Cu")
		(net "GND")
	)
	(segment
		(start 216.2885 117.9662)
		(end 216.2885 117.0272)
		(width 0.2032)
		(layer "F.Cu")
		(net "GND")
	)
	(segment
		(start 150.37309 109.80881)
		(end 151.75053 109.80881)
		(width 0.254)
		(layer "F.Cu")
		(net "GND")
	)
	(segment
		(start 149.16456 107.30894)
		(end 149.1671 107.3064)
		(width 0.254)
		(layer "F.Cu")
		(net "GND")
	)
	(segment
		(start 136.26304 116.53826)
		(end 136.32038 116.48092)
		(width 0.2032)
		(layer "F.Cu")
		(net "GND")
	)
	(segment
		(start 130.99597 154.1786)
		(end 131.30685 154.53599)
		(width 0.508)
		(layer "F.Cu")
		(net "GND")
	)
	(segment
		(start 74.3761 134.1412)
		(end 74.3761 133.1162)
		(width 0.2032)
		(layer "F.Cu")
		(net "GND")
	)
	(segment
		(start 219.1637 85.1662)
		(end 220.1737 85.1662)
		(width 0.2032)
		(layer "F.Cu")
		(net "GND")
	)
	(segment
		(start 195.31363 106.81333)
		(end 195.32126 106.82097)
		(width 0.2032)
		(layer "F.Cu")
		(net "GND")
	)
	(segment
		(start 177.30249 97.89488)
		(end 177.32586 97.91825)
		(width 0.2032)
		(layer "F.Cu")
		(net "GND")
	)
	(segment
		(start 128.43222 156.98475)
		(end 128.52607 157.0786)
		(width 0.508)
		(layer "F.Cu")
		(net "GND")
	)
	(segment
		(start 79.3761 112.8662)
		(end 80.5761 112.8662)
		(width 0.2032)
		(layer "F.Cu")
		(net "GND")
	)
	(segment
		(start 147.70076 109.80881)
		(end 149.17929 109.80881)
		(width 0.254)
		(layer "F.Cu")
		(net "GND")
	)
	(segment
		(start 197.3761 83.5786)
		(end 197.3761 81.5866)
		(width 0.2032)
		(layer "F.Cu")
		(net "GND")
	)
	(segment
		(start 147.70076 122.30891)
		(end 149.07439 122.30891)
		(width 0.254)
		(layer "F.Cu")
		(net "GND")
	)
	(segment
		(start 136.32038 116.48092)
		(end 137.66107 116.48092)
		(width 0.2032)
		(layer "F.Cu")
		(net "GND")
	)
	(segment
		(start 82.3761 87.5662)
		(end 82.3761 87.5662)
		(width 0.254)
		(layer "F.Cu")
		(net "GND")
	)
	(segment
		(start 124.51973 157.07224)
		(end 124.51973 155.99134)
		(width 0.508)
		(layer "F.Cu")
		(net "GND")
	)
	(segment
		(start 123.2285 154.3036)
		(end 123.52608 154.60118)
		(width 0.508)
		(layer "F.Cu")
		(net "GND")
	)
	(segment
		(start 151.54502 80.19267)
		(end 151.54502 77.94847)
		(width 0.762)
		(layer "F.Cu")
		(net "GND")
	)
	(segment
		(start 128.3761 86.8286)
		(end 128.8761 87.3286)
		(width 0.2032)
		(layer "F.Cu")
		(net "GND")
	)
	(segment
		(start 195.31363 111.81332)
		(end 195.32127 111.82096)
		(width 0.2032)
		(layer "F.Cu")
		(net "GND")
	)
	(segment
		(start 169.82574 97.91825)
		(end 169.82592 97.91807)
		(width 0.2032)
		(layer "F.Cu")
		(net "GND")
	)
	(segment
		(start 85.37393 87.36837)
		(end 85.37393 87.36403)
		(width 0.254)
		(layer "F.Cu")
		(net "GND")
	)
	(segment
		(start 153.9261 79.7162)
		(end 153.9261 77.9669)
		(width 0.762)
		(layer "F.Cu")
		(net "GND")
	)
	(segment
		(start 210.6837 115.4188)
		(end 210.6837 114.5892)
		(width 0.254)
		(layer "F.Cu")
		(net "GND")
	)
	(segment
		(start 82.3761 87.5662)
		(end 82.42611 87.6162)
		(width 0.254)
		(layer "F.Cu")
		(net "GND")
	)
	(segment
		(start 201.9165 117.627)
		(end 201.9165 116.5492)
		(width 0.254)
		(layer "F.Cu")
		(net "GND")
	)
	(segment
		(start 89.3921 91.1162)
		(end 89.3921 90.40578)
		(width 0.2032)
		(layer "F.Cu")
		(net "GND")
	)
	(segment
		(start 167.32588 95.09939)
		(end 167.4001 95.17361)
		(width 0.2032)
		(layer "F.Cu")
		(net "GND")
	)
	(segment
		(start 80.3761 100.44103)
		(end 80.3761 99.5662)
		(width 0.2032)
		(layer "F.Cu")
		(net "GND")
	)
	(segment
		(start 174.8491 95.2016)
		(end 174.8491 93.89184)
		(width 0.2032)
		(layer "F.Cu")
		(net "GND")
	)
	(segment
		(start 222.02491 64.6162)
		(end 222.08731 64.6786)
		(width 0.254)
		(layer "F.Cu")
		(net "GND")
	)
	(segment
		(start 167.4001 95.2286)
		(end 167.4001 95.17361)
		(width 0.2032)
		(layer "F.Cu")
		(net "GND")
	)
	(segment
		(start 225.5761 136.4912)
		(end 225.59931 136.46799)
		(width 0.254)
		(layer "F.Cu")
		(net "GND")
	)
	(segment
		(start 196.61853 109.32103)
		(end 196.6261 109.3286)
		(width 0.2032)
		(layer "F.Cu")
		(net "GND")
	)
	(segment
		(start 193.1011 87.8036)
		(end 193.6011 87.8036)
		(width 0.2032)
		(layer "F.Cu")
		(net "GND")
	)
	(segment
		(start 84.6261 107.3662)
		(end 84.8761 107.6162)
		(width 0.2032)
		(layer "F.Cu")
		(net "GND")
	)
	(segment
		(start 84.8761 121.17119)
		(end 85.1261 120.92119)
		(width 0.2032)
		(layer "F.Cu")
		(net "GND")
	)
	(segment
		(start 74.3761 138.1162)
		(end 74.3761 137.0912)
		(width 0.2032)
		(layer "F.Cu")
		(net "GND")
	)
	(segment
		(start 167.49809 96.5116)
		(end 167.49809 96.45661)
		(width 0.2032)
		(layer "F.Cu")
		(net "GND")
	)
	(segment
		(start 198.12968 114.31702)
		(end 199.35982 114.31702)
		(width 0.2032)
		(layer "F.Cu")
		(net "GND")
	)
	(segment
		(start 150.2339 122.2924)
		(end 150.25041 122.30891)
		(width 0.254)
		(layer "F.Cu")
		(net "GND")
	)
	(segment
		(start 180.3261 134.18358)
		(end 180.4261 134.08359)
		(width 0.2032)
		(layer "F.Cu")
		(net "GND")
	)
	(segment
		(start 131.43222 154.87014)
		(end 131.43222 154.87014)
		(width 0.508)
		(layer "F.Cu")
		(net "GND")
	)
	(segment
		(start 150.35037 107.35152)
		(end 151.70796 107.35152)
		(width 0.254)
		(layer "F.Cu")
		(net "GND")
	)
	(segment
		(start 207.96146 81.8662)
		(end 208.04966 81.9544)
		(width 0.254)
		(layer "F.Cu")
		(net "GND")
	)
	(segment
		(start 94.5761 75.1286)
		(end 94.7761 75.3286)
		(width 0.2032)
		(layer "F.Cu")
		(net "GND")
	)
	(segment
		(start 177.0761 86.5786)
		(end 177.8761 86.5786)
		(width 0.2032)
		(layer "F.Cu")
		(net "GND")
	)
	(segment
		(start 84.6261 121.6162)
		(end 84.8761 121.3662)
		(width 0.2032)
		(layer "F.Cu")
		(net "GND")
	)
	(segment
		(start 207.7261 135.5162)
		(end 207.7261 133.0162)
		(width 0.762)
		(layer "F.Cu")
		(net "GND")
	)
	(segment
		(start 93.7781 75.80381)
		(end 93.7781 75.7766)
		(width 0.254)
		(layer "F.Cu")
		(net "GND")
	)
	(segment
		(start 195.31363 121.8133)
		(end 195.32128 121.82095)
		(width 0.2032)
		(layer "F.Cu")
		(net "GND")
	)
	(segment
		(start 89.3761 90.38978)
		(end 89.3921 90.40578)
		(width 0.2032)
		(layer "F.Cu")
		(net "GND")
	)
	(segment
		(start 175.9261 129.78359)
		(end 175.9261 129.7286)
		(width 0.2032)
		(layer "F.Cu")
		(net "GND")
	)
	(segment
		(start 81.3761 93.6162)
		(end 82.6261 94.8662)
		(width 0.254)
		(layer "F.Cu")
		(net "GND")
	)
	(segment
		(start 153.9261 77.9669)
		(end 154.0068 77.9669)
		(width 0.762)
		(layer "F.Cu")
		(net "GND")
	)
	(segment
		(start 131.6261 89.8742)
		(end 131.66498 89.83532)
		(width 0.2032)
		(layer "F.Cu")
		(net "GND")
	)
	(segment
		(start 150.50876 117.31242)
		(end 151.09274 117.31242)
		(width 0.254)
		(layer "F.Cu")
		(net "GND")
	)
	(segment
		(start 84.97111 83.0162)
		(end 85.07111 83.1162)
		(width 0.2032)
		(layer "F.Cu")
		(net "GND")
	)
	(segment
		(start 192.70976 138.72763)
		(end 193.98636 138.72763)
		(width 0.254)
		(layer "F.Cu")
		(net "GND")
	)
	(segment
		(start 175.82599 129.8837)
		(end 175.9261 129.78359)
		(width 0.2032)
		(layer "F.Cu")
		(net "GND")
	)
	(segment
		(start 150.25041 122.30891)
		(end 151.75053 122.30891)
		(width 0.254)
		(layer "F.Cu")
		(net "GND")
	)
	(segment
		(start 149.07439 122.30891)
		(end 149.0909 122.2924)
		(width 0.254)
		(layer "F.Cu")
		(net "GND")
	)
	(segment
		(start 213.4735 116.7362)
		(end 213.4885 116.7512)
		(width 0.254)
		(layer "F.Cu")
		(net "GND")
	)
	(segment
		(start 80.3761 126.5662)
		(end 80.4261 126.6162)
		(width 0.2032)
		(layer "F.Cu")
		(net "GND")
	)
	(segment
		(start 164.82575 96.67389)
		(end 165.0511 96.44854)
		(width 0.2032)
		(layer "F.Cu")
		(net "GND")
	)
	(segment
		(start 149.0655 119.8032)
		(end 149.0909 119.8286)
		(width 0.254)
		(layer "F.Cu")
		(net "GND")
	)
	(segment
		(start 131.66498 88.78972)
		(end 132.58611 87.8686)
		(width 0.2032)
		(layer "F.Cu")
		(net "GND")
	)
	(segment
		(start 174.32612 131.47882)
		(end 174.32612 129.72861)
		(width 0.2032)
		(layer "F.Cu")
		(net "GND")
	)
	(segment
		(start 210.9167 114.3562)
		(end 210.9885 114.3562)
		(width 0.254)
		(layer "F.Cu")
		(net "GND")
	)
	(segment
		(start 180.3261 131.47882)
		(end 180.3261 129.7286)
		(width 0.2032)
		(layer "F.Cu")
		(net "GND")
	)
	(segment
		(start 210.6837 114.5892)
		(end 210.9167 114.3562)
		(width 0.254)
		(layer "F.Cu")
		(net "GND")
	)
	(segment
		(start 194.8761 84.5786)
		(end 195.1511 84.8536)
		(width 0.2032)
		(layer "F.Cu")
		(net "GND")
	)
	(segment
		(start 170.4261 129.79356)
		(end 170.4261 129.73857)
		(width 0.2032)
		(layer "F.Cu")
		(net "GND")
	)
	(segment
		(start 125.1761 85.8286)
		(end 126.6261 85.8286)
		(width 0.2032)
		(layer "F.Cu")
		(net "GND")
	)
	(segment
		(start 107.54611 157.7576)
		(end 107.54611 154.34359)
		(width 0.508)
		(layer "F.Cu")
		(net "GND")
	)
	(segment
		(start 179.80941 93.88478)
		(end 179.82572 93.86847)
		(width 0.2032)
		(layer "F.Cu")
		(net "GND")
	)
	(segment
		(start 131.43222 156.98475)
		(end 131.52607 157.0786)
		(width 0.508)
		(layer "F.Cu")
		(net "GND")
	)
	(segment
		(start 193.1011 86.5036)
		(end 193.1745 86.4302)
		(width 0.2032)
		(layer "F.Cu")
		(net "GND")
	)
	(segment
		(start 172.32587 96.44182)
		(end 172.3841 96.38359)
		(width 0.2032)
		(layer "F.Cu")
		(net "GND")
	)
	(segment
		(start 167.826 134.28368)
		(end 167.9261 134.18359)
		(width 0.2032)
		(layer "F.Cu")
		(net "GND")
	)
	(segment
		(start 210.55741 107.6662)
		(end 210.63351 107.7423)
		(width 0.2032)
		(layer "F.Cu")
		(net "GND")
	)
	(segment
		(start 85.07111 83.1162)
		(end 85.1261 83.1162)
		(width 0.2032)
		(layer "F.Cu")
		(net "GND")
	)
	(segment
		(start 198.13374 106.82097)
		(end 199.35577 106.82097)
		(width 0.2032)
		(layer "F.Cu")
		(net "GND")
	)
	(segment
		(start 195.31363 119.31343)
		(end 195.337 119.3368)
		(width 0.2032)
		(layer "F.Cu")
		(net "GND")
	)
	(segment
		(start 169.82574 95.02326)
		(end 169.82574 93.86847)
		(width 0.2032)
		(layer "F.Cu")
		(net "GND")
	)
	(segment
		(start 177.3011 97.16189)
		(end 177.3011 96.4036)
		(width 0.2032)
		(layer "F.Cu")
		(net "GND")
	)
	(segment
		(start 131.66498 89.83532)
		(end 131.66498 88.78972)
		(width 0.2032)
		(layer "F.Cu")
		(net "GND")
	)
	(segment
		(start 164.8011 95.2036)
		(end 164.82575 95.17895)
		(width 0.2032)
		(layer "F.Cu")
		(net "GND")
	)
	(segment
		(start 151.71732 114.83567)
		(end 151.74069 114.8123)
		(width 0.2032)
		(layer "F.Cu")
		(net "GND")
	)
	(segment
		(start 164.82575 97.91825)
		(end 164.82575 96.67389)
		(width 0.2032)
		(layer "F.Cu")
		(net "GND")
	)
	(segment
		(start 212.0885 117.9662)
		(end 212.0885 116.7482)
		(width 0.254)
		(layer "F.Cu")
		(net "GND")
	)
	(segment
		(start 128.3761 86.0786)
		(end 129.1261 85.3286)
		(width 0.2032)
		(layer "F.Cu")
		(net "GND")
	)
	(segment
		(start 151.70796 107.35152)
		(end 151.75053 107.30894)
		(width 0.254)
		(layer "F.Cu")
		(net "GND")
	)
	(segment
		(start 178.3761 87.0786)
		(end 179.8761 87.0786)
		(width 0.2032)
		(layer "F.Cu")
		(net "GND")
	)
	(segment
		(start 199.9737 91.8096)
		(end 199.9737 90.2712)
		(width 0.254)
		(layer "F.Cu")
		(net "GND")
	)
	(segment
		(start 131.43222 154.87014)
		(end 131.43222 154.87014)
		(width 0.508)
		(layer "F.Cu")
		(net "GND")
	)
	(segment
		(start 177.4261 129.78359)
		(end 177.4261 129.7286)
		(width 0.2032)
		(layer "F.Cu")
		(net "GND")
	)
	(segment
		(start 150.22434 117.028)
		(end 150.50876 117.31242)
		(width 0.254)
		(layer "F.Cu")
		(net "GND")
	)
	(segment
		(start 217.8761 61.8662)
		(end 217.8761 60.5786)
		(width 0.254)
		(layer "F.Cu")
		(net "GND")
	)
	(segment
		(start 150.30451 119.80879)
		(end 151.75053 119.80879)
		(width 0.254)
		(layer "F.Cu")
		(net "GND")
	)
	(segment
		(start 195.32127 116.82096)
		(end 196.61846 116.82096)
		(width 0.2032)
		(layer "F.Cu")
		(net "GND")
	)
	(segment
		(start 92.64983 87.1162)
		(end 92.66568 87.13205)
		(width 0.2032)
		(layer "F.Cu")
		(net "GND")
	)
	(segment
		(start 82.6261 89.6162)
		(end 82.6261 88.8662)
		(width 0.254)
		(layer "F.Cu")
		(net "GND")
	)
	(segment
		(start 85.8761 80.0786)
		(end 85.8761 80.0786)
		(width 0.254)
		(layer "F.Cu")
		(net "GND")
	)
	(segment
		(start 230.39336 135.04894)
		(end 230.42252 135.01978)
		(width 0.254)
		(layer "F.Cu")
		(net "GND")
	)
	(segment
		(start 165.32613 134.28355)
		(end 165.4261 134.18359)
		(width 0.2032)
		(layer "F.Cu")
		(net "GND")
	)
	(segment
		(start 141.66107 114.44892)
		(end 142.78298 114.44892)
		(width 0.2032)
		(layer "F.Cu")
		(net "GND")
	)
	(segment
		(start 198.1261 121.8286)
		(end 198.13375 121.82095)
		(width 0.2032)
		(layer "F.Cu")
		(net "GND")
	)
	(segment
		(start 217.8861 132.7162)
		(end 219.5261 132.7162)
		(width 0.762)
		(layer "F.Cu")
		(net "GND")
	)
	(segment
		(start 172.34923 95.19373)
		(end 172.34923 93.89184)
		(width 0.2032)
		(layer "F.Cu")
		(net "GND")
	)
	(segment
		(start 151.54502 77.94847)
		(end 151.57167 77.94847)
		(width 0.762)
		(layer "F.Cu")
		(net "GND")
	)
	(segment
		(start 74.3761 97.6162)
		(end 74.3761 96.5912)
		(width 0.2032)
		(layer "F.Cu")
		(net "GND")
	)
	(segment
		(start 167.82605 129.72865)
		(end 167.8261 129.7286)
		(width 0.2032)
		(layer "F.Cu")
		(net "GND")
	)
	(segment
		(start 104.52961 157.74109)
		(end 104.54612 157.7576)
		(width 0.508)
		(layer "F.Cu")
		(net "GND")
	)
	(segment
		(start 74.3761 111.1162)
		(end 74.3761 110.0912)
		(width 0.2032)
		(layer "F.Cu")
		(net "GND")
	)
	(segment
		(start 148.74187 117.31039)
		(end 149.07013 116.98213)
		(width 0.254)
		(layer "F.Cu")
		(net "GND")
	)
	(segment
		(start 82.6261 94.8662)
		(end 83.7011 94.8662)
		(width 0.254)
		(layer "F.Cu")
		(net "GND")
	)
	(segment
		(start 85.8761 81.1162)
		(end 85.8761 80.0786)
		(width 0.254)
		(layer "F.Cu")
		(net "GND")
	)
	(segment
		(start 150.40663 114.83567)
		(end 151.71732 114.83567)
		(width 0.2032)
		(layer "F.Cu")
		(net "GND")
	)
	(segment
		(start 128.8761 87.3286)
		(end 129.7261 87.3286)
		(width 0.2032)
		(layer "F.Cu")
		(net "GND")
	)
	(segment
		(start 132.58611 87.8686)
		(end 134.1261 87.8686)
		(width 0.2032)
		(layer "F.Cu")
		(net "GND")
	)
	(segment
		(start 167.826 131.47882)
		(end 167.82605 131.47877)
		(width 0.2032)
		(layer "F.Cu")
		(net "GND")
	)
	(segment
		(start 174.32611 129.72861)
		(end 174.32612 129.72861)
		(width 0.2032)
		(layer "F.Cu")
		(net "GND")
	)
	(segment
		(start 179.80941 97.90194)
		(end 179.82572 97.91825)
		(width 0.2032)
		(layer "F.Cu")
		(net "GND")
	)
	(segment
		(start 195.337 119.3368)
		(end 196.28372 119.3368)
		(width 0.2032)
		(layer "F.Cu")
		(net "GND")
	)
	(segment
		(start 187.1261 89.8286)
		(end 187.1261 87.8411)
		(width 0.2032)
		(layer "F.Cu")
		(net "GND")
	)
	(segment
		(start 147.70076 119.80879)
		(end 147.70279 119.80676)
		(width 0.254)
		(layer "F.Cu")
		(net "GND")
	)
	(segment
		(start 175.3761 86.3286)
		(end 176.8261 86.3286)
		(width 0.2032)
		(layer "F.Cu")
		(net "GND")
	)
	(segment
		(start 186.6027 87.8177)
		(end 186.6261 87.8411)
		(width 0.2032)
		(layer "F.Cu")
		(net "GND")
	)
	(segment
		(start 195.31363 114.31344)
		(end 195.31721 114.31702)
		(width 0.2032)
		(layer "F.Cu")
		(net "GND")
	)
	(segment
		(start 198.1261 119.6242)
		(end 198.18109 119.6242)
		(width 0.2032)
		(layer "F.Cu")
		(net "GND")
	)
	(segment
		(start 82.68059 83.0162)
		(end 84.1261 83.0162)
		(width 0.2032)
		(layer "F.Cu")
		(net "GND")
	)
	(segment
		(start 130.1261 83.5286)
		(end 130.1261 82.0786)
		(width 0.2032)
		(layer "F.Cu")
		(net "GND")
	)
	(segment
		(start 177.32611 129.88358)
		(end 177.4261 129.78359)
		(width 0.2032)
		(layer "F.Cu")
		(net "GND")
	)
	(segment
		(start 192.53815 142.80442)
		(end 193.93815 142.80442)
		(width 0.254)
		(layer "F.Cu")
		(net "GND")
	)
	(segment
		(start 83.9511 108.3662)
		(end 84.6261 108.3662)
		(width 0.2032)
		(layer "F.Cu")
		(net "GND")
	)
	(segment
		(start 174.81742 97.90993)
		(end 174.81742 96.41192)
		(width 0.2032)
		(layer "F.Cu")
		(net "GND")
	)
	(segment
		(start 83.8761 107.3662)
		(end 84.6261 107.3662)
		(width 0.2032)
		(layer "F.Cu")
		(net "GND")
	)
	(segment
		(start 218.06876 58.67651)
		(end 218.06876 57.46478)
		(width 0.254)
		(layer "F.Cu")
		(net "GND")
	)
	(segment
		(start 131.43222 156.98475)
		(end 131.43222 154.87014)
		(width 0.508)
		(layer "F.Cu")
		(net "GND")
	)
	(segment
		(start 226.6261 71.3662)
		(end 226.6261 70.0786)
		(width 0.254)
		(layer "F.Cu")
		(net "GND")
	)
	(segment
		(start 198.1261 106.8286)
		(end 198.13374 106.82097)
		(width 0.2032)
		(layer "F.Cu")
		(net "GND")
	)
	(segment
		(start 148.42954 119.8032)
		(end 149.0655 119.8032)
		(width 0.254)
		(layer "F.Cu")
		(net "GND")
	)
	(segment
		(start 147.70076 112.30893)
		(end 147.70203 112.3102)
		(width 0.254)
		(layer "F.Cu")
		(net "GND")
	)
	(segment
		(start 169.82574 95.02326)
		(end 169.9761 95.17361)
		(width 0.2032)
		(layer "F.Cu")
		(net "GND")
	)
	(segment
		(start 80.3761 141.6162)
		(end 80.3761 140.3162)
		(width 0.2032)
		(layer "F.Cu")
		(net "GND")
	)
	(segment
		(start 192.41494 138.98121)
		(end 192.45618 138.98121)
		(width 0.254)
		(layer "F.Cu")
		(net "GND")
	)
	(segment
		(start 149.17929 109.80881)
		(end 149.1925 109.7956)
		(width 0.254)
		(layer "F.Cu")
		(net "GND")
	)
	(segment
		(start 177.32611 131.47882)
		(end 177.32611 129.88358)
		(width 0.2032)
		(layer "F.Cu")
		(net "GND")
	)
	(segment
		(start 183.3761 86.0786)
		(end 185.3636 86.0786)
		(width 0.2032)
		(layer "F.Cu")
		(net "GND")
	)
	(segment
		(start 179.80941 95.2121)
		(end 179.80941 93.88478)
		(width 0.2032)
		(layer "F.Cu")
		(net "GND")
	)
	(segment
		(start 84.9261 87.8162)
		(end 85.37393 87.36837)
		(width 0.254)
		(layer "F.Cu")
		(net "GND")
	)
	(segment
		(start 69.93108 129.1162)
		(end 70.03108 129.2162)
		(width 0.2032)
		(layer "F.Cu")
		(net "GND")
	)
	(segment
		(start 83.3261 87.8162)
		(end 84.1261 87.8162)
		(width 0.254)
		(layer "F.Cu")
		(net "GND")
	)
	(segment
		(start 170.32612 135.5286)
		(end 170.32612 134.38356)
		(width 0.2032)
		(layer "F.Cu")
		(net "GND")
	)
	(segment
		(start 147.71428 114.83567)
		(end 149.09557 114.83567)
		(width 0.2032)
		(layer "F.Cu")
		(net "GND")
	)
	(segment
		(start 167.32588 96.68381)
		(end 167.49809 96.5116)
		(width 0.2032)
		(layer "F.Cu")
		(net "GND")
	)
	(segment
		(start 196.62252 114.31702)
		(end 196.6261 114.3206)
		(width 0.2032)
		(layer "F.Cu")
		(net "GND")
	)
	(segment
		(start 167.9261 134.18359)
		(end 167.9261 134.1286)
		(width 0.2032)
		(layer "F.Cu")
		(net "GND")
	)
	(segment
		(start 124.22214 154.2818)
		(end 124.51973 154.57938)
		(width 0.508)
		(layer "F.Cu")
		(net "GND")
	)
	(segment
		(start 147.69091 114.8123)
		(end 147.71428 114.83567)
		(width 0.2032)
		(layer "F.Cu")
		(net "GND")
	)
	(segment
		(start 198.1261 116.8286)
		(end 198.13375 116.82096)
		(width 0.2032)
		(layer "F.Cu")
		(net "GND")
	)
	(segment
		(start 164.82575 95.17895)
		(end 164.82575 93.86847)
		(width 0.2032)
		(layer "F.Cu")
		(net "GND")
	)
	(segment
		(start 196.61846 116.82096)
		(end 196.6261 116.8286)
		(width 0.2032)
		(layer "F.Cu")
		(net "GND")
	)
	(segment
		(start 196.61845 121.82095)
		(end 196.6261 121.8286)
		(width 0.2032)
		(layer "F.Cu")
		(net "GND")
	)
	(segment
		(start 178.82598 131.47882)
		(end 178.82598 129.98371)
		(width 0.2032)
		(layer "F.Cu")
		(net "GND")
	)
	(segment
		(start 176.8261 86.3286)
		(end 177.0761 86.5786)
		(width 0.2032)
		(layer "F.Cu")
		(net "GND")
	)
	(segment
		(start 107.54611 154.34359)
		(end 107.5611 154.3286)
		(width 0.508)
		(layer "F.Cu")
		(net "GND")
	)
	(segment
		(start 193.5245 86.4302)
		(end 194.1261 85.8286)
		(width 0.2032)
		(layer "F.Cu")
		(net "GND")
	)
	(segment
		(start 194.8761 84.5786)
		(end 194.8761 81.5866)
		(width 0.2032)
		(layer "F.Cu")
		(net "GND")
	)
	(segment
		(start 104.52961 157.74109)
		(end 104.52961 154.36162)
		(width 0.508)
		(layer "F.Cu")
		(net "GND")
	)
	(segment
		(start 80.3761 100.44103)
		(end 80.54375 100.60868)
		(width 0.2032)
		(layer "F.Cu")
		(net "GND")
	)
	(segment
		(start 196.28372 119.3368)
		(end 196.57112 119.6242)
		(width 0.2032)
		(layer "F.Cu")
		(net "GND")
	)
	(segment
		(start 194.1261 85.8286)
		(end 195.1261 85.8286)
		(width 0.2032)
		(layer "F.Cu")
		(net "GND")
	)
	(segment
		(start 195.3212 109.32103)
		(end 196.61853 109.32103)
		(width 0.2032)
		(layer "F.Cu")
		(net "GND")
	)
	(segment
		(start 83.7011 135.3662)
		(end 84.3761 135.3662)
		(width 0.2032)
		(layer "F.Cu")
		(net "GND")
	)
	(segment
		(start 84.3761 135.3662)
		(end 84.8761 134.8662)
		(width 0.2032)
		(layer "F.Cu")
		(net "GND")
	)
	(segment
		(start 81.3761 93.6162)
		(end 81.3761 92.6162)
		(width 0.254)
		(layer "F.Cu")
		(net "GND")
	)
	(segment
		(start 180.1261 86.8286)
		(end 180.1261 86.01239)
		(width 0.2032)
		(layer "F.Cu")
		(net "GND")
	)
	(segment
		(start 118.54609 155.05901)
		(end 118.54609 155.05901)
		(width 0.508)
		(layer "F.Cu")
		(net "GND")
	)
	(segment
		(start 193.93815 142.80442)
		(end 193.96136 142.82763)
		(width 0.254)
		(layer "F.Cu")
		(net "GND")
	)
	(segment
		(start 196.61847 106.82097)
		(end 196.6261 106.8286)
		(width 0.2032)
		(layer "F.Cu")
		(net "GND")
	)
	(segment
		(start 115.50423 157.71574)
		(end 115.50423 154.55673)
		(width 0.508)
		(layer "F.Cu")
		(net "GND")
	)
	(segment
		(start 125.1261 85.7786)
		(end 125.1761 85.8286)
		(width 0.2032)
		(layer "F.Cu")
		(net "GND")
	)
	(segment
		(start 199.35577 106.82097)
		(end 199.3634 106.81333)
		(width 0.2032)
		(layer "F.Cu")
		(net "GND")
	)
	(segment
		(start 85.37393 87.36403)
		(end 85.62176 87.1162)
		(width 0.254)
		(layer "F.Cu")
		(net "GND")
	)
	(segment
		(start 83.9511 121.6162)
		(end 84.6261 121.6162)
		(width 0.2032)
		(layer "F.Cu")
		(net "GND")
	)
	(segment
		(start 201.9165 116.5492)
		(end 202.1595 116.3062)
		(width 0.254)
		(layer "F.Cu")
		(net "GND")
	)
	(segment
		(start 165.32613 131.47882)
		(end 165.32613 129.72863)
		(width 0.2032)
		(layer "F.Cu")
		(net "GND")
	)
	(segment
		(start 91.7011 87.1162)
		(end 92.64983 87.1162)
		(width 0.2032)
		(layer "F.Cu")
		(net "GND")
	)
	(segment
		(start 217.8861 135.5162)
		(end 217.8861 132.7162)
		(width 0.762)
		(layer "F.Cu")
		(net "GND")
	)
	(segment
		(start 177.32586 93.86847)
		(end 177.34922 93.89184)
		(width 0.2032)
		(layer "F.Cu")
		(net "GND")
	)
	(segment
		(start 222.2637 88.7662)
		(end 223.7637 88.7662)
		(width 0.508)
		(layer "F.Cu")
		(net "GND")
	)
	(segment
		(start 208.04966 81.9544)
		(end 208.0909 81.9544)
		(width 0.254)
		(layer "F.Cu")
		(net "GND")
	)
	(segment
		(start 216.2675 117.0062)
		(end 216.2885 117.0272)
		(width 0.2032)
		(layer "F.Cu")
		(net "GND")
	)
	(segment
		(start 74.3761 93.6412)
		(end 74.3761 92.6162)
		(width 0.2032)
		(layer "F.Cu")
		(net "GND")
	)
	(segment
		(start 192.51494 142.78121)
		(end 192.53815 142.80442)
		(width 0.254)
		(layer "F.Cu")
		(net "GND")
	)
	(segment
		(start 221.0935 117.0792)
		(end 222.3237 117.0792)
		(width 0.254)
		(layer "F.Cu")
		(net "GND")
	)
	(segment
		(start 118.54609 155.05901)
		(end 118.54609 155.05901)
		(width 0.508)
		(layer "F.Cu")
		(net "GND")
	)
	(segment
		(start 172.83584 134.15826)
		(end 172.8907 134.1034)
		(width 0.254)
		(layer "F.Cu")
		(net "GND")
	)
	(segment
		(start 122.8745 154.3036)
		(end 123.2285 154.3036)
		(width 0.508)
		(layer "F.Cu")
		(net "GND")
	)
	(segment
		(start 80.6261 127.6162)
		(end 80.6261 126.5662)
		(width 0.2032)
		(layer "F.Cu")
		(net "GND")
	)
	(segment
		(start 199.35575 121.82095)
		(end 199.3634 121.8133)
		(width 0.2032)
		(layer "F.Cu")
		(net "GND")
	)
	(segment
		(start 180.4261 134.08359)
		(end 180.4261 134.0286)
		(width 0.2032)
		(layer "F.Cu")
		(net "GND")
	)
	(segment
		(start 170.5261 134.18359)
		(end 170.5261 134.1286)
		(width 0.2032)
		(layer "F.Cu")
		(net "GND")
	)
	(segment
		(start 180.3261 135.5286)
		(end 180.3261 134.18358)
		(width 0.2032)
		(layer "F.Cu")
		(net "GND")
	)
	(segment
		(start 122.28112 87.9836)
		(end 122.6261 88.32858)
		(width 0.2032)
		(layer "F.Cu")
		(net "GND")
	)
	(segment
		(start 198.1261 111.8286)
		(end 198.13374 111.82096)
		(width 0.2032)
		(layer "F.Cu")
		(net "GND")
	)
	(segment
		(start 150.3761 114.8662)
		(end 150.40663 114.83567)
		(width 0.2032)
		(layer "F.Cu")
		(net "GND")
	)
	(segment
		(start 74.3761 124.3662)
		(end 74.3761 123.3412)
		(width 0.2032)
		(layer "F.Cu")
		(net "GND")
	)
	(segment
		(start 150.28597 112.30893)
		(end 151.75053 112.30893)
		(width 0.254)
		(layer "F.Cu")
		(net "GND")
	)
	(segment
		(start 86.3761 67.8286)
		(end 88.3761 67.8286)
		(width 0.2032)
		(layer "F.Cu")
		(net "GND")
	)
	(segment
		(start 198.13375 116.82096)
		(end 199.35576 116.82096)
		(width 0.2032)
		(layer "F.Cu")
		(net "GND")
	)
	(segment
		(start 136.38538 114.95692)
		(end 137.66107 114.95692)
		(width 0.2032)
		(layer "F.Cu")
		(net "GND")
	)
	(segment
		(start 198.1261 114.3206)
		(end 198.12968 114.31702)
		(width 0.2032)
		(layer "F.Cu")
		(net "GND")
	)
	(segment
		(start 222.08731 64.6786)
		(end 223.6261 64.6786)
		(width 0.254)
		(layer "F.Cu")
		(net "GND")
	)
	(segment
		(start 69.8761 129.1162)
		(end 69.93108 129.1162)
		(width 0.2032)
		(layer "F.Cu")
		(net "GND")
	)
	(segment
		(start 177.30249 97.89488)
		(end 177.30249 97.16327)
		(width 0.2032)
		(layer "F.Cu")
		(net "GND")
	)
	(segment
		(start 82.3761 88.6162)
		(end 82.6261 88.8662)
		(width 0.254)
		(layer "F.Cu")
		(net "GND")
	)
	(segment
		(start 177.8761 86.5786)
		(end 178.3761 87.0786)
		(width 0.2032)
		(layer "F.Cu")
		(net "GND")
	)
	(segment
		(start 198.1261 109.3286)
		(end 198.13368 109.32103)
		(width 0.2032)
		(layer "F.Cu")
		(net "GND")
	)
	(segment
		(start 209.4095 116.8762)
		(end 209.4095 115.2902)
		(width 0.254)
		(layer "F.Cu")
		(net "GND")
	)
	(segment
		(start 186.6027 87.8177)
		(end 186.6027 87.42415)
		(width 0.2032)
		(layer "F.Cu")
		(net "GND")
	)
	(segment
		(start 177.34922 95.20172)
		(end 177.3761 95.2286)
		(width 0.2032)
		(layer "F.Cu")
		(net "GND")
	)
	(segment
		(start 230.3261 136.5162)
		(end 230.39336 136.44894)
		(width 0.254)
		(layer "F.Cu")
		(net "GND")
	)
	(segment
		(start 134.5511 157.75256)
		(end 134.5511 154.1786)
		(width 0.508)
		(layer "F.Cu")
		(net "GND")
	)
	(segment
		(start 174.81742 97.90993)
		(end 174.82573 97.91825)
		(width 0.2032)
		(layer "F.Cu")
		(net "GND")
	)
	(segment
		(start 172.83584 135.50523)
		(end 172.83584 134.15826)
		(width 0.254)
		(layer "F.Cu")
		(net "GND")
	)
	(segment
		(start 203.9485 110.0452)
		(end 203.9739 110.0198)
		(width 0.254)
		(layer "F.Cu")
		(net "GND")
	)
	(segment
		(start 126.9761 154.1786)
		(end 127.44472 154.64722)
		(width 0.508)
		(layer "F.Cu")
		(net "GND")
	)
	(segment
		(start 221.3681 64.6162)
		(end 222.02491 64.6162)
		(width 0.254)
		(layer "F.Cu")
		(net "GND")
	)
	(segment
		(start 167.826 135.5286)
		(end 167.826 134.28368)
		(width 0.2032)
		(layer "F.Cu")
		(net "GND")
	)
	(segment
		(start 85.1261 120.92119)
		(end 85.1261 120.8662)
		(width 0.2032)
		(layer "F.Cu")
		(net "GND")
	)
	(segment
		(start 218.344 118.13612)
		(end 218.344 117.1237)
		(width 0.254)
		(layer "F.Cu")
		(net "GND")
	)
	(segment
		(start 82.39059 83.3062)
		(end 82.68059 83.0162)
		(width 0.2032)
		(layer "F.Cu")
		(net "GND")
	)
	(segment
		(start 148.42598 119.80676)
		(end 148.42954 119.8032)
		(width 0.254)
		(layer "F.Cu")
		(net "GND")
	)
	(segment
		(start 74.3761 120.3912)
		(end 74.3761 119.3662)
		(width 0.2032)
		(layer "F.Cu")
		(net "GND")
	)
	(segment
		(start 122.8527 154.2818)
		(end 124.22214 154.2818)
		(width 0.508)
		(layer "F.Cu")
		(net "GND")
	)
	(segment
		(start 122.6261 89.0866)
		(end 122.6261 88.32858)
		(width 0.2032)
		(layer "F.Cu")
		(net "GND")
	)
	(segment
		(start 175.82599 131.47882)
		(end 175.82599 129.8837)
		(width 0.2032)
		(layer "F.Cu")
		(net "GND")
	)
	(segment
		(start 225.59931 135.04299)
		(end 225.62252 135.01978)
		(width 0.254)
		(layer "F.Cu")
		(net "GND")
	)
	(segment
		(start 89.3761 90.38978)
		(end 89.3761 89.4412)
		(width 0.2032)
		(layer "F.Cu")
		(net "GND")
	)
	(segment
		(start 147.70203 112.3102)
		(end 149.0909 112.3102)
		(width 0.254)
		(layer "F.Cu")
		(net "GND")
	)
	(segment
		(start 169.82592 96.40378)
		(end 169.8261 96.4036)
		(width 0.2032)
		(layer "F.Cu")
		(net "GND")
	)
	(segment
		(start 84.8761 121.3662)
		(end 84.8761 121.17119)
		(width 0.2032)
		(layer "F.Cu")
		(net "GND")
	)
	(segment
		(start 134.54606 157.7576)
		(end 134.5511 157.75256)
		(width 0.508)
		(layer "F.Cu")
		(net "GND")
	)
	(segment
		(start 185.3636 87.0786)
		(end 186.25715 87.0786)
		(width 0.2032)
		(layer "F.Cu")
		(net "GND")
	)
	(segment
		(start 150.3609 109.821)
		(end 150.37309 109.80881)
		(width 0.254)
		(layer "F.Cu")
		(net "GND")
	)
	(segment
		(start 129.1261 85.3286)
		(end 129.7261 85.3286)
		(width 0.2032)
		(layer "F.Cu")
		(net "GND")
	)
	(segment
		(start 118.54609 157.7576)
		(end 118.54609 155.05901)
		(width 0.508)
		(layer "F.Cu")
		(net "GND")
	)
	(segment
		(start 178.82598 129.98371)
		(end 179.0261 129.78359)
		(width 0.2032)
		(layer "F.Cu")
		(net "GND")
	)
	(segment
		(start 169.82592 97.91807)
		(end 169.82592 96.40378)
		(width 0.2032)
		(layer "F.Cu")
		(net "GND")
	)
	(segment
		(start 127.44472 156.99725)
		(end 127.52607 157.0786)
		(width 0.508)
		(layer "F.Cu")
		(net "GND")
	)
	(segment
		(start 186.8761 90.0786)
		(end 188.6261 90.0786)
		(width 0.2032)
		(layer "F.Cu")
		(net "GND")
	)
	(segment
		(start 126.99598 154.1786)
		(end 127.9511 154.1786)
		(width 0.508)
		(layer "F.Cu")
		(net "GND")
	)
	(segment
		(start 226.8761 67.8286)
		(end 226.8761 67.8286)
		(width 0.254)
		(layer "F.Cu")
		(net "GND")
	)
	(segment
		(start 201.5087 84.1372)
		(end 201.5087 83.0068)
		(width 0.254)
		(layer "F.Cu")
		(net "GND")
	)
	(segment
		(start 198.46849 119.3368)
		(end 199.34004 119.3368)
		(width 0.2032)
		(layer "F.Cu")
		(net "GND")
	)
	(segment
		(start 186.25715 87.0786)
		(end 186.6027 87.42415)
		(width 0.2032)
		(layer "F.Cu")
		(net "GND")
	)
	(segment
		(start 147.70076 107.30894)
		(end 149.16456 107.30894)
		(width 0.254)
		(layer "F.Cu")
		(net "GND")
	)
	(segment
		(start 203.9739 110.0198)
		(end 203.9739 109.1901)
		(width 0.254)
		(layer "F.Cu")
		(net "GND")
	)
	(segment
		(start 165.4261 134.18359)
		(end 165.4261 134.1286)
		(width 0.2032)
		(layer "F.Cu")
		(net "GND")
	)
	(segment
		(start 172.3841 96.38359)
		(end 172.3841 96.3286)
		(width 0.2032)
		(layer "F.Cu")
		(net "GND")
	)
	(segment
		(start 80.5761 112.8662)
		(end 80.6261 112.8162)
		(width 0.2032)
		(layer "F.Cu")
		(net "GND")
	)
	(segment
		(start 70.03108 129.2162)
		(end 71.1261 129.2162)
		(width 0.2032)
		(layer "F.Cu")
		(net "GND")
	)
	(segment
		(start 124.51973 155.99134)
		(end 124.54608 156.0177)
		(width 0.508)
		(layer "F.Cu")
		(net "GND")
	)
	(segment
		(start 122.8527 154.2818)
		(end 122.8745 154.3036)
		(width 0.508)
		(layer "F.Cu")
		(net "GND")
	)
	(segment
		(start 193.1745 86.4302)
		(end 193.5245 86.4302)
		(width 0.2032)
		(layer "F.Cu")
		(net "GND")
	)
	(segment
		(start 85.62176 87.1162)
		(end 87.0511 87.1162)
		(width 0.254)
		(layer "F.Cu")
		(net "GND")
	)
	(segment
		(start 206.0261 133.0162)
		(end 207.7261 133.0162)
		(width 0.762)
		(layer "F.Cu")
		(net "GND")
	)
	(segment
		(start 82.3761 88.6162)
		(end 82.3761 87.5662)
		(width 0.254)
		(layer "F.Cu")
		(net "GND")
	)
	(segment
		(start 199.35576 111.82096)
		(end 199.3634 111.81332)
		(width 0.2032)
		(layer "F.Cu")
		(net "GND")
	)
	(segment
		(start 89.3761 84.7912)
		(end 89.3761 83.1162)
		(width 0.2032)
		(layer "F.Cu")
		(net "GND")
	)
	(segment
		(start 149.09557 114.83567)
		(end 149.1261 114.8662)
		(width 0.2032)
		(layer "F.Cu")
		(net "GND")
	)
	(segment
		(start 199.35982 114.31702)
		(end 199.3634 114.31344)
		(width 0.2032)
		(layer "F.Cu")
		(net "GND")
	)
	(segment
		(start 83.1261 87.6162)
		(end 83.3261 87.8162)
		(width 0.254)
		(layer "F.Cu")
		(net "GND")
	)
	(segment
		(start 179.0261 129.78359)
		(end 179.0261 129.7286)
		(width 0.2032)
		(layer "F.Cu")
		(net "GND")
	)
	(segment
		(start 126.9761 154.1786)
		(end 126.99598 154.1786)
		(width 0.508)
		(layer "F.Cu")
		(net "GND")
	)
	(segment
		(start 84.1261 87.8162)
		(end 84.9261 87.8162)
		(width 0.254)
		(layer "F.Cu")
		(net "GND")
	)
	(segment
		(start 218.06876 57.46478)
		(end 218.1261 57.40744)
		(width 0.254)
		(layer "F.Cu")
		(net "GND")
	)
	(segment
		(start 120.53059 154.37508)
		(end 120.54609 154.35959)
		(width 0.508)
		(layer "F.Cu")
		(net "GND")
	)
	(segment
		(start 120.9761 87.9836)
		(end 122.28112 87.9836)
		(width 0.2032)
		(layer "F.Cu")
		(net "GND")
	)
	(segment
		(start 115.50423 157.71574)
		(end 115.5461 157.7576)
		(width 0.508)
		(layer "F.Cu")
		(net "GND")
	)
	(segment
		(start 165.32613 135.5286)
		(end 165.32613 134.28355)
		(width 0.2032)
		(layer "F.Cu")
		(net "GND")
	)
	(segment
		(start 213.4885 117.9662)
		(end 213.4885 116.7512)
		(width 0.254)
		(layer "F.Cu")
		(net "GND")
	)
	(segment
		(start 84.8761 108.1162)
		(end 84.8761 107.6162)
		(width 0.2032)
		(layer "F.Cu")
		(net "GND")
	)
	(segment
		(start 183.3761 87.0786)
		(end 185.3636 87.0786)
		(width 0.2032)
		(layer "F.Cu")
		(net "GND")
	)
	(segment
		(start 218.1261 57.40744)
		(end 218.1261 57.3662)
		(width 0.254)
		(layer "F.Cu")
		(net "GND")
	)
	(segment
		(start 92.66568 87.13205)
		(end 93.3761 87.13205)
		(width 0.2032)
		(layer "F.Cu")
		(net "GND")
	)
	(segment
		(start 174.82573 93.86847)
		(end 174.8491 93.89184)
		(width 0.2032)
		(layer "F.Cu")
		(net "GND")
	)
	(segment
		(start 195.31363 109.31345)
		(end 195.3212 109.32103)
		(width 0.2032)
		(layer "F.Cu")
		(net "GND")
	)
	(segment
		(start 136.3261 115.0162)
		(end 136.38538 114.95692)
		(width 0.2032)
		(layer "F.Cu")
		(net "GND")
	)
	(segment
		(start 74.3761 107.1412)
		(end 74.3761 106.1162)
		(width 0.2032)
		(layer "F.Cu")
		(net "GND")
	)
	(segment
		(start 169.9761 95.2286)
		(end 169.9761 95.17361)
		(width 0.2032)
		(layer "F.Cu")
		(net "GND")
	)
	(segment
		(start 124.51973 157.07224)
		(end 124.52608 157.0786)
		(width 0.508)
		(layer "F.Cu")
		(net "GND")
	)
	(segment
		(start 170.32612 129.89354)
		(end 170.4261 129.79356)
		(width 0.2032)
		(layer "F.Cu")
		(net "GND")
	)
	(segment
		(start 222.2637 90.9662)
		(end 223.7637 90.9662)
		(width 0.508)
		(layer "F.Cu")
		(net "GND")
	)
	(segment
		(start 167.82605 131.47877)
		(end 167.82605 129.72865)
		(width 0.2032)
		(layer "F.Cu")
		(net "GND")
	)
	(segment
		(start 88.1261 80.02861)
		(end 88.1261 80.0286)
		(width 0.254)
		(layer "F.Cu")
		(net "GND")
	)
	(segment
		(start 192.45618 138.98121)
		(end 192.70976 138.72763)
		(width 0.254)
		(layer "F.Cu")
		(net "GND")
	)
	(segment
		(start 172.82599 129.86995)
		(end 172.9261 129.76984)
		(width 0.254)
		(layer "F.Cu")
		(net "GND")
	)
	(segment
		(start 150.1831 117.028)
		(end 150.22434 117.028)
		(width 0.254)
		(layer "F.Cu")
		(net "GND")
	)
	(segment
		(start 190.1261 90.0786)
		(end 191.6261 90.0786)
		(width 0.2032)
		(layer "F.Cu")
		(net "GND")
	)
	(segment
		(start 196.61846 111.82096)
		(end 196.6261 111.8286)
		(width 0.2032)
		(layer "F.Cu")
		(net "GND")
	)
	(segment
		(start 150.2847 119.8286)
		(end 150.30451 119.80879)
		(width 0.254)
		(layer "F.Cu")
		(net "GND")
	)
	(segment
		(start 199.9737 91.8096)
		(end 199.9847 91.8206)
		(width 0.254)
		(layer "F.Cu")
		(net "GND")
	)
	(segment
		(start 167.32588 95.09939)
		(end 167.32588 93.86847)
		(width 0.2032)
		(layer "F.Cu")
		(net "GND")
	)
	(segment
		(start 207.0537 81.8662)
		(end 207.96146 81.8662)
		(width 0.254)
		(layer "F.Cu")
		(net "GND")
	)
	(segment
		(start 84.6261 108.3662)
		(end 84.8761 108.1162)
		(width 0.2032)
		(layer "F.Cu")
		(net "GND")
	)
	(segment
		(start 170.32612 134.38356)
		(end 170.5261 134.18359)
		(width 0.2032)
		(layer "F.Cu")
		(net "GND")
	)
	(segment
		(start 179.80941 97.90194)
		(end 179.80941 96.41016)
		(width 0.2032)
		(layer "F.Cu")
		(net "GND")
	)
	(segment
		(start 170.32612 131.47882)
		(end 170.32612 129.89354)
		(width 0.2032)
		(layer "F.Cu")
		(net "GND")
	)
	(segment
		(start 167.32588 97.91825)
		(end 167.32588 96.68381)
		(width 0.2032)
		(layer "F.Cu")
		(net "GND")
	)
	(segment
		(start 130.1261 83.5286)
		(end 130.1761 83.5786)
		(width 0.2032)
		(layer "F.Cu")
		(net "GND")
	)
	(segment
		(start 214.6885 117.0612)
		(end 214.7435 117.0062)
		(width 0.2032)
		(layer "F.Cu")
		(net "GND")
	)
	(segment
		(start 218.2995 117.0792)
		(end 218.344 117.1237)
		(width 0.254)
		(layer "F.Cu")
		(net "GND")
	)
	(segment
		(start 174.8491 95.2016)
		(end 174.8761 95.2286)
		(width 0.2032)
		(layer "F.Cu")
		(net "GND")
	)
	(segment
		(start 84.1261 83.0162)
		(end 84.97111 83.0162)
		(width 0.2032)
		(layer "F.Cu")
		(net "GND")
	)
	(segment
		(start 199.35576 116.82096)
		(end 199.3634 116.81331)
		(width 0.2032)
		(layer "F.Cu")
		(net "GND")
	)
	(segment
		(start 172.32587 97.91825)
		(end 172.32587 96.44182)
		(width 0.2032)
		(layer "F.Cu")
		(net "GND")
	)
	(segment
		(start 199.35583 109.32103)
		(end 199.3634 109.31345)
		(width 0.2032)
		(layer "F.Cu")
		(net "GND")
	)
	(segment
		(start 222.3237 117.0792)
		(end 222.3381 117.0936)
		(width 0.254)
		(layer "F.Cu")
		(net "GND")
	)
	(segment
		(start 214.6885 117.9662)
		(end 214.6885 117.0612)
		(width 0.2032)
		(layer "F.Cu")
		(net "GND")
	)
	(segment
		(start 114.5461 154.3286)
		(end 115.2761 154.3286)
		(width 0.508)
		(layer "F.Cu")
		(net "GND")
	)
	(segment
		(start 179.7931 95.22841)
		(end 179.80941 95.2121)
		(width 0.2032)
		(layer "F.Cu")
		(net "GND")
	)
	(segment
		(start 149.07013 116.98213)
		(end 149.11137 116.98213)
		(width 0.254)
		(layer "F.Cu")
		(net "GND")
	)
	(segment
		(start 195.31363 116.81331)
		(end 195.32127 116.82096)
		(width 0.2032)
		(layer "F.Cu")
		(net "GND")
	)
	(segment
		(start 88.1261 81.1162)
		(end 88.1261 80.02861)
		(width 0.254)
		(layer "F.Cu")
		(net "GND")
	)
	(segment
		(start 195.32126 106.82097)
		(end 196.61847 106.82097)
		(width 0.2032)
		(layer "F.Cu")
		(net "GND")
	)
	(segment
		(start 142.78298 114.44892)
		(end 143.16077 114.8267)
		(width 0.2032)
		(layer "F.Cu")
		(net "GND")
	)
	(segment
		(start 195.31721 114.31702)
		(end 196.62252 114.31702)
		(width 0.2032)
		(layer "F.Cu")
		(net "GND")
	)
	(segment
		(start 94.7761 75.3286)
		(end 96.1261 75.3286)
		(width 0.2032)
		(layer "F.Cu")
		(net "GND")
	)
	(segment
		(start 165.0511 96.44854)
		(end 165.0511 96.39356)
		(width 0.2032)
		(layer "F.Cu")
		(net "GND")
	)
	(segment
		(start 193.6011 87.8036)
		(end 195.1261 89.3286)
		(width 0.2032)
		(layer "F.Cu")
		(net "GND")
	)
	(segment
		(start 199.34004 119.3368)
		(end 199.3634 119.31343)
		(width 0.2032)
		(layer "F.Cu")
		(net "GND")
	)
	(via
		(at 65.7781 137.3106)
		(size 0.4064)
		(drill 0.2032)
		(layers "F.Cu" "B.Cu")
		(tenting
			(front yes)
			(back yes)
		)
		(net "GND")
	)
	(via
		(at 71.8741 131.2146)
		(size 0.4064)
		(drill 0.2032)
		(layers "F.Cu" "B.Cu")
		(tenting
			(front yes)
			(back yes)
		)
		(net "GND")
	)
	(via
		(at 74.3761 92.6162)
		(size 0.4064)
		(drill 0.2032)
		(layers "F.Cu" "B.Cu")
		(tenting
			(front yes)
			(back yes)
		)
		(net "GND")
	)
	(via
		(at 60.1901 126.1346)
		(size 0.4064)
		(drill 0.2032)
		(layers "F.Cu" "B.Cu")
		(tenting
			(front yes)
			(back yes)
		)
		(net "GND")
	)
	(via
		(at 76.9541 129.1826)
		(size 0.4064)
		(drill 0.2032)
		(layers "F.Cu" "B.Cu")
		(tenting
			(front yes)
			(back yes)
		)
		(net "GND")
	)
	(via
		(at 66.7941 125.1186)
		(size 0.4064)
		(drill 0.2032)
		(layers "F.Cu" "B.Cu")
		(tenting
			(front yes)
			(back yes)
		)
		(net "GND")
	)
	(via
		(at 73.3981 144.4226)
		(size 0.4064)
		(drill 0.2032)
		(layers "F.Cu" "B.Cu")
		(tenting
			(front yes)
			(back yes)
		)
		(net "GND")
	)
	(via
		(at 61.7141 116.9906)
		(size 0.4064)
		(drill 0.2032)
		(layers "F.Cu" "B.Cu")
		(tenting
			(front yes)
			(back yes)
		)
		(net "GND")
	)
	(via
		(at 56.6341 121.0546)
		(size 0.4064)
		(drill 0.2032)
		(layers "F.Cu" "B.Cu")
		(tenting
			(front yes)
			(back yes)
		)
		(net "GND")
	)
	(via
		(at 69.8421 141.3746)
		(size 0.4064)
		(drill 0.2032)
		(layers "F.Cu" "B.Cu")
		(tenting
			(front yes)
			(back yes)
		)
		(net "GND")
	)
	(via
		(at 212.2261 92.2162)
		(size 0.4064)
		(drill 0.2032)
		(layers "F.Cu" "B.Cu")
		(tenting
			(front yes)
			(back yes)
		)
		(net "GND")
	)
	(via
		(at 66.7941 121.0546)
		(size 0.4064)
		(drill 0.2032)
		(layers "F.Cu" "B.Cu")
		(tenting
			(front yes)
			(back yes)
		)
		(net "GND")
	)
	(via
		(at 89.3921 91.1162)
		(size 0.4064)
		(drill 0.2032)
		(layers "F.Cu" "B.Cu")
		(tenting
			(front yes)
			(back yes)
		)
		(net "GND")
	)
	(via
		(at 77.4621 103.7826)
		(size 0.4064)
		(drill 0.2032)
		(layers "F.Cu" "B.Cu")
		(tenting
			(front yes)
			(back yes)
		)
		(net "GND")
	)
	(via
		(at 77.4621 120.0386)
		(size 0.4064)
		(drill 0.2032)
		(layers "F.Cu" "B.Cu")
		(tenting
			(front yes)
			(back yes)
		)
		(net "GND")
	)
	(via
		(at 57.6501 108.8626)
		(size 0.4064)
		(drill 0.2032)
		(layers "F.Cu" "B.Cu")
		(tenting
			(front yes)
			(back yes)
		)
		(net "GND")
	)
	(via
		(at 154.0068 77.9669)
		(size 1.27)
		(drill 0.7112)
		(layers "F.Cu" "B.Cu")
		(net "GND")
	)
	(via
		(at 75.4301 144.4226)
		(size 0.4064)
		(drill 0.2032)
		(layers "F.Cu" "B.Cu")
		(tenting
			(front yes)
			(back yes)
		)
		(net "GND")
	)
	(via
		(at 65.7781 119.0226)
		(size 0.4064)
		(drill 0.2032)
		(layers "F.Cu" "B.Cu")
		(tenting
			(front yes)
			(back yes)
		)
		(net "GND")
	)
	(via
		(at 61.7141 131.2146)
		(size 0.4064)
		(drill 0.2032)
		(layers "F.Cu" "B.Cu")
		(tenting
			(front yes)
			(back yes)
		)
		(net "GND")
	)
	(via
		(at 67.3021 97.6866)
		(size 0.4064)
		(drill 0.2032)
		(layers "F.Cu" "B.Cu")
		(tenting
			(front yes)
			(back yes)
		)
		(net "GND")
	)
	(via
		(at 74.3761 106.1162)
		(size 0.4064)
		(drill 0.2032)
		(layers "F.Cu" "B.Cu")
		(tenting
			(front yes)
			(back yes)
		)
		(net "GND")
	)
	(via
		(at 120.54609 154.35959)
		(size 0.4064)
		(drill 0.2032)
		(layers "F.Cu" "B.Cu")
		(tenting
			(front yes)
			(back yes)
		)
		(net "GND")
	)
	(via
		(at 149.0909 122.2924)
		(size 0.4064)
		(drill 0.2032)
		(layers "F.Cu" "B.Cu")
		(tenting
			(front yes)
			(back yes)
		)
		(net "GND")
	)
	(via
		(at 75.4301 91.5906)
		(size 0.4064)
		(drill 0.2032)
		(layers "F.Cu" "B.Cu")
		(tenting
			(front yes)
			(back yes)
		)
		(net "GND")
	)
	(via
		(at 67.3021 120.0386)
		(size 0.4064)
		(drill 0.2032)
		(layers "F.Cu" "B.Cu")
		(tenting
			(front yes)
			(back yes)
		)
		(net "GND")
	)
	(via
		(at 74.4141 91.5906)
		(size 0.4064)
		(drill 0.2032)
		(layers "F.Cu" "B.Cu")
		(tenting
			(front yes)
			(back yes)
		)
		(net "GND")
	)
	(via
		(at 201.9165 117.627)
		(size 0.4064)
		(drill 0.2032)
		(layers "F.Cu" "B.Cu")
		(tenting
			(front yes)
			(back yes)
		)
		(net "GND")
	)
	(via
		(at 88.2761 88.2162)
		(size 0.5)
		(drill 0.2)
		(layers "F.Cu" "B.Cu")
		(net "GND")
	)
	(via
		(at 192.41494 138.98121)
		(size 0.4064)
		(drill 0.2032)
		(layers "F.Cu" "B.Cu")
		(tenting
			(front yes)
			(back yes)
		)
		(net "GND")
	)
	(via
		(at 64.7621 116.9906)
		(size 0.4064)
		(drill 0.2032)
		(layers "F.Cu" "B.Cu")
		(tenting
			(front yes)
			(back yes)
		)
		(net "GND")
	)
	(via
		(at 76.4461 132.2306)
		(size 0.4064)
		(drill 0.2032)
		(layers "F.Cu" "B.Cu")
		(tenting
			(front yes)
			(back yes)
		)
		(net "GND")
	)
	(via
		(at 80.6261 127.6162)
		(size 0.4064)
		(drill 0.2032)
		(layers "F.Cu" "B.Cu")
		(tenting
			(front yes)
			(back yes)
		)
		(net "GND")
	)
	(via
		(at 69.8421 96.6706)
		(size 0.4064)
		(drill 0.2032)
		(layers "F.Cu" "B.Cu")
		(tenting
			(front yes)
			(back yes)
		)
		(net "GND")
	)
	(via
		(at 167.8261 129.7286)
		(size 0.4064)
		(drill 0.2032)
		(layers "F.Cu" "B.Cu")
		(tenting
			(front yes)
			(back yes)
		)
		(net "GND")
	)
	(via
		(at 76.4461 93.6226)
		(size 0.4064)
		(drill 0.2032)
		(layers "F.Cu" "B.Cu")
		(tenting
			(front yes)
			(back yes)
		)
		(net "GND")
	)
	(via
		(at 76.9541 114.9586)
		(size 0.4064)
		(drill 0.2032)
		(layers "F.Cu" "B.Cu")
		(tenting
			(front yes)
			(back yes)
		)
		(net "GND")
	)
	(via
		(at 75.9381 131.2146)
		(size 0.4064)
		(drill 0.2032)
		(layers "F.Cu" "B.Cu")
		(tenting
			(front yes)
			(back yes)
		)
		(net "GND")
	)
	(via
		(at 80.3761 141.6162)
		(size 0.4064)
		(drill 0.2032)
		(layers "F.Cu" "B.Cu")
		(tenting
			(front yes)
			(back yes)
		)
		(net "GND")
	)
	(via
		(at 90.4761 86.0162)
		(size 0.5)
		(drill 0.2)
		(layers "F.Cu" "B.Cu")
		(net "GND")
	)
	(via
		(at 175.9261 129.7286)
		(size 0.4064)
		(drill 0.2032)
		(layers "F.Cu" "B.Cu")
		(tenting
			(front yes)
			(back yes)
		)
		(net "GND")
	)
	(via
		(at 60.6981 90.5746)
		(size 0.4064)
		(drill 0.2032)
		(layers "F.Cu" "B.Cu")
		(tenting
			(front yes)
			(back yes)
		)
		(net "GND")
	)
	(via
		(at 68.3181 97.6866)
		(size 0.4064)
		(drill 0.2032)
		(layers "F.Cu" "B.Cu")
		(tenting
			(front yes)
			(back yes)
		)
		(net "GND")
	)
	(via
		(at 208.4261 92.1162)
		(size 0.4064)
		(drill 0.2032)
		(layers "F.Cu" "B.Cu")
		(tenting
			(front yes)
			(back yes)
		)
		(net "GND")
	)
	(via
		(at 76.9541 137.3106)
		(size 0.4064)
		(drill 0.2032)
		(layers "F.Cu" "B.Cu")
		(tenting
			(front yes)
			(back yes)
		)
		(net "GND")
	)
	(via
		(at 68.8261 133.2466)
		(size 0.4064)
		(drill 0.2032)
		(layers "F.Cu" "B.Cu")
		(tenting
			(front yes)
			(back yes)
		)
		(net "GND")
	)
	(via
		(at 126.99598 154.1786)
		(size 0.4064)
		(drill 0.2032)
		(layers "F.Cu" "B.Cu")
		(tenting
			(front yes)
			(back yes)
		)
		(net "GND")
	)
	(via
		(at 76.4461 118.0066)
		(size 0.4064)
		(drill 0.2032)
		(layers "F.Cu" "B.Cu")
		(tenting
			(front yes)
			(back yes)
		)
		(net "GND")
	)
	(via
		(at 60.6981 125.1186)
		(size 0.4064)
		(drill 0.2032)
		(layers "F.Cu" "B.Cu")
		(tenting
			(front yes)
			(back yes)
		)
		(net "GND")
	)
	(via
		(at 68.3181 91.5906)
		(size 0.4064)
		(drill 0.2032)
		(layers "F.Cu" "B.Cu")
		(tenting
			(front yes)
			(back yes)
		)
		(net "GND")
	)
	(via
		(at 89.3761 83.1162)
		(size 0.4064)
		(drill 0.2032)
		(layers "F.Cu" "B.Cu")
		(tenting
			(front yes)
			(back yes)
		)
		(net "GND")
	)
	(via
		(at 76.4461 124.1026)
		(size 0.4064)
		(drill 0.2032)
		(layers "F.Cu" "B.Cu")
		(tenting
			(front yes)
			(back yes)
		)
		(net "GND")
	)
	(via
		(at 198.1261 116.8286)
		(size 0.4064)
		(drill 0.2032)
		(layers "F.Cu" "B.Cu")
		(tenting
			(front yes)
			(back yes)
		)
		(net "GND")
	)
	(via
		(at 69.3341 144.4226)
		(size 0.4064)
		(drill 0.2032)
		(layers "F.Cu" "B.Cu")
		(tenting
			(front yes)
			(back yes)
		)
		(net "GND")
	)
	(via
		(at 71.8741 96.6706)
		(size 0.4064)
		(drill 0.2032)
		(layers "F.Cu" "B.Cu")
		(tenting
			(front yes)
			(back yes)
		)
		(net "GND")
	)
	(via
		(at 81.3761 92.6162)
		(size 0.4064)
		(drill 0.2032)
		(layers "F.Cu" "B.Cu")
		(tenting
			(front yes)
			(back yes)
		)
		(net "GND")
	)
	(via
		(at 65.2701 118.0066)
		(size 0.4064)
		(drill 0.2032)
		(layers "F.Cu" "B.Cu")
		(tenting
			(front yes)
			(back yes)
		)
		(net "GND")
	)
	(via
		(at 72.8901 119.0226)
		(size 0.4064)
		(drill 0.2032)
		(layers "F.Cu" "B.Cu")
		(tenting
			(front yes)
			(back yes)
		)
		(net "GND")
	)
	(via
		(at 167.9261 134.1286)
		(size 0.4064)
		(drill 0.2032)
		(layers "F.Cu" "B.Cu")
		(tenting
			(front yes)
			(back yes)
		)
		(net "GND")
	)
	(via
		(at 196.6261 111.8286)
		(size 0.4064)
		(drill 0.2032)
		(layers "F.Cu" "B.Cu")
		(tenting
			(front yes)
			(back yes)
		)
		(net "GND")
	)
	(via
		(at 61.2061 138.3266)
		(size 0.4064)
		(drill 0.2032)
		(layers "F.Cu" "B.Cu")
		(tenting
			(front yes)
			(back yes)
		)
		(net "GND")
	)
	(via
		(at 226.8761 66.6162)
		(size 0.4064)
		(drill 0.2032)
		(layers "F.Cu" "B.Cu")
		(tenting
			(front yes)
			(back yes)
		)
		(net "GND")
	)
	(via
		(at 74.4141 144.4226)
		(size 0.4064)
		(drill 0.2032)
		(layers "F.Cu" "B.Cu")
		(tenting
			(front yes)
			(back yes)
		)
		(net "GND")
	)
	(via
		(at 74.4141 118.0066)
		(size 0.4064)
		(drill 0.2032)
		(layers "F.Cu" "B.Cu")
		(tenting
			(front yes)
			(back yes)
		)
		(net "GND")
	)
	(via
		(at 77.4621 93.6226)
		(size 0.4064)
		(drill 0.2032)
		(layers "F.Cu" "B.Cu")
		(tenting
			(front yes)
			(back yes)
		)
		(net "GND")
	)
	(via
		(at 61.2061 132.2306)
		(size 0.4064)
		(drill 0.2032)
		(layers "F.Cu" "B.Cu")
		(tenting
			(front yes)
			(back yes)
		)
		(net "GND")
	)
	(via
		(at 172.3841 95.2286)
		(size 0.4064)
		(drill 0.2032)
		(layers "F.Cu" "B.Cu")
		(tenting
			(front yes)
			(back yes)
		)
		(net "GND")
	)
	(via
		(at 67.3021 93.6226)
		(size 0.4064)
		(drill 0.2032)
		(layers "F.Cu" "B.Cu")
		(tenting
			(front yes)
			(back yes)
		)
		(net "GND")
	)
	(via
		(at 228.4261 113.5162)
		(size 0.4064)
		(drill 0.2032)
		(layers "F.Cu" "B.Cu")
		(tenting
			(front yes)
			(back yes)
		)
		(net "GND")
	)
	(via
		(at 214.5261 92.2162)
		(size 0.4064)
		(drill 0.2032)
		(layers "F.Cu" "B.Cu")
		(tenting
			(front yes)
			(back yes)
		)
		(net "GND")
	)
	(via
		(at 75.4301 142.3906)
		(size 0.4064)
		(drill 0.2032)
		(layers "F.Cu" "B.Cu")
		(tenting
			(front yes)
			(back yes)
		)
		(net "GND")
	)
	(via
		(at 74.9221 131.2146)
		(size 0.4064)
		(drill 0.2032)
		(layers "F.Cu" "B.Cu")
		(tenting
			(front yes)
			(back yes)
		)
		(net "GND")
	)
	(via
		(at 149.1261 114.8662)
		(size 0.4064)
		(drill 0.2032)
		(layers "F.Cu" "B.Cu")
		(tenting
			(front yes)
			(back yes)
		)
		(net "GND")
	)
	(via
		(at 175.3761 86.3286)
		(size 0.4064)
		(drill 0.2032)
		(layers "F.Cu" "B.Cu")
		(tenting
			(front yes)
			(back yes)
		)
		(net "GND")
	)
	(via
		(at 172.9261 129.7286)
		(size 0.4064)
		(drill 0.2032)
		(layers "F.Cu" "B.Cu")
		(tenting
			(front yes)
			(back yes)
		)
		(net "GND")
	)
	(via
		(at 76.9541 92.6066)
		(size 0.4064)
		(drill 0.2032)
		(layers "F.Cu" "B.Cu")
		(tenting
			(front yes)
			(back yes)
		)
		(net "GND")
	)
	(via
		(at 71.8741 123.0866)
		(size 0.4064)
		(drill 0.2032)
		(layers "F.Cu" "B.Cu")
		(tenting
			(front yes)
			(back yes)
		)
		(net "GND")
	)
	(via
		(at 76.9541 104.7986)
		(size 0.4064)
		(drill 0.2032)
		(layers "F.Cu" "B.Cu")
		(tenting
			(front yes)
			(back yes)
		)
		(net "GND")
	)
	(via
		(at 73.9061 141.3746)
		(size 0.4064)
		(drill 0.2032)
		(layers "F.Cu" "B.Cu")
		(tenting
			(front yes)
			(back yes)
		)
		(net "GND")
	)
	(via
		(at 74.9221 129.1826)
		(size 0.4064)
		(drill 0.2032)
		(layers "F.Cu" "B.Cu")
		(tenting
			(front yes)
			(back yes)
		)
		(net "GND")
	)
	(via
		(at 66.7941 90.5746)
		(size 0.4064)
		(drill 0.2032)
		(layers "F.Cu" "B.Cu")
		(tenting
			(front yes)
			(back yes)
		)
		(net "GND")
	)
	(via
		(at 75.9381 112.9266)
		(size 0.4064)
		(drill 0.2032)
		(layers "F.Cu" "B.Cu")
		(tenting
			(front yes)
			(back yes)
		)
		(net "GND")
	)
	(via
		(at 73.3981 118.0066)
		(size 0.4064)
		(drill 0.2032)
		(layers "F.Cu" "B.Cu")
		(tenting
			(front yes)
			(back yes)
		)
		(net "GND")
	)
	(via
		(at 71.8741 112.9266)
		(size 0.4064)
		(drill 0.2032)
		(layers "F.Cu" "B.Cu")
		(tenting
			(front yes)
			(back yes)
		)
		(net "GND")
	)
	(via
		(at 60.6981 131.2146)
		(size 0.4064)
		(drill 0.2032)
		(layers "F.Cu" "B.Cu")
		(tenting
			(front yes)
			(back yes)
		)
		(net "GND")
	)
	(via
		(at 217.8761 61.8662)
		(size 0.4064)
		(drill 0.2032)
		(layers "F.Cu" "B.Cu")
		(tenting
			(front yes)
			(back yes)
		)
		(net "GND")
	)
	(via
		(at 179.0261 129.7286)
		(size 0.4064)
		(drill 0.2032)
		(layers "F.Cu" "B.Cu")
		(tenting
			(front yes)
			(back yes)
		)
		(net "GND")
	)
	(via
		(at 74.4141 128.1666)
		(size 0.4064)
		(drill 0.2032)
		(layers "F.Cu" "B.Cu")
		(tenting
			(front yes)
			(back yes)
		)
		(net "GND")
	)
	(via
		(at 64.2541 103.7826)
		(size 0.4064)
		(drill 0.2032)
		(layers "F.Cu" "B.Cu")
		(tenting
			(front yes)
			(back yes)
		)
		(net "GND")
	)
	(via
		(at 227.1261 113.6162)
		(size 0.4064)
		(drill 0.2032)
		(layers "F.Cu" "B.Cu")
		(tenting
			(front yes)
			(back yes)
		)
		(net "GND")
	)
	(via
		(at 76.4461 120.0386)
		(size 0.4064)
		(drill 0.2032)
		(layers "F.Cu" "B.Cu")
		(tenting
			(front yes)
			(back yes)
		)
		(net "GND")
	)
	(via
		(at 60.1901 144.4226)
		(size 0.4064)
		(drill 0.2032)
		(layers "F.Cu" "B.Cu")
		(tenting
			(front yes)
			(back yes)
		)
		(net "GND")
	)
	(via
		(at 67.3021 142.3906)
		(size 0.4064)
		(drill 0.2032)
		(layers "F.Cu" "B.Cu")
		(tenting
			(front yes)
			(back yes)
		)
		(net "GND")
	)
	(via
		(at 198.1261 109.3286)
		(size 0.4064)
		(drill 0.2032)
		(layers "F.Cu" "B.Cu")
		(tenting
			(front yes)
			(back yes)
		)
		(net "GND")
	)
	(via
		(at 77.4621 124.1026)
		(size 0.4064)
		(drill 0.2032)
		(layers "F.Cu" "B.Cu")
		(tenting
			(front yes)
			(back yes)
		)
		(net "GND")
	)
	(via
		(at 69.3341 132.2306)
		(size 0.4064)
		(drill 0.2032)
		(layers "F.Cu" "B.Cu")
		(tenting
			(front yes)
			(back yes)
		)
		(net "GND")
	)
	(via
		(at 89.3761 88.2162)
		(size 0.5)
		(drill 0.2)
		(layers "F.Cu" "B.Cu")
		(net "GND")
	)
	(via
		(at 77.4621 105.8146)
		(size 0.4064)
		(drill 0.2032)
		(layers "F.Cu" "B.Cu")
		(tenting
			(front yes)
			(back yes)
		)
		(net "GND")
	)
	(via
		(at 64.7621 90.5746)
		(size 0.4064)
		(drill 0.2032)
		(layers "F.Cu" "B.Cu")
		(tenting
			(front yes)
			(back yes)
		)
		(net "GND")
	)
	(via
		(at 218.344 118.13612)
		(size 0.4064)
		(drill 0.2032)
		(layers "F.Cu" "B.Cu")
		(tenting
			(front yes)
			(back yes)
		)
		(net "GND")
	)
	(via
		(at 75.9381 104.7986)
		(size 0.4064)
		(drill 0.2032)
		(layers "F.Cu" "B.Cu")
		(tenting
			(front yes)
			(back yes)
		)
		(net "GND")
	)
	(via
		(at 69.8421 139.3426)
		(size 0.4064)
		(drill 0.2032)
		(layers "F.Cu" "B.Cu")
		(tenting
			(front yes)
			(back yes)
		)
		(net "GND")
	)
	(via
		(at 219.5261 132.7162)
		(size 0.4064)
		(drill 0.2032)
		(layers "F.Cu" "B.Cu")
		(tenting
			(front yes)
			(back yes)
		)
		(net "GND")
	)
	(via
		(at 68.3181 120.0386)
		(size 0.4064)
		(drill 0.2032)
		(layers "F.Cu" "B.Cu")
		(tenting
			(front yes)
			(back yes)
		)
		(net "GND")
	)
	(via
		(at 198.1261 121.8286)
		(size 0.4064)
		(drill 0.2032)
		(layers "F.Cu" "B.Cu")
		(tenting
			(front yes)
			(back yes)
		)
		(net "GND")
	)
	(via
		(at 71.3661 140.3586)
		(size 0.4064)
		(drill 0.2032)
		(layers "F.Cu" "B.Cu")
		(tenting
			(front yes)
			(back yes)
		)
		(net "GND")
	)
	(via
		(at 67.8101 133.2466)
		(size 0.4064)
		(drill 0.2032)
		(layers "F.Cu" "B.Cu")
		(tenting
			(front yes)
			(back yes)
		)
		(net "GND")
	)
	(via
		(at 68.3181 128.1666)
		(size 0.4064)
		(drill 0.2032)
		(layers "F.Cu" "B.Cu")
		(tenting
			(front yes)
			(back yes)
		)
		(net "GND")
	)
	(via
		(at 68.8261 96.6706)
		(size 0.4064)
		(drill 0.2032)
		(layers "F.Cu" "B.Cu")
		(tenting
			(front yes)
			(back yes)
		)
		(net "GND")
	)
	(via
		(at 74.4141 126.1346)
		(size 0.4064)
		(drill 0.2032)
		(layers "F.Cu" "B.Cu")
		(tenting
			(front yes)
			(back yes)
		)
		(net "GND")
	)
	(via
		(at 198.1261 119.6242)
		(size 0.4064)
		(drill 0.2032)
		(layers "F.Cu" "B.Cu")
		(tenting
			(front yes)
			(back yes)
		)
		(net "GND")
	)
	(via
		(at 61.2061 103.7826)
		(size 0.4064)
		(drill 0.2032)
		(layers "F.Cu" "B.Cu")
		(tenting
			(front yes)
			(back yes)
		)
		(net "GND")
	)
	(via
		(at 218.1261 57.3662)
		(size 0.4064)
		(drill 0.2032)
		(layers "F.Cu" "B.Cu")
		(tenting
			(front yes)
			(back yes)
		)
		(net "GND")
	)
	(via
		(at 230.42252 135.01978)
		(size 0.4064)
		(drill 0.2032)
		(layers "F.Cu" "B.Cu")
		(tenting
			(front yes)
			(back yes)
		)
		(net "GND")
	)
	(via
		(at 167.4001 95.2286)
		(size 0.4064)
		(drill 0.2032)
		(layers "F.Cu" "B.Cu")
		(tenting
			(front yes)
			(back yes)
		)
		(net "GND")
	)
	(via
		(at 77.4621 111.9106)
		(size 0.4064)
		(drill 0.2032)
		(layers "F.Cu" "B.Cu")
		(tenting
			(front yes)
			(back yes)
		)
		(net "GND")
	)
	(via
		(at 225.62252 135.01978)
		(size 0.4064)
		(drill 0.2032)
		(layers "F.Cu" "B.Cu")
		(tenting
			(front yes)
			(back yes)
		)
		(net "GND")
	)
	(via
		(at 77.4621 134.2626)
		(size 0.4064)
		(drill 0.2032)
		(layers "F.Cu" "B.Cu")
		(tenting
			(front yes)
			(back yes)
		)
		(net "GND")
	)
	(via
		(at 68.3181 118.0066)
		(size 0.4064)
		(drill 0.2032)
		(layers "F.Cu" "B.Cu")
		(tenting
			(front yes)
			(back yes)
		)
		(net "GND")
	)
	(via
		(at 177.3011 96.4036)
		(size 0.4064)
		(drill 0.2032)
		(layers "F.Cu" "B.Cu")
		(tenting
			(front yes)
			(back yes)
		)
		(net "GND")
	)
	(via
		(at 71.8741 141.3746)
		(size 0.4064)
		(drill 0.2032)
		(layers "F.Cu" "B.Cu")
		(tenting
			(front yes)
			(back yes)
		)
		(net "GND")
	)
	(via
		(at 222.3381 117.0936)
		(size 0.4064)
		(drill 0.2032)
		(layers "F.Cu" "B.Cu")
		(tenting
			(front yes)
			(back yes)
		)
		(net "GND")
	)
	(via
		(at 107.5611 154.3286)
		(size 0.4064)
		(drill 0.2032)
		(layers "F.Cu" "B.Cu")
		(tenting
			(front yes)
			(back yes)
		)
		(net "GND")
	)
	(via
		(at 73.9061 116.9906)
		(size 0.4064)
		(drill 0.2032)
		(layers "F.Cu" "B.Cu")
		(tenting
			(front yes)
			(back yes)
		)
		(net "GND")
	)
	(via
		(at 67.3021 132.2306)
		(size 0.4064)
		(drill 0.2032)
		(layers "F.Cu" "B.Cu")
		(tenting
			(front yes)
			(back yes)
		)
		(net "GND")
	)
	(via
		(at 57.1421 95.6546)
		(size 0.4064)
		(drill 0.2032)
		(layers "F.Cu" "B.Cu")
		(tenting
			(front yes)
			(back yes)
		)
		(net "GND")
	)
	(via
		(at 76.4461 105.8146)
		(size 0.4064)
		(drill 0.2032)
		(layers "F.Cu" "B.Cu")
		(tenting
			(front yes)
			(back yes)
		)
		(net "GND")
	)
	(via
		(at 196.6261 109.3286)
		(size 0.4064)
		(drill 0.2032)
		(layers "F.Cu" "B.Cu")
		(tenting
			(front yes)
			(back yes)
		)
		(net "GND")
	)
	(via
		(at 65.7781 121.0546)
		(size 0.4064)
		(drill 0.2032)
		(layers "F.Cu" "B.Cu")
		(tenting
			(front yes)
			(back yes)
		)
		(net "GND")
	)
	(via
		(at 213.4885 117.9662)
		(size 0.4064)
		(drill 0.2032)
		(layers "F.Cu" "B.Cu")
		(tenting
			(front yes)
			(back yes)
		)
		(net "GND")
	)
	(via
		(at 196.6261 116.8286)
		(size 0.4064)
		(drill 0.2032)
		(layers "F.Cu" "B.Cu")
		(tenting
			(front yes)
			(back yes)
		)
		(net "GND")
	)
	(via
		(at 172.3841 96.3286)
		(size 0.4064)
		(drill 0.2032)
		(layers "F.Cu" "B.Cu")
		(tenting
			(front yes)
			(back yes)
		)
		(net "GND")
	)
	(via
		(at 68.3181 113.9426)
		(size 0.4064)
		(drill 0.2032)
		(layers "F.Cu" "B.Cu")
		(tenting
			(front yes)
			(back yes)
		)
		(net "GND")
	)
	(via
		(at 72.3821 138.3266)
		(size 0.4064)
		(drill 0.2032)
		(layers "F.Cu" "B.Cu")
		(tenting
			(front yes)
			(back yes)
		)
		(net "GND")
	)
	(via
		(at 67.3021 105.8146)
		(size 0.4064)
		(drill 0.2032)
		(layers "F.Cu" "B.Cu")
		(tenting
			(front yes)
			(back yes)
		)
		(net "GND")
	)
	(via
		(at 73.3981 113.9426)
		(size 0.4064)
		(drill 0.2032)
		(layers "F.Cu" "B.Cu")
		(tenting
			(front yes)
			(back yes)
		)
		(net "GND")
	)
	(via
		(at 75.4301 113.9426)
		(size 0.4064)
		(drill 0.2032)
		(layers "F.Cu" "B.Cu")
		(tenting
			(front yes)
			(back yes)
		)
		(net "GND")
	)
	(via
		(at 68.8261 127.1506)
		(size 0.4064)
		(drill 0.2032)
		(layers "F.Cu" "B.Cu")
		(tenting
			(front yes)
			(back yes)
		)
		(net "GND")
	)
	(via
		(at 61.7141 90.5746)
		(size 0.4064)
		(drill 0.2032)
		(layers "F.Cu" "B.Cu")
		(tenting
			(front yes)
			(back yes)
		)
		(net "GND")
	)
	(via
		(at 208.9261 92.1162)
		(size 0.4064)
		(drill 0.2032)
		(layers "F.Cu" "B.Cu")
		(tenting
			(front yes)
			(back yes)
		)
		(net "GND")
	)
	(via
		(at 68.8261 104.7986)
		(size 0.4064)
		(drill 0.2032)
		(layers "F.Cu" "B.Cu")
		(tenting
			(front yes)
			(back yes)
		)
		(net "GND")
	)
	(via
		(at 69.3341 91.5906)
		(size 0.4064)
		(drill 0.2032)
		(layers "F.Cu" "B.Cu")
		(tenting
			(front yes)
			(back yes)
		)
		(net "GND")
	)
	(via
		(at 61.2061 111.9106)
		(size 0.4064)
		(drill 0.2032)
		(layers "F.Cu" "B.Cu")
		(tenting
			(front yes)
			(back yes)
		)
		(net "GND")
	)
	(via
		(at 88.2761 87.1162)
		(size 0.5)
		(drill 0.2)
		(layers "F.Cu" "B.Cu")
		(net "GND")
	)
	(via
		(at 150.2847 119.8286)
		(size 0.4064)
		(drill 0.2032)
		(layers "F.Cu" "B.Cu")
		(tenting
			(front yes)
			(back yes)
		)
		(net "GND")
	)
	(via
		(at 62.7301 116.9906)
		(size 0.4064)
		(drill 0.2032)
		(layers "F.Cu" "B.Cu")
		(tenting
			(front yes)
			(back yes)
		)
		(net "GND")
	)
	(via
		(at 174.32611 129.72861)
		(size 0.4064)
		(drill 0.2032)
		(layers "F.Cu" "B.Cu")
		(tenting
			(front yes)
			(back yes)
		)
		(net "GND")
	)
	(via
		(at 77.4621 91.5906)
		(size 0.4064)
		(drill 0.2032)
		(layers "F.Cu" "B.Cu")
		(tenting
			(front yes)
			(back yes)
		)
		(net "GND")
	)
	(via
		(at 67.3021 126.1346)
		(size 0.4064)
		(drill 0.2032)
		(layers "F.Cu" "B.Cu")
		(tenting
			(front yes)
			(back yes)
		)
		(net "GND")
	)
	(via
		(at 194.8761 81.5866)
		(size 0.4064)
		(drill 0.2032)
		(layers "F.Cu" "B.Cu")
		(tenting
			(front yes)
			(back yes)
		)
		(net "GND")
	)
	(via
		(at 210.6837 115.4188)
		(size 0.4064)
		(drill 0.2032)
		(layers "F.Cu" "B.Cu")
		(tenting
			(front yes)
			(back yes)
		)
		(net "GND")
	)
	(via
		(at 73.9061 131.2146)
		(size 0.4064)
		(drill 0.2032)
		(layers "F.Cu" "B.Cu")
		(tenting
			(front yes)
			(back yes)
		)
		(net "GND")
	)
	(via
		(at 65.7781 139.3426)
		(size 0.4064)
		(drill 0.2032)
		(layers "F.Cu" "B.Cu")
		(tenting
			(front yes)
			(back yes)
		)
		(net "GND")
	)
	(via
		(at 67.8101 116.9906)
		(size 0.4064)
		(drill 0.2032)
		(layers "F.Cu" "B.Cu")
		(tenting
			(front yes)
			(back yes)
		)
		(net "GND")
	)
	(via
		(at 198.1261 106.8286)
		(size 0.4064)
		(drill 0.2032)
		(layers "F.Cu" "B.Cu")
		(tenting
			(front yes)
			(back yes)
		)
		(net "GND")
	)
	(via
		(at 60.6981 119.0226)
		(size 0.4064)
		(drill 0.2032)
		(layers "F.Cu" "B.Cu")
		(tenting
			(front yes)
			(back yes)
		)
		(net "GND")
	)
	(via
		(at 65.7781 104.7986)
		(size 0.4064)
		(drill 0.2032)
		(layers "F.Cu" "B.Cu")
		(tenting
			(front yes)
			(back yes)
		)
		(net "GND")
	)
	(via
		(at 90.4761 88.2162)
		(size 0.5)
		(drill 0.2)
		(layers "F.Cu" "B.Cu")
		(net "GND")
	)
	(via
		(at 76.9541 106.8306)
		(size 0.4064)
		(drill 0.2032)
		(layers "F.Cu" "B.Cu")
		(tenting
			(front yes)
			(back yes)
		)
		(net "GND")
	)
	(via
		(at 59.1741 144.4226)
		(size 0.4064)
		(drill 0.2032)
		(layers "F.Cu" "B.Cu")
		(tenting
			(front yes)
			(back yes)
		)
		(net "GND")
	)
	(via
		(at 66.7941 106.8306)
		(size 0.4064)
		(drill 0.2032)
		(layers "F.Cu" "B.Cu")
		(tenting
			(front yes)
			(back yes)
		)
		(net "GND")
	)
	(via
		(at 70.3501 91.5906)
		(size 0.4064)
		(drill 0.2032)
		(layers "F.Cu" "B.Cu")
		(tenting
			(front yes)
			(back yes)
		)
		(net "GND")
	)
	(via
		(at 56.6341 131.2146)
		(size 0.4064)
		(drill 0.2032)
		(layers "F.Cu" "B.Cu")
		(tenting
			(front yes)
			(back yes)
		)
		(net "GND")
	)
	(via
		(at 77.4621 142.3906)
		(size 0.4064)
		(drill 0.2032)
		(layers "F.Cu" "B.Cu")
		(tenting
			(front yes)
			(back yes)
		)
		(net "GND")
	)
	(via
		(at 70.8581 96.6706)
		(size 0.4064)
		(drill 0.2032)
		(layers "F.Cu" "B.Cu")
		(tenting
			(front yes)
			(back yes)
		)
		(net "GND")
	)
	(via
		(at 66.2861 142.3906)
		(size 0.4064)
		(drill 0.2032)
		(layers "F.Cu" "B.Cu")
		(tenting
			(front yes)
			(back yes)
		)
		(net "GND")
	)
	(via
		(at 65.7781 98.7026)
		(size 0.4064)
		(drill 0.2032)
		(layers "F.Cu" "B.Cu")
		(tenting
			(front yes)
			(back yes)
		)
		(net "GND")
	)
	(via
		(at 66.7941 123.0866)
		(size 0.4064)
		(drill 0.2032)
		(layers "F.Cu" "B.Cu")
		(tenting
			(front yes)
			(back yes)
		)
		(net "GND")
	)
	(via
		(at 61.2061 126.1346)
		(size 0.4064)
		(drill 0.2032)
		(layers "F.Cu" "B.Cu")
		(tenting
			(front yes)
			(back yes)
		)
		(net "GND")
	)
	(via
		(at 128.98452 154.23884)
		(size 0.4064)
		(drill 0.2032)
		(layers "F.Cu" "B.Cu")
		(tenting
			(front yes)
			(back yes)
		)
		(net "GND")
	)
	(via
		(at 66.7941 131.2146)
		(size 0.4064)
		(drill 0.2032)
		(layers "F.Cu" "B.Cu")
		(tenting
			(front yes)
			(back yes)
		)
		(net "GND")
	)
	(via
		(at 67.8101 104.7986)
		(size 0.4064)
		(drill 0.2032)
		(layers "F.Cu" "B.Cu")
		(tenting
			(front yes)
			(back yes)
		)
		(net "GND")
	)
	(via
		(at 67.8101 137.3106)
		(size 0.4064)
		(drill 0.2032)
		(layers "F.Cu" "B.Cu")
		(tenting
			(front yes)
			(back yes)
		)
		(net "GND")
	)
	(via
		(at 74.3761 124.3662)
		(size 0.4064)
		(drill 0.2032)
		(layers "F.Cu" "B.Cu")
		(tenting
			(front yes)
			(back yes)
		)
		(net "GND")
	)
	(via
		(at 59.6821 116.9906)
		(size 0.4064)
		(drill 0.2032)
		(layers "F.Cu" "B.Cu")
		(tenting
			(front yes)
			(back yes)
		)
		(net "GND")
	)
	(via
		(at 66.2861 105.8146)
		(size 0.4064)
		(drill 0.2032)
		(layers "F.Cu" "B.Cu")
		(tenting
			(front yes)
			(back yes)
		)
		(net "GND")
	)
	(via
		(at 69.3341 128.1666)
		(size 0.4064)
		(drill 0.2032)
		(layers "F.Cu" "B.Cu")
		(tenting
			(front yes)
			(back yes)
		)
		(net "GND")
	)
	(via
		(at 164.8011 95.2036)
		(size 0.4064)
		(drill 0.2032)
		(layers "F.Cu" "B.Cu")
		(tenting
			(front yes)
			(back yes)
		)
		(net "GND")
	)
	(via
		(at 76.9541 133.2466)
		(size 0.4064)
		(drill 0.2032)
		(layers "F.Cu" "B.Cu")
		(tenting
			(front yes)
			(back yes)
		)
		(net "GND")
	)
	(via
		(at 165.0511 96.39356)
		(size 0.4064)
		(drill 0.2032)
		(layers "F.Cu" "B.Cu")
		(tenting
			(front yes)
			(back yes)
		)
		(net "GND")
	)
	(via
		(at 74.9221 116.9906)
		(size 0.4064)
		(drill 0.2032)
		(layers "F.Cu" "B.Cu")
		(tenting
			(front yes)
			(back yes)
		)
		(net "GND")
	)
	(via
		(at 68.8261 123.0866)
		(size 0.4064)
		(drill 0.2032)
		(layers "F.Cu" "B.Cu")
		(tenting
			(front yes)
			(back yes)
		)
		(net "GND")
	)
	(via
		(at 67.8101 121.0546)
		(size 0.4064)
		(drill 0.2032)
		(layers "F.Cu" "B.Cu")
		(tenting
			(front yes)
			(back yes)
		)
		(net "GND")
	)
	(via
		(at 57.1421 122.0706)
		(size 0.4064)
		(drill 0.2032)
		(layers "F.Cu" "B.Cu")
		(tenting
			(front yes)
			(back yes)
		)
		(net "GND")
	)
	(via
		(at 57.1421 144.4226)
		(size 0.4064)
		(drill 0.2032)
		(layers "F.Cu" "B.Cu")
		(tenting
			(front yes)
			(back yes)
		)
		(net "GND")
	)
	(via
		(at 85.1261 83.1162)
		(size 0.4064)
		(drill 0.2032)
		(layers "F.Cu" "B.Cu")
		(tenting
			(front yes)
			(back yes)
		)
		(net "GND")
	)
	(via
		(at 76.4461 134.2626)
		(size 0.4064)
		(drill 0.2032)
		(layers "F.Cu" "B.Cu")
		(tenting
			(front yes)
			(back yes)
		)
		(net "GND")
	)
	(via
		(at 76.9541 90.5746)
		(size 0.4064)
		(drill 0.2032)
		(layers "F.Cu" "B.Cu")
		(tenting
			(front yes)
			(back yes)
		)
		(net "GND")
	)
	(via
		(at 69.3341 93.6226)
		(size 0.4064)
		(drill 0.2032)
		(layers "F.Cu" "B.Cu")
		(tenting
			(front yes)
			(back yes)
		)
		(net "GND")
	)
	(via
		(at 96.1261 75.3286)
		(size 0.4064)
		(drill 0.2032)
		(layers "F.Cu" "B.Cu")
		(tenting
			(front yes)
			(back yes)
		)
		(net "GND")
	)
	(via
		(at 67.8101 110.8946)
		(size 0.4064)
		(drill 0.2032)
		(layers "F.Cu" "B.Cu")
		(tenting
			(front yes)
			(back yes)
		)
		(net "GND")
	)
	(via
		(at 74.3761 133.1162)
		(size 0.4064)
		(drill 0.2032)
		(layers "F.Cu" "B.Cu")
		(tenting
			(front yes)
			(back yes)
		)
		(net "GND")
	)
	(via
		(at 67.8101 129.1826)
		(size 0.4064)
		(drill 0.2032)
		(layers "F.Cu" "B.Cu")
		(tenting
			(front yes)
			(back yes)
		)
		(net "GND")
	)
	(via
		(at 71.8741 116.9906)
		(size 0.4064)
		(drill 0.2032)
		(layers "F.Cu" "B.Cu")
		(tenting
			(front yes)
			(back yes)
		)
		(net "GND")
	)
	(via
		(at 76.4461 144.4226)
		(size 0.4064)
		(drill 0.2032)
		(layers "F.Cu" "B.Cu")
		(tenting
			(front yes)
			(back yes)
		)
		(net "GND")
	)
	(via
		(at 70.8581 139.3426)
		(size 0.4064)
		(drill 0.2032)
		(layers "F.Cu" "B.Cu")
		(tenting
			(front yes)
			(back yes)
		)
		(net "GND")
	)
	(via
		(at 56.6341 123.0866)
		(size 0.4064)
		(drill 0.2032)
		(layers "F.Cu" "B.Cu")
		(tenting
			(front yes)
			(back yes)
		)
		(net "GND")
	)
	(via
		(at 74.9221 139.3426)
		(size 0.4064)
		(drill 0.2032)
		(layers "F.Cu" "B.Cu")
		(tenting
			(front yes)
			(back yes)
		)
		(net "GND")
	)
	(via
		(at 89.3761 87.1162)
		(size 0.5)
		(drill 0.2)
		(layers "F.Cu" "B.Cu")
		(net "GND")
	)
	(via
		(at 192.51494 142.78121)
		(size 0.4064)
		(drill 0.2032)
		(layers "F.Cu" "B.Cu")
		(tenting
			(front yes)
			(back yes)
		)
		(net "GND")
	)
	(via
		(at 76.4461 138.3266)
		(size 0.4064)
		(drill 0.2032)
		(layers "F.Cu" "B.Cu")
		(tenting
			(front yes)
			(back yes)
		)
		(net "GND")
	)
	(via
		(at 66.2861 103.7826)
		(size 0.4064)
		(drill 0.2032)
		(layers "F.Cu" "B.Cu")
		(tenting
			(front yes)
			(back yes)
		)
		(net "GND")
	)
	(via
		(at 72.8901 116.9906)
		(size 0.4064)
		(drill 0.2032)
		(layers "F.Cu" "B.Cu")
		(tenting
			(front yes)
			(back yes)
		)
		(net "GND")
	)
	(via
		(at 59.6821 90.5746)
		(size 0.4064)
		(drill 0.2032)
		(layers "F.Cu" "B.Cu")
		(tenting
			(front yes)
			(back yes)
		)
		(net "GND")
	)
	(via
		(at 73.3981 91.5906)
		(size 0.4064)
		(drill 0.2032)
		(layers "F.Cu" "B.Cu")
		(tenting
			(front yes)
			(back yes)
		)
		(net "GND")
	)
	(via
		(at 68.3181 140.3586)
		(size 0.4064)
		(drill 0.2032)
		(layers "F.Cu" "B.Cu")
		(tenting
			(front yes)
			(back yes)
		)
		(net "GND")
	)
	(via
		(at 76.9541 139.3426)
		(size 0.4064)
		(drill 0.2032)
		(layers "F.Cu" "B.Cu")
		(tenting
			(front yes)
			(back yes)
		)
		(net "GND")
	)
	(via
		(at 60.6981 116.9906)
		(size 0.4064)
		(drill 0.2032)
		(layers "F.Cu" "B.Cu")
		(tenting
			(front yes)
			(back yes)
		)
		(net "GND")
	)
	(via
		(at 67.8101 141.3746)
		(size 0.4064)
		(drill 0.2032)
		(layers "F.Cu" "B.Cu")
		(tenting
			(front yes)
			(back yes)
		)
		(net "GND")
	)
	(via
		(at 77.4621 144.4226)
		(size 0.4064)
		(drill 0.2032)
		(layers "F.Cu" "B.Cu")
		(tenting
			(front yes)
			(back yes)
		)
		(net "GND")
	)
	(via
		(at 73.3981 142.3906)
		(size 0.4064)
		(drill 0.2032)
		(layers "F.Cu" "B.Cu")
		(tenting
			(front yes)
			(back yes)
		)
		(net "GND")
	)
	(via
		(at 67.8101 90.5746)
		(size 0.4064)
		(drill 0.2032)
		(layers "F.Cu" "B.Cu")
		(tenting
			(front yes)
			(back yes)
		)
		(net "GND")
	)
	(via
		(at 68.3181 103.7826)
		(size 0.4064)
		(drill 0.2032)
		(layers "F.Cu" "B.Cu")
		(tenting
			(front yes)
			(back yes)
		)
		(net "GND")
	)
	(via
		(at 73.3981 140.3586)
		(size 0.4064)
		(drill 0.2032)
		(layers "F.Cu" "B.Cu")
		(tenting
			(front yes)
			(back yes)
		)
		(net "GND")
	)
	(via
		(at 130.1261 82.0786)
		(size 0.4064)
		(drill 0.2032)
		(layers "F.Cu" "B.Cu")
		(tenting
			(front yes)
			(back yes)
		)
		(net "GND")
	)
	(via
		(at 198.1261 114.3206)
		(size 0.4064)
		(drill 0.2032)
		(layers "F.Cu" "B.Cu")
		(tenting
			(front yes)
			(back yes)
		)
		(net "GND")
	)
	(via
		(at 76.9541 119.0226)
		(size 0.4064)
		(drill 0.2032)
		(layers "F.Cu" "B.Cu")
		(tenting
			(front yes)
			(back yes)
		)
		(net "GND")
	)
	(via
		(at 74.9221 114.9586)
		(size 0.4064)
		(drill 0.2032)
		(layers "F.Cu" "B.Cu")
		(tenting
			(front yes)
			(back yes)
		)
		(net "GND")
	)
	(via
		(at 199.9847 91.8206)
		(size 0.4064)
		(drill 0.2032)
		(layers "F.Cu" "B.Cu")
		(tenting
			(front yes)
			(back yes)
		)
		(net "GND")
	)
	(via
		(at 65.7781 96.6706)
		(size 0.4064)
		(drill 0.2032)
		(layers "F.Cu" "B.Cu")
		(tenting
			(front yes)
			(back yes)
		)
		(net "GND")
	)
	(via
		(at 60.6981 139.3426)
		(size 0.4064)
		(drill 0.2032)
		(layers "F.Cu" "B.Cu")
		(tenting
			(front yes)
			(back yes)
		)
		(net "GND")
	)
	(via
		(at 195.1011 89.3036)
		(size 0.4064)
		(drill 0.2032)
		(layers "F.Cu" "B.Cu")
		(tenting
			(front yes)
			(back yes)
		)
		(net "GND")
	)
	(via
		(at 68.3181 144.4226)
		(size 0.4064)
		(drill 0.2032)
		(layers "F.Cu" "B.Cu")
		(tenting
			(front yes)
			(back yes)
		)
		(net "GND")
	)
	(via
		(at 74.9221 90.5746)
		(size 0.4064)
		(drill 0.2032)
		(layers "F.Cu" "B.Cu")
		(tenting
			(front yes)
			(back yes)
		)
		(net "GND")
	)
	(via
		(at 68.3181 134.2626)
		(size 0.4064)
		(drill 0.2032)
		(layers "F.Cu" "B.Cu")
		(tenting
			(front yes)
			(back yes)
		)
		(net "GND")
	)
	(via
		(at 68.3181 142.3906)
		(size 0.4064)
		(drill 0.2032)
		(layers "F.Cu" "B.Cu")
		(tenting
			(front yes)
			(back yes)
		)
		(net "GND")
	)
	(via
		(at 56.6341 135.2786)
		(size 0.4064)
		(drill 0.2032)
		(layers "F.Cu" "B.Cu")
		(tenting
			(front yes)
			(back yes)
		)
		(net "GND")
	)
	(via
		(at 149.0909 112.3102)
		(size 0.4064)
		(drill 0.2032)
		(layers "F.Cu" "B.Cu")
		(tenting
			(front yes)
			(back yes)
		)
		(net "GND")
	)
	(via
		(at 74.3761 138.1162)
		(size 0.4064)
		(drill 0.2032)
		(layers "F.Cu" "B.Cu")
		(tenting
			(front yes)
			(back yes)
		)
		(net "GND")
	)
	(via
		(at 197.3761 81.5866)
		(size 0.4064)
		(drill 0.2032)
		(layers "F.Cu" "B.Cu")
		(tenting
			(front yes)
			(back yes)
		)
		(net "GND")
	)
	(via
		(at 66.7941 137.3106)
		(size 0.4064)
		(drill 0.2032)
		(layers "F.Cu" "B.Cu")
		(tenting
			(front yes)
			(back yes)
		)
		(net "GND")
	)
	(via
		(at 74.4141 142.3906)
		(size 0.4064)
		(drill 0.2032)
		(layers "F.Cu" "B.Cu")
		(tenting
			(front yes)
			(back yes)
		)
		(net "GND")
	)
	(via
		(at 203.9739 109.1901)
		(size 0.4064)
		(drill 0.2032)
		(layers "F.Cu" "B.Cu")
		(tenting
			(front yes)
			(back yes)
		)
		(net "GND")
	)
	(via
		(at 77.4621 132.2306)
		(size 0.4064)
		(drill 0.2032)
		(layers "F.Cu" "B.Cu")
		(tenting
			(front yes)
			(back yes)
		)
		(net "GND")
	)
	(via
		(at 61.2061 97.6866)
		(size 0.4064)
		(drill 0.2032)
		(layers "F.Cu" "B.Cu")
		(tenting
			(front yes)
			(back yes)
		)
		(net "GND")
	)
	(via
		(at 65.2701 126.1346)
		(size 0.4064)
		(drill 0.2032)
		(layers "F.Cu" "B.Cu")
		(tenting
			(front yes)
			(back yes)
		)
		(net "GND")
	)
	(via
		(at 58.1581 144.4226)
		(size 0.4064)
		(drill 0.2032)
		(layers "F.Cu" "B.Cu")
		(tenting
			(front yes)
			(back yes)
		)
		(net "GND")
	)
	(via
		(at 66.7941 133.2466)
		(size 0.4064)
		(drill 0.2032)
		(layers "F.Cu" "B.Cu")
		(tenting
			(front yes)
			(back yes)
		)
		(net "GND")
	)
	(via
		(at 183.3761 87.0786)
		(size 0.4064)
		(drill 0.2032)
		(layers "F.Cu" "B.Cu")
		(tenting
			(front yes)
			(back yes)
		)
		(net "GND")
	)
	(via
		(at 65.7781 125.1186)
		(size 0.4064)
		(drill 0.2032)
		(layers "F.Cu" "B.Cu")
		(tenting
			(front yes)
			(back yes)
		)
		(net "GND")
	)
	(via
		(at 93.3761 87.13205)
		(size 0.4064)
		(drill 0.2032)
		(layers "F.Cu" "B.Cu")
		(tenting
			(front yes)
			(back yes)
		)
		(net "GND")
	)
	(via
		(at 169.8261 96.4036)
		(size 0.4064)
		(drill 0.2032)
		(layers "F.Cu" "B.Cu")
		(tenting
			(front yes)
			(back yes)
		)
		(net "GND")
	)
	(via
		(at 77.4621 128.1666)
		(size 0.4064)
		(drill 0.2032)
		(layers "F.Cu" "B.Cu")
		(tenting
			(front yes)
			(back yes)
		)
		(net "GND")
	)
	(via
		(at 72.3821 118.0066)
		(size 0.4064)
		(drill 0.2032)
		(layers "F.Cu" "B.Cu")
		(tenting
			(front yes)
			(back yes)
		)
		(net "GND")
	)
	(via
		(at 75.9381 125.1186)
		(size 0.4064)
		(drill 0.2032)
		(layers "F.Cu" "B.Cu")
		(tenting
			(front yes)
			(back yes)
		)
		(net "GND")
	)
	(via
		(at 208.0909 81.9544)
		(size 0.4064)
		(drill 0.2032)
		(layers "F.Cu" "B.Cu")
		(tenting
			(front yes)
			(back yes)
		)
		(net "GND")
	)
	(via
		(at 150.2339 122.2924)
		(size 0.4064)
		(drill 0.2032)
		(layers "F.Cu" "B.Cu")
		(tenting
			(front yes)
			(back yes)
		)
		(net "GND")
	)
	(via
		(at 68.8261 131.2146)
		(size 0.4064)
		(drill 0.2032)
		(layers "F.Cu" "B.Cu")
		(tenting
			(front yes)
			(back yes)
		)
		(net "GND")
	)
	(via
		(at 211.7261 92.2162)
		(size 0.4064)
		(drill 0.2032)
		(layers "F.Cu" "B.Cu")
		(tenting
			(front yes)
			(back yes)
		)
		(net "GND")
	)
	(via
		(at 167.49809 96.45661)
		(size 0.4064)
		(drill 0.2032)
		(layers "F.Cu" "B.Cu")
		(tenting
			(front yes)
			(back yes)
		)
		(net "GND")
	)
	(via
		(at 150.1831 117.028)
		(size 0.4064)
		(drill 0.2032)
		(layers "F.Cu" "B.Cu")
		(tenting
			(front yes)
			(back yes)
		)
		(net "GND")
	)
	(via
		(at 88.1261 81.1162)
		(size 0.4064)
		(drill 0.2032)
		(layers "F.Cu" "B.Cu")
		(tenting
			(front yes)
			(back yes)
		)
		(net "GND")
	)
	(via
		(at 68.8261 119.0226)
		(size 0.4064)
		(drill 0.2032)
		(layers "F.Cu" "B.Cu")
		(tenting
			(front yes)
			(back yes)
		)
		(net "GND")
	)
	(via
		(at 88.3761 67.8286)
		(size 0.4064)
		(drill 0.2032)
		(layers "F.Cu" "B.Cu")
		(tenting
			(front yes)
			(back yes)
		)
		(net "GND")
	)
	(via
		(at 66.2861 138.3266)
		(size 0.4064)
		(drill 0.2032)
		(layers "F.Cu" "B.Cu")
		(tenting
			(front yes)
			(back yes)
		)
		(net "GND")
	)
	(via
		(at 76.4461 140.3586)
		(size 0.4064)
		(drill 0.2032)
		(layers "F.Cu" "B.Cu")
		(tenting
			(front yes)
			(back yes)
		)
		(net "GND")
	)
	(via
		(at 71.1261 103.3662)
		(size 0.4064)
		(drill 0.2032)
		(layers "F.Cu" "B.Cu")
		(tenting
			(front yes)
			(back yes)
		)
		(net "GND")
	)
	(via
		(at 67.3021 91.5906)
		(size 0.4064)
		(drill 0.2032)
		(layers "F.Cu" "B.Cu")
		(tenting
			(front yes)
			(back yes)
		)
		(net "GND")
	)
	(via
		(at 225.2261 113.6162)
		(size 0.4064)
		(drill 0.2032)
		(layers "F.Cu" "B.Cu")
		(tenting
			(front yes)
			(back yes)
		)
		(net "GND")
	)
	(via
		(at 62.2221 103.7826)
		(size 0.4064)
		(drill 0.2032)
		(layers "F.Cu" "B.Cu")
		(tenting
			(front yes)
			(back yes)
		)
		(net "GND")
	)
	(via
		(at 71.8741 92.6066)
		(size 0.4064)
		(drill 0.2032)
		(layers "F.Cu" "B.Cu")
		(tenting
			(front yes)
			(back yes)
		)
		(net "GND")
	)
	(via
		(at 72.3821 91.5906)
		(size 0.4064)
		(drill 0.2032)
		(layers "F.Cu" "B.Cu")
		(tenting
			(front yes)
			(back yes)
		)
		(net "GND")
	)
	(via
		(at 75.4301 126.1346)
		(size 0.4064)
		(drill 0.2032)
		(layers "F.Cu" "B.Cu")
		(tenting
			(front yes)
			(back yes)
		)
		(net "GND")
	)
	(via
		(at 72.8901 114.9586)
		(size 0.4064)
		(drill 0.2032)
		(layers "F.Cu" "B.Cu")
		(tenting
			(front yes)
			(back yes)
		)
		(net "GND")
	)
	(via
		(at 70.8581 141.3746)
		(size 0.4064)
		(drill 0.2032)
		(layers "F.Cu" "B.Cu")
		(tenting
			(front yes)
			(back yes)
		)
		(net "GND")
	)
	(via
		(at 59.1741 103.7826)
		(size 0.4064)
		(drill 0.2032)
		(layers "F.Cu" "B.Cu")
		(tenting
			(front yes)
			(back yes)
		)
		(net "GND")
	)
	(via
		(at 56.6341 90.5746)
		(size 0.4064)
		(drill 0.2032)
		(layers "F.Cu" "B.Cu")
		(tenting
			(front yes)
			(back yes)
		)
		(net "GND")
	)
	(via
		(at 71.3661 144.4226)
		(size 0.4064)
		(drill 0.2032)
		(layers "F.Cu" "B.Cu")
		(tenting
			(front yes)
			(back yes)
		)
		(net "GND")
	)
	(via
		(at 210.6885 107.7423)
		(size 0.4064)
		(drill 0.2032)
		(layers "F.Cu" "B.Cu")
		(tenting
			(front yes)
			(back yes)
		)
		(net "GND")
	)
	(via
		(at 126.6261 85.8286)
		(size 0.4064)
		(drill 0.2032)
		(layers "F.Cu" "B.Cu")
		(tenting
			(front yes)
			(back yes)
		)
		(net "GND")
	)
	(via
		(at 77.4621 113.9426)
		(size 0.4064)
		(drill 0.2032)
		(layers "F.Cu" "B.Cu")
		(tenting
			(front yes)
			(back yes)
		)
		(net "GND")
	)
	(via
		(at 134.5511 154.1786)
		(size 0.4064)
		(drill 0.2032)
		(layers "F.Cu" "B.Cu")
		(tenting
			(front yes)
			(back yes)
		)
		(net "GND")
	)
	(via
		(at 61.7141 112.9266)
		(size 0.4064)
		(drill 0.2032)
		(layers "F.Cu" "B.Cu")
		(tenting
			(front yes)
			(back yes)
		)
		(net "GND")
	)
	(via
		(at 75.4301 111.9106)
		(size 0.4064)
		(drill 0.2032)
		(layers "F.Cu" "B.Cu")
		(tenting
			(front yes)
			(back yes)
		)
		(net "GND")
	)
	(via
		(at 183.3761 86.0786)
		(size 0.4064)
		(drill 0.2032)
		(layers "F.Cu" "B.Cu")
		(tenting
			(front yes)
			(back yes)
		)
		(net "GND")
	)
	(via
		(at 71.8741 137.3106)
		(size 0.4064)
		(drill 0.2032)
		(layers "F.Cu" "B.Cu")
		(tenting
			(front yes)
			(back yes)
		)
		(net "GND")
	)
	(via
		(at 72.3821 93.6226)
		(size 0.4064)
		(drill 0.2032)
		(layers "F.Cu" "B.Cu")
		(tenting
			(front yes)
			(back yes)
		)
		(net "GND")
	)
	(via
		(at 75.4301 128.1666)
		(size 0.4064)
		(drill 0.2032)
		(layers "F.Cu" "B.Cu")
		(tenting
			(front yes)
			(back yes)
		)
		(net "GND")
	)
	(via
		(at 61.2061 91.5906)
		(size 0.4064)
		(drill 0.2032)
		(layers "F.Cu" "B.Cu")
		(tenting
			(front yes)
			(back yes)
		)
		(net "GND")
	)
	(via
		(at 70.8581 92.6066)
		(size 0.4064)
		(drill 0.2032)
		(layers "F.Cu" "B.Cu")
		(tenting
			(front yes)
			(back yes)
		)
		(net "GND")
	)
	(via
		(at 60.6981 104.7986)
		(size 0.4064)
		(drill 0.2032)
		(layers "F.Cu" "B.Cu")
		(tenting
			(front yes)
			(back yes)
		)
		(net "GND")
	)
	(via
		(at 74.4141 140.3586)
		(size 0.4064)
		(drill 0.2032)
		(layers "F.Cu" "B.Cu")
		(tenting
			(front yes)
			(back yes)
		)
		(net "GND")
	)
	(via
		(at 76.9541 116.9906)
		(size 0.4064)
		(drill 0.2032)
		(layers "F.Cu" "B.Cu")
		(tenting
			(front yes)
			(back yes)
		)
		(net "GND")
	)
	(via
		(at 68.8261 141.3746)
		(size 0.4064)
		(drill 0.2032)
		(layers "F.Cu" "B.Cu")
		(tenting
			(front yes)
			(back yes)
		)
		(net "GND")
	)
	(via
		(at 150.35037 107.35152)
		(size 0.4064)
		(drill 0.2032)
		(layers "F.Cu" "B.Cu")
		(tenting
			(front yes)
			(back yes)
		)
		(net "GND")
	)
	(via
		(at 68.3181 132.2306)
		(size 0.4064)
		(drill 0.2032)
		(layers "F.Cu" "B.Cu")
		(tenting
			(front yes)
			(back yes)
		)
		(net "GND")
	)
	(via
		(at 177.3761 95.2286)
		(size 0.4064)
		(drill 0.2032)
		(layers "F.Cu" "B.Cu")
		(tenting
			(front yes)
			(back yes)
		)
		(net "GND")
	)
	(via
		(at 60.6981 112.9266)
		(size 0.4064)
		(drill 0.2032)
		(layers "F.Cu" "B.Cu")
		(tenting
			(front yes)
			(back yes)
		)
		(net "GND")
	)
	(via
		(at 219.1637 85.1662)
		(size 0.4064)
		(drill 0.2032)
		(layers "F.Cu" "B.Cu")
		(tenting
			(front yes)
			(back yes)
		)
		(net "GND")
	)
	(via
		(at 68.8261 98.7026)
		(size 0.4064)
		(drill 0.2032)
		(layers "F.Cu" "B.Cu")
		(tenting
			(front yes)
			(back yes)
		)
		(net "GND")
	)
	(via
		(at 170.4261 129.73857)
		(size 0.4064)
		(drill 0.2032)
		(layers "F.Cu" "B.Cu")
		(tenting
			(front yes)
			(back yes)
		)
		(net "GND")
	)
	(via
		(at 75.9381 114.9586)
		(size 0.4064)
		(drill 0.2032)
		(layers "F.Cu" "B.Cu")
		(tenting
			(front yes)
			(back yes)
		)
		(net "GND")
	)
	(via
		(at 196.6261 121.8286)
		(size 0.4064)
		(drill 0.2032)
		(layers "F.Cu" "B.Cu")
		(tenting
			(front yes)
			(back yes)
		)
		(net "GND")
	)
	(via
		(at 66.2861 93.6226)
		(size 0.4064)
		(drill 0.2032)
		(layers "F.Cu" "B.Cu")
		(tenting
			(front yes)
			(back yes)
		)
		(net "GND")
	)
	(via
		(at 74.9221 112.9266)
		(size 0.4064)
		(drill 0.2032)
		(layers "F.Cu" "B.Cu")
		(tenting
			(front yes)
			(back yes)
		)
		(net "GND")
	)
	(via
		(at 74.3761 97.6162)
		(size 0.4064)
		(drill 0.2032)
		(layers "F.Cu" "B.Cu")
		(tenting
			(front yes)
			(back yes)
		)
		(net "GND")
	)
	(via
		(at 68.3181 93.6226)
		(size 0.4064)
		(drill 0.2032)
		(layers "F.Cu" "B.Cu")
		(tenting
			(front yes)
			(back yes)
		)
		(net "GND")
	)
	(via
		(at 66.2861 91.5906)
		(size 0.4064)
		(drill 0.2032)
		(layers "F.Cu" "B.Cu")
		(tenting
			(front yes)
			(back yes)
		)
		(net "GND")
	)
	(via
		(at 151.57167 77.94847)
		(size 1.27)
		(drill 0.7112)
		(layers "F.Cu" "B.Cu")
		(net "GND")
	)
	(via
		(at 174.8761 95.2286)
		(size 0.4064)
		(drill 0.2032)
		(layers "F.Cu" "B.Cu")
		(tenting
			(front yes)
			(back yes)
		)
		(net "GND")
	)
	(via
		(at 63.2381 144.4226)
		(size 0.4064)
		(drill 0.2032)
		(layers "F.Cu" "B.Cu")
		(tenting
			(front yes)
			(back yes)
		)
		(net "GND")
	)
	(via
		(at 136.26304 116.53826)
		(size 0.4064)
		(drill 0.2032)
		(layers "F.Cu" "B.Cu")
		(tenting
			(front yes)
			(back yes)
		)
		(net "GND")
	)
	(via
		(at 83.8761 107.3662)
		(size 0.4064)
		(drill 0.2032)
		(layers "F.Cu" "B.Cu")
		(tenting
			(front yes)
			(back yes)
		)
		(net "GND")
	)
	(via
		(at 69.3341 103.7826)
		(size 0.4064)
		(drill 0.2032)
		(layers "F.Cu" "B.Cu")
		(tenting
			(front yes)
			(back yes)
		)
		(net "GND")
	)
	(via
		(at 66.2861 97.6866)
		(size 0.4064)
		(drill 0.2032)
		(layers "F.Cu" "B.Cu")
		(tenting
			(front yes)
			(back yes)
		)
		(net "GND")
	)
	(via
		(at 71.8741 114.9586)
		(size 0.4064)
		(drill 0.2032)
		(layers "F.Cu" "B.Cu")
		(tenting
			(front yes)
			(back yes)
		)
		(net "GND")
	)
	(via
		(at 183.3761 86.5786)
		(size 0.4064)
		(drill 0.2032)
		(layers "F.Cu" "B.Cu")
		(tenting
			(front yes)
			(back yes)
		)
		(net "GND")
	)
	(via
		(at 69.3341 97.6866)
		(size 0.4064)
		(drill 0.2032)
		(layers "F.Cu" "B.Cu")
		(tenting
			(front yes)
			(back yes)
		)
		(net "GND")
	)
	(via
		(at 72.8901 90.5746)
		(size 0.4064)
		(drill 0.2032)
		(layers "F.Cu" "B.Cu")
		(tenting
			(front yes)
			(back yes)
		)
		(net "GND")
	)
	(via
		(at 67.8101 119.0226)
		(size 0.4064)
		(drill 0.2032)
		(layers "F.Cu" "B.Cu")
		(tenting
			(front yes)
			(back yes)
		)
		(net "GND")
	)
	(via
		(at 67.8101 131.2146)
		(size 0.4064)
		(drill 0.2032)
		(layers "F.Cu" "B.Cu")
		(tenting
			(front yes)
			(back yes)
		)
		(net "GND")
	)
	(via
		(at 104.54612 154.36162)
		(size 0.4064)
		(drill 0.2032)
		(layers "F.Cu" "B.Cu")
		(tenting
			(front yes)
			(back yes)
		)
		(net "GND")
	)
	(via
		(at 149.1671 107.3064)
		(size 0.4064)
		(drill 0.2032)
		(layers "F.Cu" "B.Cu")
		(tenting
			(front yes)
			(back yes)
		)
		(net "GND")
	)
	(via
		(at 130.99597 154.1786)
		(size 0.4064)
		(drill 0.2032)
		(layers "F.Cu" "B.Cu")
		(tenting
			(front yes)
			(back yes)
		)
		(net "GND")
	)
	(via
		(at 67.3021 118.0066)
		(size 0.4064)
		(drill 0.2032)
		(layers "F.Cu" "B.Cu")
		(tenting
			(front yes)
			(back yes)
		)
		(net "GND")
	)
	(via
		(at 214.6885 117.9662)
		(size 0.4064)
		(drill 0.2032)
		(layers "F.Cu" "B.Cu")
		(tenting
			(front yes)
			(back yes)
		)
		(net "GND")
	)
	(via
		(at 150.3609 109.821)
		(size 0.4064)
		(drill 0.2032)
		(layers "F.Cu" "B.Cu")
		(tenting
			(front yes)
			(back yes)
		)
		(net "GND")
	)
	(via
		(at 61.2061 144.4226)
		(size 0.4064)
		(drill 0.2032)
		(layers "F.Cu" "B.Cu")
		(tenting
			(front yes)
			(back yes)
		)
		(net "GND")
	)
	(via
		(at 69.8421 131.2146)
		(size 0.4064)
		(drill 0.2032)
		(layers "F.Cu" "B.Cu")
		(tenting
			(front yes)
			(back yes)
		)
		(net "GND")
	)
	(via
		(at 67.3021 144.4226)
		(size 0.4064)
		(drill 0.2032)
		(layers "F.Cu" "B.Cu")
		(tenting
			(front yes)
			(back yes)
		)
		(net "GND")
	)
	(via
		(at 70.3501 93.6226)
		(size 0.4064)
		(drill 0.2032)
		(layers "F.Cu" "B.Cu")
		(tenting
			(front yes)
			(back yes)
		)
		(net "GND")
	)
	(via
		(at 76.9541 125.1186)
		(size 0.4064)
		(drill 0.2032)
		(layers "F.Cu" "B.Cu")
		(tenting
			(front yes)
			(back yes)
		)
		(net "GND")
	)
	(via
		(at 73.9061 114.9586)
		(size 0.4064)
		(drill 0.2032)
		(layers "F.Cu" "B.Cu")
		(tenting
			(front yes)
			(back yes)
		)
		(net "GND")
	)
	(via
		(at 61.2061 105.8146)
		(size 0.4064)
		(drill 0.2032)
		(layers "F.Cu" "B.Cu")
		(tenting
			(front yes)
			(back yes)
		)
		(net "GND")
	)
	(via
		(at 75.9381 90.5746)
		(size 0.4064)
		(drill 0.2032)
		(layers "F.Cu" "B.Cu")
		(tenting
			(front yes)
			(back yes)
		)
		(net "GND")
	)
	(via
		(at 149.1925 109.7956)
		(size 0.4064)
		(drill 0.2032)
		(layers "F.Cu" "B.Cu")
		(tenting
			(front yes)
			(back yes)
		)
		(net "GND")
	)
	(via
		(at 66.2861 126.1346)
		(size 0.4064)
		(drill 0.2032)
		(layers "F.Cu" "B.Cu")
		(tenting
			(front yes)
			(back yes)
		)
		(net "GND")
	)
	(via
		(at 69.3341 140.3586)
		(size 0.4064)
		(drill 0.2032)
		(layers "F.Cu" "B.Cu")
		(tenting
			(front yes)
			(back yes)
		)
		(net "GND")
	)
	(via
		(at 223.7637 88.7662)
		(size 0.4064)
		(drill 0.2032)
		(layers "F.Cu" "B.Cu")
		(tenting
			(front yes)
			(back yes)
		)
		(net "GND")
	)
	(via
		(at 82.3761 88.6162)
		(size 0.4064)
		(drill 0.2032)
		(layers "F.Cu" "B.Cu")
		(tenting
			(front yes)
			(back yes)
		)
		(net "GND")
	)
	(via
		(at 209.4261 92.1162)
		(size 0.4064)
		(drill 0.2032)
		(layers "F.Cu" "B.Cu")
		(tenting
			(front yes)
			(back yes)
		)
		(net "GND")
	)
	(via
		(at 75.4301 105.8146)
		(size 0.4064)
		(drill 0.2032)
		(layers "F.Cu" "B.Cu")
		(tenting
			(front yes)
			(back yes)
		)
		(net "GND")
	)
	(via
		(at 66.2861 120.0386)
		(size 0.4064)
		(drill 0.2032)
		(layers "F.Cu" "B.Cu")
		(tenting
			(front yes)
			(back yes)
		)
		(net "GND")
	)
	(via
		(at 76.4461 113.9426)
		(size 0.4064)
		(drill 0.2032)
		(layers "F.Cu" "B.Cu")
		(tenting
			(front yes)
			(back yes)
		)
		(net "GND")
	)
	(via
		(at 196.6261 119.6242)
		(size 0.4064)
		(drill 0.2032)
		(layers "F.Cu" "B.Cu")
		(tenting
			(front yes)
			(back yes)
		)
		(net "GND")
	)
	(via
		(at 66.7941 119.0226)
		(size 0.4064)
		(drill 0.2032)
		(layers "F.Cu" "B.Cu")
		(tenting
			(front yes)
			(back yes)
		)
		(net "GND")
	)
	(via
		(at 170.5261 134.1286)
		(size 0.4064)
		(drill 0.2032)
		(layers "F.Cu" "B.Cu")
		(tenting
			(front yes)
			(back yes)
		)
		(net "GND")
	)
	(via
		(at 61.2061 118.0066)
		(size 0.4064)
		(drill 0.2032)
		(layers "F.Cu" "B.Cu")
		(tenting
			(front yes)
			(back yes)
		)
		(net "GND")
	)
	(via
		(at 57.1421 103.7826)
		(size 0.4064)
		(drill 0.2032)
		(layers "F.Cu" "B.Cu")
		(tenting
			(front yes)
			(back yes)
		)
		(net "GND")
	)
	(via
		(at 77.4621 109.8786)
		(size 0.4064)
		(drill 0.2032)
		(layers "F.Cu" "B.Cu")
		(tenting
			(front yes)
			(back yes)
		)
		(net "GND")
	)
	(via
		(at 72.8901 112.9266)
		(size 0.4064)
		(drill 0.2032)
		(layers "F.Cu" "B.Cu")
		(tenting
			(front yes)
			(back yes)
		)
		(net "GND")
	)
	(via
		(at 76.4461 111.9106)
		(size 0.4064)
		(drill 0.2032)
		(layers "F.Cu" "B.Cu")
		(tenting
			(front yes)
			(back yes)
		)
		(net "GND")
	)
	(via
		(at 66.7941 110.8946)
		(size 0.4064)
		(drill 0.2032)
		(layers "F.Cu" "B.Cu")
		(tenting
			(front yes)
			(back yes)
		)
		(net "GND")
	)
	(via
		(at 70.3501 97.6866)
		(size 0.4064)
		(drill 0.2032)
		(layers "F.Cu" "B.Cu")
		(tenting
			(front yes)
			(back yes)
		)
		(net "GND")
	)
	(via
		(at 77.4621 126.1346)
		(size 0.4064)
		(drill 0.2032)
		(layers "F.Cu" "B.Cu")
		(tenting
			(front yes)
			(back yes)
		)
		(net "GND")
	)
	(via
		(at 67.3021 109.8786)
		(size 0.4064)
		(drill 0.2032)
		(layers "F.Cu" "B.Cu")
		(tenting
			(front yes)
			(back yes)
		)
		(net "GND")
	)
	(via
		(at 66.2861 118.0066)
		(size 0.4064)
		(drill 0.2032)
		(layers "F.Cu" "B.Cu")
		(tenting
			(front yes)
			(back yes)
		)
		(net "GND")
	)
	(via
		(at 56.6341 94.6386)
		(size 0.4064)
		(drill 0.2032)
		(layers "F.Cu" "B.Cu")
		(tenting
			(front yes)
			(back yes)
		)
		(net "GND")
	)
	(via
		(at 72.3821 120.0386)
		(size 0.4064)
		(drill 0.2032)
		(layers "F.Cu" "B.Cu")
		(tenting
			(front yes)
			(back yes)
		)
		(net "GND")
	)
	(via
		(at 72.8901 141.3746)
		(size 0.4064)
		(drill 0.2032)
		(layers "F.Cu" "B.Cu")
		(tenting
			(front yes)
			(back yes)
		)
		(net "GND")
	)
	(via
		(at 80.54375 100.66367)
		(size 0.4064)
		(drill 0.2032)
		(layers "F.Cu" "B.Cu")
		(tenting
			(front yes)
			(back yes)
		)
		(net "GND")
	)
	(via
		(at 68.3181 105.8146)
		(size 0.4064)
		(drill 0.2032)
		(layers "F.Cu" "B.Cu")
		(tenting
			(front yes)
			(back yes)
		)
		(net "GND")
	)
	(via
		(at 92.1261 76.2206)
		(size 0.4064)
		(drill 0.2032)
		(layers "F.Cu" "B.Cu")
		(tenting
			(front yes)
			(back yes)
		)
		(net "GND")
	)
	(via
		(at 206.0261 133.0162)
		(size 0.4064)
		(drill 0.2032)
		(layers "F.Cu" "B.Cu")
		(tenting
			(front yes)
			(back yes)
		)
		(net "GND")
	)
	(via
		(at 66.2861 144.4226)
		(size 0.4064)
		(drill 0.2032)
		(layers "F.Cu" "B.Cu")
		(tenting
			(front yes)
			(back yes)
		)
		(net "GND")
	)
	(via
		(at 69.3341 134.2626)
		(size 0.4064)
		(drill 0.2032)
		(layers "F.Cu" "B.Cu")
		(tenting
			(front yes)
			(back yes)
		)
		(net "GND")
	)
	(via
		(at 66.2861 111.9106)
		(size 0.4064)
		(drill 0.2032)
		(layers "F.Cu" "B.Cu")
		(tenting
			(front yes)
			(back yes)
		)
		(net "GND")
	)
	(via
		(at 74.9221 141.3746)
		(size 0.4064)
		(drill 0.2032)
		(layers "F.Cu" "B.Cu")
		(tenting
			(front yes)
			(back yes)
		)
		(net "GND")
	)
	(via
		(at 72.3821 144.4226)
		(size 0.4064)
		(drill 0.2032)
		(layers "F.Cu" "B.Cu")
		(tenting
			(front yes)
			(back yes)
		)
		(net "GND")
	)
	(via
		(at 85.1261 120.8662)
		(size 0.4064)
		(drill 0.2032)
		(layers "F.Cu" "B.Cu")
		(tenting
			(front yes)
			(back yes)
		)
		(net "GND")
	)
	(via
		(at 75.4301 132.2306)
		(size 0.4064)
		(drill 0.2032)
		(layers "F.Cu" "B.Cu")
		(tenting
			(front yes)
			(back yes)
		)
		(net "GND")
	)
	(via
		(at 72.8901 139.3426)
		(size 0.4064)
		(drill 0.2032)
		(layers "F.Cu" "B.Cu")
		(tenting
			(front yes)
			(back yes)
		)
		(net "GND")
	)
	(via
		(at 67.3021 103.7826)
		(size 0.4064)
		(drill 0.2032)
		(layers "F.Cu" "B.Cu")
		(tenting
			(front yes)
			(back yes)
		)
		(net "GND")
	)
	(via
		(at 90.4761 87.1162)
		(size 0.5)
		(drill 0.2)
		(layers "F.Cu" "B.Cu")
		(net "GND")
	)
	(via
		(at 177.4261 129.7286)
		(size 0.4064)
		(drill 0.2032)
		(layers "F.Cu" "B.Cu")
		(tenting
			(front yes)
			(back yes)
		)
		(net "GND")
	)
	(via
		(at 70.3501 138.3266)
		(size 0.4064)
		(drill 0.2032)
		(layers "F.Cu" "B.Cu")
		(tenting
			(front yes)
			(back yes)
		)
		(net "GND")
	)
	(via
		(at 66.7941 104.7986)
		(size 0.4064)
		(drill 0.2032)
		(layers "F.Cu" "B.Cu")
		(tenting
			(front yes)
			(back yes)
		)
		(net "GND")
	)
	(via
		(at 66.7941 96.6706)
		(size 0.4064)
		(drill 0.2032)
		(layers "F.Cu" "B.Cu")
		(tenting
			(front yes)
			(back yes)
		)
		(net "GND")
	)
	(via
		(at 71.8741 119.0226)
		(size 0.4064)
		(drill 0.2032)
		(layers "F.Cu" "B.Cu")
		(tenting
			(front yes)
			(back yes)
		)
		(net "GND")
	)
	(via
		(at 60.1901 103.7826)
		(size 0.4064)
		(drill 0.2032)
		(layers "F.Cu" "B.Cu")
		(tenting
			(front yes)
			(back yes)
		)
		(net "GND")
	)
	(via
		(at 72.3821 111.9106)
		(size 0.4064)
		(drill 0.2032)
		(layers "F.Cu" "B.Cu")
		(tenting
			(front yes)
			(back yes)
		)
		(net "GND")
	)
	(via
		(at 73.9061 139.3426)
		(size 0.4064)
		(drill 0.2032)
		(layers "F.Cu" "B.Cu")
		(tenting
			(front yes)
			(back yes)
		)
		(net "GND")
	)
	(via
		(at 66.7941 98.7026)
		(size 0.4064)
		(drill 0.2032)
		(layers "F.Cu" "B.Cu")
		(tenting
			(front yes)
			(back yes)
		)
		(net "GND")
	)
	(via
		(at 71.8741 110.8946)
		(size 0.4064)
		(drill 0.2032)
		(layers "F.Cu" "B.Cu")
		(tenting
			(front yes)
			(back yes)
		)
		(net "GND")
	)
	(via
		(at 69.8421 104.7986)
		(size 0.4064)
		(drill 0.2032)
		(layers "F.Cu" "B.Cu")
		(tenting
			(front yes)
			(back yes)
		)
		(net "GND")
	)
	(via
		(at 60.6981 98.7026)
		(size 0.4064)
		(drill 0.2032)
		(layers "F.Cu" "B.Cu")
		(tenting
			(front yes)
			(back yes)
		)
		(net "GND")
	)
	(via
		(at 65.7781 116.9906)
		(size 0.4064)
		(drill 0.2032)
		(layers "F.Cu" "B.Cu")
		(tenting
			(front yes)
			(back yes)
		)
		(net "GND")
	)
	(via
		(at 64.2541 144.4226)
		(size 0.4064)
		(drill 0.2032)
		(layers "F.Cu" "B.Cu")
		(tenting
			(front yes)
			(back yes)
		)
		(net "GND")
	)
	(via
		(at 74.4141 113.9426)
		(size 0.4064)
		(drill 0.2032)
		(layers "F.Cu" "B.Cu")
		(tenting
			(front yes)
			(back yes)
		)
		(net "GND")
	)
	(via
		(at 76.9541 112.9266)
		(size 0.4064)
		(drill 0.2032)
		(layers "F.Cu" "B.Cu")
		(tenting
			(front yes)
			(back yes)
		)
		(net "GND")
	)
	(via
		(at 180.3261 129.7286)
		(size 0.4064)
		(drill 0.2032)
		(layers "F.Cu" "B.Cu")
		(tenting
			(front yes)
			(back yes)
		)
		(net "GND")
	)
	(via
		(at 65.7781 112.9266)
		(size 0.4064)
		(drill 0.2032)
		(layers "F.Cu" "B.Cu")
		(tenting
			(front yes)
			(back yes)
		)
		(net "GND")
	)
	(via
		(at 215.0261 92.2162)
		(size 0.4064)
		(drill 0.2032)
		(layers "F.Cu" "B.Cu")
		(tenting
			(front yes)
			(back yes)
		)
		(net "GND")
	)
	(via
		(at 71.8741 125.1186)
		(size 0.4064)
		(drill 0.2032)
		(layers "F.Cu" "B.Cu")
		(tenting
			(front yes)
			(back yes)
		)
		(net "GND")
	)
	(via
		(at 84.8761 134.8662)
		(size 0.4064)
		(drill 0.2032)
		(layers "F.Cu" "B.Cu")
		(tenting
			(front yes)
			(back yes)
		)
		(net "GND")
	)
	(via
		(at 191.6261 90.0786)
		(size 0.4064)
		(drill 0.2032)
		(layers "F.Cu" "B.Cu")
		(tenting
			(front yes)
			(back yes)
		)
		(net "GND")
	)
	(via
		(at 207.0967 88.7472)
		(size 0.4064)
		(drill 0.2032)
		(layers "F.Cu" "B.Cu")
		(tenting
			(front yes)
			(back yes)
		)
		(net "GND")
	)
	(via
		(at 67.8101 123.0866)
		(size 0.4064)
		(drill 0.2032)
		(layers "F.Cu" "B.Cu")
		(tenting
			(front yes)
			(back yes)
		)
		(net "GND")
	)
	(via
		(at 75.9381 139.3426)
		(size 0.4064)
		(drill 0.2032)
		(layers "F.Cu" "B.Cu")
		(tenting
			(front yes)
			(back yes)
		)
		(net "GND")
	)
	(via
		(at 68.8261 90.5746)
		(size 0.4064)
		(drill 0.2032)
		(layers "F.Cu" "B.Cu")
		(tenting
			(front yes)
			(back yes)
		)
		(net "GND")
	)
	(via
		(at 136.3261 115.0162)
		(size 0.4064)
		(drill 0.2032)
		(layers "F.Cu" "B.Cu")
		(tenting
			(front yes)
			(back yes)
		)
		(net "GND")
	)
	(via
		(at 226.1261 113.6162)
		(size 0.4064)
		(drill 0.2032)
		(layers "F.Cu" "B.Cu")
		(tenting
			(front yes)
			(back yes)
		)
		(net "GND")
	)
	(via
		(at 70.3501 144.4226)
		(size 0.4064)
		(drill 0.2032)
		(layers "F.Cu" "B.Cu")
		(tenting
			(front yes)
			(back yes)
		)
		(net "GND")
	)
	(via
		(at 118.03129 154.41678)
		(size 0.4064)
		(drill 0.2032)
		(layers "F.Cu" "B.Cu")
		(tenting
			(front yes)
			(back yes)
		)
		(net "GND")
	)
	(via
		(at 65.7781 90.5746)
		(size 0.4064)
		(drill 0.2032)
		(layers "F.Cu" "B.Cu")
		(tenting
			(front yes)
			(back yes)
		)
		(net "GND")
	)
	(via
		(at 66.7941 116.9906)
		(size 0.4064)
		(drill 0.2032)
		(layers "F.Cu" "B.Cu")
		(tenting
			(front yes)
			(back yes)
		)
		(net "GND")
	)
	(via
		(at 73.9061 90.5746)
		(size 0.4064)
		(drill 0.2032)
		(layers "F.Cu" "B.Cu")
		(tenting
			(front yes)
			(back yes)
		)
		(net "GND")
	)
	(via
		(at 196.6261 114.3206)
		(size 0.4064)
		(drill 0.2032)
		(layers "F.Cu" "B.Cu")
		(tenting
			(front yes)
			(back yes)
		)
		(net "GND")
	)
	(via
		(at 216.2885 117.9662)
		(size 0.4064)
		(drill 0.2032)
		(layers "F.Cu" "B.Cu")
		(tenting
			(front yes)
			(back yes)
		)
		(net "GND")
	)
	(via
		(at 76.4461 91.5906)
		(size 0.4064)
		(drill 0.2032)
		(layers "F.Cu" "B.Cu")
		(tenting
			(front yes)
			(back yes)
		)
		(net "GND")
	)
	(via
		(at 66.2861 134.2626)
		(size 0.4064)
		(drill 0.2032)
		(layers "F.Cu" "B.Cu")
		(tenting
			(front yes)
			(back yes)
		)
		(net "GND")
	)
	(via
		(at 73.3981 111.9106)
		(size 0.4064)
		(drill 0.2032)
		(layers "F.Cu" "B.Cu")
		(tenting
			(front yes)
			(back yes)
		)
		(net "GND")
	)
	(via
		(at 149.11137 116.98213)
		(size 0.4064)
		(drill 0.2032)
		(layers "F.Cu" "B.Cu")
		(tenting
			(front yes)
			(back yes)
		)
		(net "GND")
	)
	(via
		(at 66.7941 92.6066)
		(size 0.4064)
		(drill 0.2032)
		(layers "F.Cu" "B.Cu")
		(tenting
			(front yes)
			(back yes)
		)
		(net "GND")
	)
	(via
		(at 67.8101 106.8306)
		(size 0.4064)
		(drill 0.2032)
		(layers "F.Cu" "B.Cu")
		(tenting
			(front yes)
			(back yes)
		)
		(net "GND")
	)
	(via
		(at 180.4261 134.0286)
		(size 0.4064)
		(drill 0.2032)
		(layers "F.Cu" "B.Cu")
		(tenting
			(front yes)
			(back yes)
		)
		(net "GND")
	)
	(via
		(at 76.4461 109.8786)
		(size 0.4064)
		(drill 0.2032)
		(layers "F.Cu" "B.Cu")
		(tenting
			(front yes)
			(back yes)
		)
		(net "GND")
	)
	(via
		(at 68.8261 121.0546)
		(size 0.4064)
		(drill 0.2032)
		(layers "F.Cu" "B.Cu")
		(tenting
			(front yes)
			(back yes)
		)
		(net "GND")
	)
	(via
		(at 76.9541 110.8946)
		(size 0.4064)
		(drill 0.2032)
		(layers "F.Cu" "B.Cu")
		(tenting
			(front yes)
			(back yes)
		)
		(net "GND")
	)
	(via
		(at 172.83584 134.15826)
		(size 0.4064)
		(drill 0.2032)
		(layers "F.Cu" "B.Cu")
		(tenting
			(front yes)
			(back yes)
		)
		(net "GND")
	)
	(via
		(at 76.9541 141.3746)
		(size 0.4064)
		(drill 0.2032)
		(layers "F.Cu" "B.Cu")
		(tenting
			(front yes)
			(back yes)
		)
		(net "GND")
	)
	(via
		(at 69.8421 92.6066)
		(size 0.4064)
		(drill 0.2032)
		(layers "F.Cu" "B.Cu")
		(tenting
			(front yes)
			(back yes)
		)
		(net "GND")
	)
	(via
		(at 114.5461 154.3286)
		(size 0.4064)
		(drill 0.2032)
		(layers "F.Cu" "B.Cu")
		(tenting
			(front yes)
			(back yes)
		)
		(net "GND")
	)
	(via
		(at 150.2847 112.3102)
		(size 0.4064)
		(drill 0.2032)
		(layers "F.Cu" "B.Cu")
		(tenting
			(front yes)
			(back yes)
		)
		(net "GND")
	)
	(via
		(at 67.8101 92.6066)
		(size 0.4064)
		(drill 0.2032)
		(layers "F.Cu" "B.Cu")
		(tenting
			(front yes)
			(back yes)
		)
		(net "GND")
	)
	(via
		(at 67.3021 124.1026)
		(size 0.4064)
		(drill 0.2032)
		(layers "F.Cu" "B.Cu")
		(tenting
			(front yes)
			(back yes)
		)
		(net "GND")
	)
	(via
		(at 72.3821 140.3586)
		(size 0.4064)
		(drill 0.2032)
		(layers "F.Cu" "B.Cu")
		(tenting
			(front yes)
			(back yes)
		)
		(net "GND")
	)
	(via
		(at 71.8741 133.2466)
		(size 0.4064)
		(drill 0.2032)
		(layers "F.Cu" "B.Cu")
		(tenting
			(front yes)
			(back yes)
		)
		(net "GND")
	)
	(via
		(at 212.0885 117.9662)
		(size 0.4064)
		(drill 0.2032)
		(layers "F.Cu" "B.Cu")
		(tenting
			(front yes)
			(back yes)
		)
		(net "GND")
	)
	(via
		(at 69.3341 142.3906)
		(size 0.4064)
		(drill 0.2032)
		(layers "F.Cu" "B.Cu")
		(tenting
			(front yes)
			(back yes)
		)
		(net "GND")
	)
	(via
		(at 79.3761 112.8662)
		(size 0.4064)
		(drill 0.2032)
		(layers "F.Cu" "B.Cu")
		(tenting
			(front yes)
			(back yes)
		)
		(net "GND")
	)
	(via
		(at 68.8261 129.1826)
		(size 0.4064)
		(drill 0.2032)
		(layers "F.Cu" "B.Cu")
		(tenting
			(front yes)
			(back yes)
		)
		(net "GND")
	)
	(via
		(at 67.3021 134.2626)
		(size 0.4064)
		(drill 0.2032)
		(layers "F.Cu" "B.Cu")
		(tenting
			(front yes)
			(back yes)
		)
		(net "GND")
	)
	(via
		(at 71.8741 90.5746)
		(size 0.4064)
		(drill 0.2032)
		(layers "F.Cu" "B.Cu")
		(tenting
			(front yes)
			(back yes)
		)
		(net "GND")
	)
	(via
		(at 70.3501 142.3906)
		(size 0.4064)
		(drill 0.2032)
		(layers "F.Cu" "B.Cu")
		(tenting
			(front yes)
			(back yes)
		)
		(net "GND")
	)
	(via
		(at 75.4301 140.3586)
		(size 0.4064)
		(drill 0.2032)
		(layers "F.Cu" "B.Cu")
		(tenting
			(front yes)
			(back yes)
		)
		(net "GND")
	)
	(via
		(at 179.7931 95.22841)
		(size 0.4064)
		(drill 0.2032)
		(layers "F.Cu" "B.Cu")
		(tenting
			(front yes)
			(back yes)
		)
		(net "GND")
	)
	(via
		(at 68.3181 124.1026)
		(size 0.4064)
		(drill 0.2032)
		(layers "F.Cu" "B.Cu")
		(tenting
			(front yes)
			(back yes)
		)
		(net "GND")
	)
	(via
		(at 66.2861 124.1026)
		(size 0.4064)
		(drill 0.2032)
		(layers "F.Cu" "B.Cu")
		(tenting
			(front yes)
			(back yes)
		)
		(net "GND")
	)
	(via
		(at 211.2261 92.2162)
		(size 0.4064)
		(drill 0.2032)
		(layers "F.Cu" "B.Cu")
		(tenting
			(front yes)
			(back yes)
		)
		(net "GND")
	)
	(via
		(at 131.6261 89.8742)
		(size 0.4064)
		(drill 0.2032)
		(layers "F.Cu" "B.Cu")
		(tenting
			(front yes)
			(back yes)
		)
		(net "GND")
	)
	(via
		(at 67.3021 138.3266)
		(size 0.4064)
		(drill 0.2032)
		(layers "F.Cu" "B.Cu")
		(tenting
			(front yes)
			(back yes)
		)
		(net "GND")
	)
	(via
		(at 77.4621 118.0066)
		(size 0.4064)
		(drill 0.2032)
		(layers "F.Cu" "B.Cu")
		(tenting
			(front yes)
			(back yes)
		)
		(net "GND")
	)
	(via
		(at 76.4461 126.1346)
		(size 0.4064)
		(drill 0.2032)
		(layers "F.Cu" "B.Cu")
		(tenting
			(front yes)
			(back yes)
		)
		(net "GND")
	)
	(via
		(at 69.8421 133.2466)
		(size 0.4064)
		(drill 0.2032)
		(layers "F.Cu" "B.Cu")
		(tenting
			(front yes)
			(back yes)
		)
		(net "GND")
	)
	(via
		(at 71.3661 138.3266)
		(size 0.4064)
		(drill 0.2032)
		(layers "F.Cu" "B.Cu")
		(tenting
			(front yes)
			(back yes)
		)
		(net "GND")
	)
	(via
		(at 58.1581 122.0706)
		(size 0.4064)
		(drill 0.2032)
		(layers "F.Cu" "B.Cu")
		(tenting
			(front yes)
			(back yes)
		)
		(net "GND")
	)
	(via
		(at 68.8261 114.9586)
		(size 0.4064)
		(drill 0.2032)
		(layers "F.Cu" "B.Cu")
		(tenting
			(front yes)
			(back yes)
		)
		(net "GND")
	)
	(via
		(at 68.8261 137.3106)
		(size 0.4064)
		(drill 0.2032)
		(layers "F.Cu" "B.Cu")
		(tenting
			(front yes)
			(back yes)
		)
		(net "GND")
	)
	(via
		(at 68.8261 92.6066)
		(size 0.4064)
		(drill 0.2032)
		(layers "F.Cu" "B.Cu")
		(tenting
			(front yes)
			(back yes)
		)
		(net "GND")
	)
	(via
		(at 77.4621 138.3266)
		(size 0.4064)
		(drill 0.2032)
		(layers "F.Cu" "B.Cu")
		(tenting
			(front yes)
			(back yes)
		)
		(net "GND")
	)
	(via
		(at 75.4301 118.0066)
		(size 0.4064)
		(drill 0.2032)
		(layers "F.Cu" "B.Cu")
		(tenting
			(front yes)
			(back yes)
		)
		(net "GND")
	)
	(via
		(at 60.1901 118.0066)
		(size 0.4064)
		(drill 0.2032)
		(layers "F.Cu" "B.Cu")
		(tenting
			(front yes)
			(back yes)
		)
		(net "GND")
	)
	(via
		(at 65.7781 131.2146)
		(size 0.4064)
		(drill 0.2032)
		(layers "F.Cu" "B.Cu")
		(tenting
			(front yes)
			(back yes)
		)
		(net "GND")
	)
	(via
		(at 198.1261 111.8286)
		(size 0.4064)
		(drill 0.2032)
		(layers "F.Cu" "B.Cu")
		(tenting
			(front yes)
			(back yes)
		)
		(net "GND")
	)
	(via
		(at 76.4461 128.1666)
		(size 0.4064)
		(drill 0.2032)
		(layers "F.Cu" "B.Cu")
		(tenting
			(front yes)
			(back yes)
		)
		(net "GND")
	)
	(via
		(at 77.4621 140.3586)
		(size 0.4064)
		(drill 0.2032)
		(layers "F.Cu" "B.Cu")
		(tenting
			(front yes)
			(back yes)
		)
		(net "GND")
	)
	(via
		(at 85.8761 81.1162)
		(size 0.4064)
		(drill 0.2032)
		(layers "F.Cu" "B.Cu")
		(tenting
			(front yes)
			(back yes)
		)
		(net "GND")
	)
	(via
		(at 88.2761 86.0162)
		(size 0.5)
		(drill 0.2)
		(layers "F.Cu" "B.Cu")
		(net "GND")
	)
	(via
		(at 67.3021 111.9106)
		(size 0.4064)
		(drill 0.2032)
		(layers "F.Cu" "B.Cu")
		(tenting
			(front yes)
			(back yes)
		)
		(net "GND")
	)
	(via
		(at 143.16077 114.8267)
		(size 0.4064)
		(drill 0.2032)
		(layers "F.Cu" "B.Cu")
		(net "GND")
	)
	(via
		(at 188.6261 90.0786)
		(size 0.4064)
		(drill 0.2032)
		(layers "F.Cu" "B.Cu")
		(tenting
			(front yes)
			(back yes)
		)
		(net "GND")
	)
	(via
		(at 74.3761 111.1162)
		(size 0.4064)
		(drill 0.2032)
		(layers "F.Cu" "B.Cu")
		(tenting
			(front yes)
			(back yes)
		)
		(net "GND")
	)
	(via
		(at 72.3821 142.3906)
		(size 0.4064)
		(drill 0.2032)
		(layers "F.Cu" "B.Cu")
		(tenting
			(front yes)
			(back yes)
		)
		(net "GND")
	)
	(via
		(at 66.7941 129.1826)
		(size 0.4064)
		(drill 0.2032)
		(layers "F.Cu" "B.Cu")
		(tenting
			(front yes)
			(back yes)
		)
		(net "GND")
	)
	(via
		(at 71.3661 91.5906)
		(size 0.4064)
		(drill 0.2032)
		(layers "F.Cu" "B.Cu")
		(tenting
			(front yes)
			(back yes)
		)
		(net "GND")
	)
	(via
		(at 221.3681 64.6162)
		(size 0.4064)
		(drill 0.2032)
		(layers "F.Cu" "B.Cu")
		(tenting
			(front yes)
			(back yes)
		)
		(net "GND")
	)
	(via
		(at 128.3761 86.8286)
		(size 0.4064)
		(drill 0.2032)
		(layers "F.Cu" "B.Cu")
		(tenting
			(front yes)
			(back yes)
		)
		(net "GND")
	)
	(via
		(at 57.6501 135.2786)
		(size 0.4064)
		(drill 0.2032)
		(layers "F.Cu" "B.Cu")
		(tenting
			(front yes)
			(back yes)
		)
		(net "GND")
	)
	(via
		(at 223.7637 90.9662)
		(size 0.4064)
		(drill 0.2032)
		(layers "F.Cu" "B.Cu")
		(tenting
			(front yes)
			(back yes)
		)
		(net "GND")
	)
	(via
		(at 76.4461 103.7826)
		(size 0.4064)
		(drill 0.2032)
		(layers "F.Cu" "B.Cu")
		(tenting
			(front yes)
			(back yes)
		)
		(net "GND")
	)
	(via
		(at 226.6261 71.3662)
		(size 0.4064)
		(drill 0.2032)
		(layers "F.Cu" "B.Cu")
		(tenting
			(front yes)
			(back yes)
		)
		(net "GND")
	)
	(via
		(at 150.3761 114.8662)
		(size 0.4064)
		(drill 0.2032)
		(layers "F.Cu" "B.Cu")
		(tenting
			(front yes)
			(back yes)
		)
		(net "GND")
	)
	(via
		(at 66.2861 109.8786)
		(size 0.4064)
		(drill 0.2032)
		(layers "F.Cu" "B.Cu")
		(tenting
			(front yes)
			(back yes)
		)
		(net "GND")
	)
	(via
		(at 66.7941 139.3426)
		(size 0.4064)
		(drill 0.2032)
		(layers "F.Cu" "B.Cu")
		(tenting
			(front yes)
			(back yes)
		)
		(net "GND")
	)
	(via
		(at 75.9381 116.9906)
		(size 0.4064)
		(drill 0.2032)
		(layers "F.Cu" "B.Cu")
		(tenting
			(front yes)
			(back yes)
		)
		(net "GND")
	)
	(via
		(at 67.8101 125.1186)
		(size 0.4064)
		(drill 0.2032)
		(layers "F.Cu" "B.Cu")
		(tenting
			(front yes)
			(back yes)
		)
		(net "GND")
	)
	(via
		(at 75.9381 129.1826)
		(size 0.4064)
		(drill 0.2032)
		(layers "F.Cu" "B.Cu")
		(tenting
			(front yes)
			(back yes)
		)
		(net "GND")
	)
	(via
		(at 70.8581 90.5746)
		(size 0.4064)
		(drill 0.2032)
		(layers "F.Cu" "B.Cu")
		(tenting
			(front yes)
			(back yes)
		)
		(net "GND")
	)
	(via
		(at 66.2861 132.2306)
		(size 0.4064)
		(drill 0.2032)
		(layers "F.Cu" "B.Cu")
		(tenting
			(front yes)
			(back yes)
		)
		(net "GND")
	)
	(via
		(at 76.9541 123.0866)
		(size 0.4064)
		(drill 0.2032)
		(layers "F.Cu" "B.Cu")
		(tenting
			(front yes)
			(back yes)
		)
		(net "GND")
	)
	(via
		(at 75.9381 141.3746)
		(size 0.4064)
		(drill 0.2032)
		(layers "F.Cu" "B.Cu")
		(tenting
			(front yes)
			(back yes)
		)
		(net "GND")
	)
	(via
		(at 65.7781 123.0866)
		(size 0.4064)
		(drill 0.2032)
		(layers "F.Cu" "B.Cu")
		(tenting
			(front yes)
			(back yes)
		)
		(net "GND")
	)
	(via
		(at 75.9381 119.0226)
		(size 0.4064)
		(drill 0.2032)
		(layers "F.Cu" "B.Cu")
		(tenting
			(front yes)
			(back yes)
		)
		(net "GND")
	)
	(via
		(at 72.3821 109.8786)
		(size 0.4064)
		(drill 0.2032)
		(layers "F.Cu" "B.Cu")
		(tenting
			(front yes)
			(back yes)
		)
		(net "GND")
	)
	(via
		(at 215.5261 92.2162)
		(size 0.4064)
		(drill 0.2032)
		(layers "F.Cu" "B.Cu")
		(tenting
			(front yes)
			(back yes)
		)
		(net "GND")
	)
	(via
		(at 149.0909 119.8286)
		(size 0.4064)
		(drill 0.2032)
		(layers "F.Cu" "B.Cu")
		(tenting
			(front yes)
			(back yes)
		)
		(net "GND")
	)
	(via
		(at 71.8741 139.3426)
		(size 0.4064)
		(drill 0.2032)
		(layers "F.Cu" "B.Cu")
		(tenting
			(front yes)
			(back yes)
		)
		(net "GND")
	)
	(via
		(at 122.6261 89.0866)
		(size 0.4064)
		(drill 0.2032)
		(layers "F.Cu" "B.Cu")
		(tenting
			(front yes)
			(back yes)
		)
		(net "GND")
	)
	(via
		(at 128.3761 86.0786)
		(size 0.4064)
		(drill 0.2032)
		(layers "F.Cu" "B.Cu")
		(tenting
			(front yes)
			(back yes)
		)
		(net "GND")
	)
	(via
		(at 179.7931 96.39385)
		(size 0.4064)
		(drill 0.2032)
		(layers "F.Cu" "B.Cu")
		(tenting
			(front yes)
			(back yes)
		)
		(net "GND")
	)
	(via
		(at 209.4095 115.2902)
		(size 0.4064)
		(drill 0.2032)
		(layers "F.Cu" "B.Cu")
		(tenting
			(front yes)
			(back yes)
		)
		(net "GND")
	)
	(via
		(at 71.3661 93.6226)
		(size 0.4064)
		(drill 0.2032)
		(layers "F.Cu" "B.Cu")
		(tenting
			(front yes)
			(back yes)
		)
		(net "GND")
	)
	(via
		(at 76.9541 131.2146)
		(size 0.4064)
		(drill 0.2032)
		(layers "F.Cu" "B.Cu")
		(tenting
			(front yes)
			(back yes)
		)
		(net "GND")
	)
	(via
		(at 169.9761 95.2286)
		(size 0.4064)
		(drill 0.2032)
		(layers "F.Cu" "B.Cu")
		(tenting
			(front yes)
			(back yes)
		)
		(net "GND")
	)
	(via
		(at 67.8101 98.7026)
		(size 0.4064)
		(drill 0.2032)
		(layers "F.Cu" "B.Cu")
		(tenting
			(front yes)
			(back yes)
		)
		(net "GND")
	)
	(via
		(at 165.32613 129.72863)
		(size 0.4064)
		(drill 0.2032)
		(layers "F.Cu" "B.Cu")
		(tenting
			(front yes)
			(back yes)
		)
		(net "GND")
	)
	(via
		(at 56.6341 108.8626)
		(size 0.4064)
		(drill 0.2032)
		(layers "F.Cu" "B.Cu")
		(tenting
			(front yes)
			(back yes)
		)
		(net "GND")
	)
	(via
		(at 74.3761 119.3662)
		(size 0.4064)
		(drill 0.2032)
		(layers "F.Cu" "B.Cu")
		(tenting
			(front yes)
			(back yes)
		)
		(net "GND")
	)
	(via
		(at 65.2701 103.7826)
		(size 0.4064)
		(drill 0.2032)
		(layers "F.Cu" "B.Cu")
		(tenting
			(front yes)
			(back yes)
		)
		(net "GND")
	)
	(via
		(at 201.5087 83.0068)
		(size 0.4064)
		(drill 0.2032)
		(layers "F.Cu" "B.Cu")
		(tenting
			(front yes)
			(back yes)
		)
		(net "GND")
	)
	(via
		(at 65.7781 106.8306)
		(size 0.4064)
		(drill 0.2032)
		(layers "F.Cu" "B.Cu")
		(tenting
			(front yes)
			(back yes)
		)
		(net "GND")
	)
	(via
		(at 71.3661 142.3906)
		(size 0.4064)
		(drill 0.2032)
		(layers "F.Cu" "B.Cu")
		(tenting
			(front yes)
			(back yes)
		)
		(net "GND")
	)
	(via
		(at 67.8101 96.6706)
		(size 0.4064)
		(drill 0.2032)
		(layers "F.Cu" "B.Cu")
		(tenting
			(front yes)
			(back yes)
		)
		(net "GND")
	)
	(via
		(at 76.4461 142.3906)
		(size 0.4064)
		(drill 0.2032)
		(layers "F.Cu" "B.Cu")
		(tenting
			(front yes)
			(back yes)
		)
		(net "GND")
	)
	(via
		(at 165.4261 134.1286)
		(size 0.4064)
		(drill 0.2032)
		(layers "F.Cu" "B.Cu")
		(tenting
			(front yes)
			(back yes)
		)
		(net "GND")
	)
	(via
		(at 174.8091 96.4036)
		(size 0.4064)
		(drill 0.2032)
		(layers "F.Cu" "B.Cu")
		(tenting
			(front yes)
			(back yes)
		)
		(net "GND")
	)
	(via
		(at 122.8527 154.2818)
		(size 0.4064)
		(drill 0.2032)
		(layers "F.Cu" "B.Cu")
		(tenting
			(front yes)
			(back yes)
		)
		(net "GND")
	)
	(via
		(at 67.8101 114.9586)
		(size 0.4064)
		(drill 0.2032)
		(layers "F.Cu" "B.Cu")
		(tenting
			(front yes)
			(back yes)
		)
		(net "GND")
	)
	(via
		(at 69.8421 90.5746)
		(size 0.4064)
		(drill 0.2032)
		(layers "F.Cu" "B.Cu")
		(tenting
			(front yes)
			(back yes)
		)
		(net "GND")
	)
	(via
		(at 72.3821 113.9426)
		(size 0.4064)
		(drill 0.2032)
		(layers "F.Cu" "B.Cu")
		(tenting
			(front yes)
			(back yes)
		)
		(net "GND")
	)
	(via
		(at 65.2701 144.4226)
		(size 0.4064)
		(drill 0.2032)
		(layers "F.Cu" "B.Cu")
		(tenting
			(front yes)
			(back yes)
		)
		(net "GND")
	)
	(via
		(at 70.3501 140.3586)
		(size 0.4064)
		(drill 0.2032)
		(layers "F.Cu" "B.Cu")
		(tenting
			(front yes)
			(back yes)
		)
		(net "GND")
	)
	(via
		(at 62.2221 144.4226)
		(size 0.4064)
		(drill 0.2032)
		(layers "F.Cu" "B.Cu")
		(tenting
			(front yes)
			(back yes)
		)
		(net "GND")
	)
	(via
		(at 69.8761 129.1162)
		(size 0.4064)
		(drill 0.2032)
		(layers "F.Cu" "B.Cu")
		(tenting
			(front yes)
			(back yes)
		)
		(net "GND")
	)
	(via
		(at 73.9061 112.9266)
		(size 0.4064)
		(drill 0.2032)
		(layers "F.Cu" "B.Cu")
		(tenting
			(front yes)
			(back yes)
		)
		(net "GND")
	)
	(via
		(at 63.7461 116.9906)
		(size 0.4064)
		(drill 0.2032)
		(layers "F.Cu" "B.Cu")
		(tenting
			(front yes)
			(back yes)
		)
		(net "GND")
	)
	(via
		(at 68.8261 116.9906)
		(size 0.4064)
		(drill 0.2032)
		(layers "F.Cu" "B.Cu")
		(tenting
			(front yes)
			(back yes)
		)
		(net "GND")
	)
	(via
		(at 196.6261 106.8286)
		(size 0.4064)
		(drill 0.2032)
		(layers "F.Cu" "B.Cu")
		(tenting
			(front yes)
			(back yes)
		)
		(net "GND")
	)
	(via
		(at 89.3761 86.0162)
		(size 0.5)
		(drill 0.2)
		(layers "F.Cu" "B.Cu")
		(net "GND")
	)
	(arc
		(start 131.306848 154.535981)
		(mid 131.399845 154.691687)
		(end 131.43222 154.870138)
		(width 0.508)
		(layer "F.Cu")
		(net "GND")
	)
	(arc
		(start 118.343423 154.653006)
		(mid 118.492607 154.832121)
		(end 118.546089 155.059007)
		(width 0.508)
		(layer "F.Cu")
		(net "GND")
	)
	(segment
		(start 129.50722 154.58472)
		(end 130.12689 154.58472)
		(width 0.508)
		(layer "B.Cu")
		(net "GND")
	)
	(segment
		(start 133.58245 157.02222)
		(end 133.58245 154.70118)
		(width 0.508)
		(layer "B.Cu")
		(net "GND")
	)
	(segment
		(start 125.52608 157.0786)
		(end 125.52608 154.47618)
		(width 0.508)
		(layer "B.Cu")
		(net "GND")
	)
	(segment
		(start 117.54609 155.01903)
		(end 117.54609 155.01902)
		(width 0.508)
		(layer "B.Cu")
		(net "GND")
	)
	(segment
		(start 129.30854 154.38605)
		(end 129.30894 154.38644)
		(width 0.508)
		(layer "B.Cu")
		(net "GND")
	)
	(segment
		(start 130.42447 156.977)
		(end 130.42447 154.8823)
		(width 0.508)
		(layer "B.Cu")
		(net "GND")
	)
	(segment
		(start 120.54609 157.7576)
		(end 120.54609 154.35959)
		(width 0.508)
		(layer "B.Cu")
		(net "GND")
	)
	(segment
		(start 129.30894 154.38644)
		(end 129.50722 154.58472)
		(width 0.508)
		(layer "B.Cu")
		(net "GND")
	)
	(segment
		(start 133.55745 157.04721)
		(end 133.58245 157.02222)
		(width 0.508)
		(layer "B.Cu")
		(net "GND")
	)
	(segment
		(start 126.52608 157.0786)
		(end 126.55745 157.04722)
		(width 0.508)
		(layer "B.Cu")
		(net "GND")
	)
	(segment
		(start 130.42447 156.977)
		(end 130.52607 157.0786)
		(width 0.508)
		(layer "B.Cu")
		(net "GND")
	)
	(segment
		(start 134.10503 154.1786)
		(end 134.5511 154.1786)
		(width 0.508)
		(layer "B.Cu")
		(net "GND")
	)
	(segment
		(start 114.5461 157.7576)
		(end 114.5461 154.3286)
		(width 0.508)
		(layer "B.Cu")
		(net "GND")
	)
	(segment
		(start 126.9761 154.1786)
		(end 126.99598 154.1786)
		(width 0.508)
		(layer "B.Cu")
		(net "GND")
	)
	(segment
		(start 133.55745 157.74622)
		(end 133.55745 157.04721)
		(width 0.508)
		(layer "B.Cu")
		(net "GND")
	)
	(segment
		(start 122.54608 154.58842)
		(end 122.8527 154.2818)
		(width 0.508)
		(layer "B.Cu")
		(net "GND")
	)
	(segment
		(start 104.54612 157.7576)
		(end 104.54612 154.36162)
		(width 0.508)
		(layer "B.Cu")
		(net "GND")
	)
	(segment
		(start 117.7652 154.60117)
		(end 118.03129 154.41678)
		(width 0.508)
		(layer "B.Cu")
		(net "GND")
	)
	(segment
		(start 122.54608 157.7576)
		(end 122.54608 154.58842)
		(width 0.508)
		(layer "B.Cu")
		(net "GND")
	)
	(segment
		(start 125.82366 154.1786)
		(end 126.9761 154.1786)
		(width 0.508)
		(layer "B.Cu")
		(net "GND")
	)
	(segment
		(start 117.54609 157.7576)
		(end 117.54609 155.01903)
		(width 0.508)
		(layer "B.Cu")
		(net "GND")
	)
	(segment
		(start 128.98452 154.23884)
		(end 128.9851 154.23889)
		(width 0.508)
		(layer "B.Cu")
		(net "GND")
	)
	(segment
		(start 133.58245 154.70118)
		(end 134.10503 154.1786)
		(width 0.508)
		(layer "B.Cu")
		(net "GND")
	)
	(segment
		(start 133.54606 157.7576)
		(end 133.55745 157.74622)
		(width 0.508)
		(layer "B.Cu")
		(net "GND")
	)
	(segment
		(start 125.52608 154.47618)
		(end 125.82366 154.1786)
		(width 0.508)
		(layer "B.Cu")
		(net "GND")
	)
	(segment
		(start 129.50722 157.05975)
		(end 129.50722 154.58472)
		(width 0.508)
		(layer "B.Cu")
		(net "GND")
	)
	(segment
		(start 129.50722 157.05975)
		(end 129.52607 157.0786)
		(width 0.508)
		(layer "B.Cu")
		(net "GND")
	)
	(segment
		(start 130.12689 154.58472)
		(end 130.42447 154.8823)
		(width 0.508)
		(layer "B.Cu")
		(net "GND")
	)
	(segment
		(start 126.55745 154.59725)
		(end 126.9761 154.1786)
		(width 0.508)
		(layer "B.Cu")
		(net "GND")
	)
	(segment
		(start 133.52606 157.0786)
		(end 133.55745 157.04721)
		(width 0.508)
		(layer "B.Cu")
		(net "GND")
	)
	(segment
		(start 126.55745 157.04722)
		(end 126.55745 154.59725)
		(width 0.508)
		(layer "B.Cu")
		(net "GND")
	)
	(arc
		(start 128.985097 154.238883)
		(mid 129.160104 154.283261)
		(end 129.308538 154.386044)
		(width 0.508)
		(layer "B.Cu")
		(net "GND")
	)
	(arc
		(start 117.54609 155.019027)
		(mid 117.604189 154.783119)
		(end 117.765194 154.601169)
		(width 0.508)
		(layer "B.Cu")
		(net "GND")
	)
	(segment
		(start 172.6261 108.4162)
		(end 193.1261 128.9162)
		(width 0.2032)
		(layer "F.Cu")
		(net "FPGA_TMS")
	)
	(segment
		(start 227.8261 140.6162)
		(end 227.8261 132.5162)
		(width 0.2032)
		(layer "F.Cu")
		(net "FPGA_TMS")
	)
	(segment
		(start 146.3532 104.81232)
		(end 147.69091 104.81232)
		(width 0.2032)
		(layer "F.Cu")
		(net "FPGA_TMS")
	)
	(segment
		(start 227.8261 140.6162)
		(end 228.3261 141.1162)
		(width 0.2032)
		(layer "F.Cu")
		(net "FPGA_TMS")
	)
	(segment
		(start 229.5261 138.9162)
		(end 229.6761 138.7662)
		(width 0.2032)
		(layer "F.Cu")
		(net "FPGA_TMS")
	)
	(segment
		(start 228.3261 141.1162)
		(end 229.5261 141.1162)
		(width 0.2032)
		(layer "F.Cu")
		(net "FPGA_TMS")
	)
	(segment
		(start 146.17557 104.68967)
		(end 146.23056 104.68967)
		(width 0.2032)
		(layer "F.Cu")
		(net "FPGA_TMS")
	)
	(segment
		(start 154.9261 106.7162)
		(end 156.6261 108.4162)
		(width 0.2032)
		(layer "F.Cu")
		(net "FPGA_TMS")
	)
	(segment
		(start 224.2261 128.9162)
		(end 227.8261 132.5162)
		(width 0.2032)
		(layer "F.Cu")
		(net "FPGA_TMS")
	)
	(segment
		(start 156.6261 108.4162)
		(end 172.6261 108.4162)
		(width 0.2032)
		(layer "F.Cu")
		(net "FPGA_TMS")
	)
	(segment
		(start 146.23056 104.68967)
		(end 146.3532 104.81232)
		(width 0.2032)
		(layer "F.Cu")
		(net "FPGA_TMS")
	)
	(segment
		(start 193.1261 128.9162)
		(end 224.2261 128.9162)
		(width 0.2032)
		(layer "F.Cu")
		(net "FPGA_TMS")
	)
	(segment
		(start 229.5261 141.1162)
		(end 229.5261 138.9162)
		(width 0.2032)
		(layer "F.Cu")
		(net "FPGA_TMS")
	)
	(via
		(at 154.9261 106.7162)
		(size 0.4064)
		(drill 0.2032)
		(layers "F.Cu" "B.Cu")
		(tenting
			(front yes)
			(back yes)
		)
		(net "FPGA_TMS")
	)
	(via
		(at 146.17557 104.68967)
		(size 0.4064)
		(drill 0.2032)
		(layers "F.Cu" "B.Cu")
		(tenting
			(front yes)
			(back yes)
		)
		(net "FPGA_TMS")
	)
	(segment
		(start 146.17557 104.68967)
		(end 148.89957 104.68967)
		(width 0.2032)
		(layer "In2.Cu")
		(net "FPGA_TMS")
	)
	(segment
		(start 148.89957 104.68967)
		(end 150.9261 106.7162)
		(width 0.2032)
		(layer "In2.Cu")
		(net "FPGA_TMS")
	)
	(segment
		(start 150.9261 106.7162)
		(end 154.9261 106.7162)
		(width 0.2032)
		(layer "In2.Cu")
		(net "FPGA_TMS")
	)
	(segment
		(start 219.8761 60.5786)
		(end 219.8761 59.08385)
		(width 0.2032)
		(layer "F.Cu")
		(net "+3.3V")
	)
	(segment
		(start 85.3761 86.1162)
		(end 87.0511 86.1162)
		(width 0.2032)
		(layer "F.Cu")
		(net "+3.3V")
	)
	(segment
		(start 125.1261 84.3786)
		(end 125.1261 82.8286)
		(width 0.3048)
		(layer "F.Cu")
		(net "+3.3V")
	)
	(segment
		(start 188.8761 88.2036)
		(end 188.8761 87.9786)
		(width 0.2032)
		(layer "F.Cu")
		(net "+3.3V")
	)
	(segment
		(start 215.5051 98.9452)
		(end 215.7761 99.2162)
		(width 0.508)
		(layer "F.Cu")
		(net "+3.3V")
	)
	(segment
		(start 125.0761 84.3286)
		(end 125.1261 84.3786)
		(width 0.508)
		(layer "F.Cu")
		(net "+3.3V")
	)
	(segment
		(start 193.7011 87.1536)
		(end 194.3511 86.5036)
		(width 0.2032)
		(layer "F.Cu")
		(net "+3.3V")
	)
	(segment
		(start 79.46734 111.4162)
		(end 80.6261 111.4162)
		(width 0.254)
		(layer "F.Cu")
		(net "+3.3V")
	)
	(segment
		(start 80.4011 138.9162)
		(end 80.7991 138.5182)
		(width 0.254)
		(layer "F.Cu")
		(net "+3.3V")
	)
	(segment
		(start 193.3761 81.5866)
		(end 193.3761 81.5786)
		(width 0.2032)
		(layer "F.Cu")
		(net "+3.3V")
	)
	(segment
		(start 79.3761 100.6162)
		(end 79.3761 98.3662)
		(width 0.254)
		(layer "F.Cu")
		(net "+3.3V")
	)
	(segment
		(start 188.8761 88.2036)
		(end 189.3511 88.6786)
		(width 0.2032)
		(layer "F.Cu")
		(net "+3.3V")
	)
	(segment
		(start 219.47085 58.6786)
		(end 223.6261 58.6786)
		(width 0.2032)
		(layer "F.Cu")
		(net "+3.3V")
	)
	(segment
		(start 86.4011 73.8536)
		(end 92.1011 73.8536)
		(width 0.508)
		(layer "F.Cu")
		(net "+3.3V")
	)
	(segment
		(start 167.86031 86.56281)
		(end 167.86031 86.56281)
		(width 0.2032)
		(layer "F.Cu")
		(net "+3.3V")
	)
	(segment
		(start 85.3761 86.6162)
		(end 87.0511 86.6162)
		(width 0.254)
		(layer "F.Cu")
		(net "+3.3V")
	)
	(segment
		(start 166.1261 86.85118)
		(end 166.42368 86.5536)
		(width 0.508)
		(layer "F.Cu")
		(net "+3.3V")
	)
	(segment
		(start 85.1261 86.3662)
		(end 85.3761 86.6162)
		(width 0.254)
		(layer "F.Cu")
		(net "+3.3V")
	)
	(segment
		(start 184.6261 90.0786)
		(end 185.4761 90.0786)
		(width 0.2032)
		(layer "F.Cu")
		(net "+3.3V")
	)
	(segment
		(start 210.7887 89.7662)
		(end 212.5637 89.7662)
		(width 0.508)
		(layer "F.Cu")
		(net "+3.3V")
	)
	(segment
		(start 209.4637 86.7662)
		(end 209.4637 86.68372)
		(width 0.508)
		(layer "F.Cu")
		(net "+3.3V")
	)
	(segment
		(start 90.1261 122.0786)
		(end 90.1261 119.7162)
		(width 0.508)
		(layer "F.Cu")
		(net "+3.3V")
	)
	(segment
		(start 81.22731 136.8662)
		(end 81.3761 137.01499)
		(width 0.254)
		(layer "F.Cu")
		(net "+3.3V")
	)
	(segment
		(start 219.46876 58.67651)
		(end 219.46876 57.51385)
		(width 0.2032)
		(layer "F.Cu")
		(net "+3.3V")
	)
	(segment
		(start 81.6261 109.8662)
		(end 81.79589 110.03599)
		(width 0.254)
		(layer "F.Cu")
		(net "+3.3V")
	)
	(segment
		(start 81.3761 97.1912)
		(end 81.3761 96.51499)
		(width 0.254)
		(layer "F.Cu")
		(net "+3.3V")
	)
	(segment
		(start 192.53636 144.15263)
		(end 193.93636 144.15263)
		(width 0.254)
		(layer "F.Cu")
		(net "+3.3V")
	)
	(segment
		(start 159.7261 88.6162)
		(end 161.5761 86.7662)
		(width 1.016)
		(layer "F.Cu")
		(net "+3.3V")
	)
	(segment
		(start 131.5761 83.5786)
		(end 131.5761 82.1286)
		(width 0.508)
		(layer "F.Cu")
		(net "+3.3V")
	)
	(segment
		(start 219.47085 58.6786)
		(end 219.8761 59.08385)
		(width 0.2032)
		(layer "F.Cu")
		(net "+3.3V")
	)
	(segment
		(start 84.3761 126.6162)
		(end 85.3761 126.6162)
		(width 0.254)
		(layer "F.Cu")
		(net "+3.3V")
	)
	(segment
		(start 58.4261 84.0912)
		(end 58.4511 84.0662)
		(width 0.254)
		(layer "F.Cu")
		(net "+3.3V")
	)
	(segment
		(start 187.8886 87.5786)
		(end 187.912 87.602)
		(width 0.2032)
		(layer "F.Cu")
		(net "+3.3V")
	)
	(segment
		(start 187.1261 85.0536)
		(end 187.8761 84.3036)
		(width 0.2032)
		(layer "F.Cu")
		(net "+3.3V")
	)
	(segment
		(start 219.3761 57.42119)
		(end 219.3761 57.3662)
		(width 0.2032)
		(layer "F.Cu")
		(net "+3.3V")
	)
	(segment
		(start 57.1261 143.1162)
		(end 57.15526 143.14536)
		(width 0.254)
		(layer "F.Cu")
		(net "+3.3V")
	)
	(segment
		(start 73.3761 51.3662)
		(end 73.3761 50.1162)
		(width 0.2032)
		(layer "F.Cu")
		(net "+3.3V")
	)
	(segment
		(start 57.1511 129.8412)
		(end 58.4261 129.8412)
		(width 0.254)
		(layer "F.Cu")
		(net "+3.3V")
	)
	(segment
		(start 188.4995 87.602)
		(end 188.8761 87.9786)
		(width 0.2032)
		(layer "F.Cu")
		(net "+3.3V")
	)
	(segment
		(start 80.3761 138.9162)
		(end 80.4011 138.9162)
		(width 0.254)
		(layer "F.Cu")
		(net "+3.3V")
	)
	(segment
		(start 79.3761 125.1162)
		(end 80.5761 125.1162)
		(width 0.254)
		(layer "F.Cu")
		(net "+3.3V")
	)
	(segment
		(start 176.8761 88.8286)
		(end 178.1261 90.0786)
		(width 0.2032)
		(layer "F.Cu")
		(net "+3.3V")
	)
	(segment
		(start 193.1261 85.3536)
		(end 193.4761 85.0036)
		(width 0.2032)
		(layer "F.Cu")
		(net "+3.3V")
	)
	(segment
		(start 176.8761 88.8286)
		(end 176.8761 87.7786)
		(width 0.2032)
		(layer "F.Cu")
		(net "+3.3V")
	)
	(segment
		(start 57.1261 116.3662)
		(end 57.15526 116.33704)
		(width 0.254)
		(layer "F.Cu")
		(net "+3.3V")
	)
	(segment
		(start 90.1261 122.0786)
		(end 91.2461 122.0786)
		(width 0.508)
		(layer "F.Cu")
		(net "+3.3V")
	)
	(segment
		(start 79.3761 98.3662)
		(end 79.5761 98.1662)
		(width 0.254)
		(layer "F.Cu")
		(net "+3.3V")
	)
	(segment
		(start 84.0761 86.3662)
		(end 84.1261 86.4162)
		(width 0.254)
		(layer "F.Cu")
		(net "+3.3V")
	)
	(segment
		(start 185.4761 89.1786)
		(end 186.1261 88.5286)
		(width 0.2032)
		(layer "F.Cu")
		(net "+3.3V")
	)
	(segment
		(start 183.8511 89.0536)
		(end 183.8761 89.0786)
		(width 0.2032)
		(layer "F.Cu")
		(net "+3.3V")
	)
	(segment
		(start 70.01734 127.0162)
		(end 70.9261 127.0162)
		(width 0.254)
		(layer "F.Cu")
		(net "+3.3V")
	)
	(segment
		(start 81.79589 110.27141)
		(end 81.79589 110.03599)
		(width 0.254)
		(layer "F.Cu")
		(net "+3.3V")
	)
	(segment
		(start 131.61799 83.62049)
		(end 132.8631 83.62049)
		(width 0.508)
		(layer "F.Cu")
		(net "+3.3V")
	)
	(segment
		(start 185.4761 90.0786)
		(end 185.4761 89.1786)
		(width 0.2032)
		(layer "F.Cu")
		(net "+3.3V")
	)
	(segment
		(start 82.1261 100.6162)
		(end 82.1261 99.6162)
		(width 0.254)
		(layer "F.Cu")
		(net "+3.3V")
	)
	(segment
		(start 197.0511 86.5036)
		(end 197.3511 86.2036)
		(width 0.2032)
		(layer "F.Cu")
		(net "+3.3V")
	)
	(segment
		(start 187.8761 84.3036)
		(end 188.17525 84.3036)
		(width 0.2032)
		(layer "F.Cu")
		(net "+3.3V")
	)
	(segment
		(start 188.17525 84.31859)
		(end 188.17525 84.3036)
		(width 0.2032)
		(layer "F.Cu")
		(net "+3.3V")
	)
	(segment
		(start 80.4011 98.1662)
		(end 81.3761 97.1912)
		(width 0.254)
		(layer "F.Cu")
		(net "+3.3V")
	)
	(segment
		(start 190.1261 88.6786)
		(end 190.2261 88.5786)
		(width 0.2032)
		(layer "F.Cu")
		(net "+3.3V")
	)
	(segment
		(start 161.5761 86.7662)
		(end 164.1261 84.2162)
		(width 1.016)
		(layer "F.Cu")
		(net "+3.3V")
	)
	(segment
		(start 210.7637 89.7662)
		(end 210.7637 88.0662)
		(width 0.508)
		(layer "F.Cu")
		(net "+3.3V")
	)
	(segment
		(start 81.3761 137.9162)
		(end 81.3761 137.01499)
		(width 0.254)
		(layer "F.Cu")
		(net "+3.3V")
	)
	(segment
		(start 166.1261 87.8286)
		(end 166.1261 86.85118)
		(width 0.508)
		(layer "F.Cu")
		(net "+3.3V")
	)
	(segment
		(start 189.3511 88.6786)
		(end 190.1261 88.6786)
		(width 0.2032)
		(layer "F.Cu")
		(net "+3.3V")
	)
	(segment
		(start 57.1261 102.8662)
		(end 57.1511 102.8412)
		(width 0.254)
		(layer "F.Cu")
		(net "+3.3V")
	)
	(segment
		(start 193.1011 85.8536)
		(end 193.1261 85.8286)
		(width 0.2032)
		(layer "F.Cu")
		(net "+3.3V")
	)
	(segment
		(start 219.3761 57.42119)
		(end 219.46876 57.51385)
		(width 0.2032)
		(layer "F.Cu")
		(net "+3.3V")
	)
	(segment
		(start 80.5761 125.1162)
		(end 80.6261 125.1662)
		(width 0.254)
		(layer "F.Cu")
		(net "+3.3V")
	)
	(segment
		(start 57.1511 102.8412)
		(end 58.4261 102.8412)
		(width 0.254)
		(layer "F.Cu")
		(net "+3.3V")
	)
	(segment
		(start 57.1511 73.0912)
		(end 58.4261 73.0912)
		(width 0.254)
		(layer "F.Cu")
		(net "+3.3V")
	)
	(segment
		(start 214.2637 89.7662)
		(end 215.5637 89.7662)
		(width 0.508)
		(layer "F.Cu")
		(net "+3.3V")
	)
	(segment
		(start 80.7991 138.5182)
		(end 80.7991 138.4932)
		(width 0.254)
		(layer "F.Cu")
		(net "+3.3V")
	)
	(segment
		(start 164.6261 87.8286)
		(end 166.1261 87.8286)
		(width 0.508)
		(layer "F.Cu")
		(net "+3.3V")
	)
	(segment
		(start 81.22731 96.3662)
		(end 81.3761 96.51499)
		(width 0.254)
		(layer "F.Cu")
		(net "+3.3V")
	)
	(segment
		(start 84.1261 140.3662)
		(end 85.3761 140.3662)
		(width 0.254)
		(layer "F.Cu")
		(net "+3.3V")
	)
	(segment
		(start 80.3761 98.1662)
		(end 80.4011 98.1662)
		(width 0.254)
		(layer "F.Cu")
		(net "+3.3V")
	)
	(segment
		(start 164.1261 84.2162)
		(end 172.9261 84.2162)
		(width 1.016)
		(layer "F.Cu")
		(net "+3.3V")
	)
	(segment
		(start 195.1511 86.5036)
		(end 197.0511 86.5036)
		(width 0.2032)
		(layer "F.Cu")
		(net "+3.3V")
	)
	(segment
		(start 192.41136 140.37763)
		(end 192.4526 140.37763)
		(width 0.254)
		(layer "F.Cu")
		(net "+3.3V")
	)
	(segment
		(start 69.8761 127.1162)
		(end 69.91734 127.1162)
		(width 0.254)
		(layer "F.Cu")
		(net "+3.3V")
	)
	(segment
		(start 193.3761 83.4786)
		(end 193.4761 83.5786)
		(width 0.2032)
		(layer "F.Cu")
		(net "+3.3V")
	)
	(segment
		(start 213.7261 87.2162)
		(end 213.7261 83.6162)
		(width 1.016)
		(layer "F.Cu")
		(net "+3.3V")
	)
	(segment
		(start 178.1261 79.0162)
		(end 209.1261 79.0162)
		(width 1.016)
		(layer "F.Cu")
		(net "+3.3V")
	)
	(segment
		(start 210.2661 132.1762)
		(end 210.3261 132.1162)
		(width 0.508)
		(layer "F.Cu")
		(net "+3.3V")
	)
	(segment
		(start 193.93636 144.15263)
		(end 193.96136 144.12763)
		(width 0.254)
		(layer "F.Cu")
		(net "+3.3V")
	)
	(segment
		(start 183.8761 89.3286)
		(end 183.8761 89.0786)
		(width 0.2032)
		(layer "F.Cu")
		(net "+3.3V")
	)
	(segment
		(start 81.1261 86.1162)
		(end 81.16734 86.1162)
		(width 0.254)
		(layer "F.Cu")
		(net "+3.3V")
	)
	(segment
		(start 57.15526 143.14536)
		(end 58.38026 143.14536)
		(width 0.254)
		(layer "F.Cu")
		(net "+3.3V")
	)
	(segment
		(start 86.3761 73.8286)
		(end 86.4011 73.8536)
		(width 0.508)
		(layer "F.Cu")
		(net "+3.3V")
	)
	(segment
		(start 219.46876 58.67651)
		(end 219.47085 58.6786)
		(width 0.2032)
		(layer "F.Cu")
		(net "+3.3V")
	)
	(segment
		(start 80.5511 136.8662)
		(end 81.22731 136.8662)
		(width 0.254)
		(layer "F.Cu")
		(net "+3.3V")
	)
	(segment
		(start 194.3511 86.5036)
		(end 195.1511 86.5036)
		(width 0.2032)
		(layer "F.Cu")
		(net "+3.3V")
	)
	(segment
		(start 132.8631 83.62049)
		(end 133.30121 84.0586)
		(width 0.508)
		(layer "F.Cu")
		(net "+3.3V")
	)
	(segment
		(start 229.0261 136.5162)
		(end 229.0261 135.0162)
		(width 0.254)
		(layer "F.Cu")
		(net "+3.3V")
	)
	(segment
		(start 123.4711 84.1736)
		(end 123.6261 84.3286)
		(width 0.508)
		(layer "F.Cu")
		(net "+3.3V")
	)
	(segment
		(start 57.1511 84.0912)
		(end 58.4261 84.0912)
		(width 0.254)
		(layer "F.Cu")
		(net "+3.3V")
	)
	(segment
		(start 79.3761 111.3662)
		(end 79.41734 111.3662)
		(width 0.254)
		(layer "F.Cu")
		(net "+3.3V")
	)
	(segment
		(start 82.3761 127.6162)
		(end 82.3761 126.6162)
		(width 0.254)
		(layer "F.Cu")
		(net "+3.3V")
	)
	(segment
		(start 197.3761 84.9786)
		(end 197.4136 85.0161)
		(width 0.2032)
		(layer "F.Cu")
		(net "+3.3V")
	)
	(segment
		(start 162.6385 87.8286)
		(end 164.6261 87.8286)
		(width 0.508)
		(layer "F.Cu")
		(net "+3.3V")
	)
	(segment
		(start 193.1261 85.8286)
		(end 193.1261 85.3536)
		(width 0.2032)
		(layer "F.Cu")
		(net "+3.3V")
	)
	(segment
		(start 215.5637 89.7662)
		(end 215.8347 89.4952)
		(width 0.508)
		(layer "F.Cu")
		(net "+3.3V")
	)
	(segment
		(start 84.1261 99.6162)
		(end 84.1261 99.6162)
		(width 0.254)
		(layer "F.Cu")
		(net "+3.3V")
	)
	(segment
		(start 133.30121 84.0586)
		(end 134.1261 84.0586)
		(width 0.508)
		(layer "F.Cu")
		(net "+3.3V")
	)
	(segment
		(start 94.3761 73.5286)
		(end 96.5761 73.5286)
		(width 0.508)
		(layer "F.Cu")
		(net "+3.3V")
	)
	(segment
		(start 197.3511 85.0036)
		(end 197.3761 84.9786)
		(width 0.2032)
		(layer "F.Cu")
		(net "+3.3V")
	)
	(segment
		(start 159.7261 90.2162)
		(end 159.7261 88.6162)
		(width 1.016)
		(layer "F.Cu")
		(net "+3.3V")
	)
	(segment
		(start 209.4637 86.7662)
		(end 210.7637 88.0662)
		(width 0.508)
		(layer "F.Cu")
		(net "+3.3V")
	)
	(segment
		(start 70.9261 99.6662)
		(end 70.9261 98.45744)
		(width 0.254)
		(layer "F.Cu")
		(net "+3.3V")
	)
	(segment
		(start 58.38026 143.14536)
		(end 58.4511 143.2162)
		(width 0.254)
		(layer "F.Cu")
		(net "+3.3V")
	)
	(segment
		(start 209.4637 86.68372)
		(end 209.5647 86.58273)
		(width 0.508)
		(layer "F.Cu")
		(net "+3.3V")
	)
	(segment
		(start 179.0511 90.0786)
		(end 179.1761 89.9536)
		(width 0.2032)
		(layer "F.Cu")
		(net "+3.3V")
	)
	(segment
		(start 93.14029 73.75616)
		(end 93.32866 73.56779)
		(width 0.508)
		(layer "F.Cu")
		(net "+3.3V")
	)
	(segment
		(start 81.6261 123.1162)
		(end 81.8761 123.3662)
		(width 0.254)
		(layer "F.Cu")
		(net "+3.3V")
	)
	(segment
		(start 80.6261 125.1662)
		(end 80.6511 125.1662)
		(width 0.254)
		(layer "F.Cu")
		(net "+3.3V")
	)
	(segment
		(start 84.1761 86.3662)
		(end 85.1261 86.3662)
		(width 0.254)
		(layer "F.Cu")
		(net "+3.3V")
	)
	(segment
		(start 224.2261 135.05744)
		(end 224.2761 135.10744)
		(width 0.254)
		(layer "F.Cu")
		(net "+3.3V")
	)
	(segment
		(start 84.1261 112.8662)
		(end 85.1261 112.8662)
		(width 0.254)
		(layer "F.Cu")
		(net "+3.3V")
	)
	(segment
		(start 169.0761 87.7786)
		(end 176.8761 87.7786)
		(width 0.2032)
		(layer "F.Cu")
		(net "+3.3V")
	)
	(segment
		(start 57.15526 116.33704)
		(end 58.33026 116.33704)
		(width 0.254)
		(layer "F.Cu")
		(net "+3.3V")
	)
	(segment
		(start 123.6261 84.3286)
		(end 125.0761 84.3286)
		(width 0.508)
		(layer "F.Cu")
		(net "+3.3V")
	)
	(segment
		(start 83.1261 115.5786)
		(end 83.1341 115.5866)
		(width 0.508)
		(layer "F.Cu")
		(net "+3.3V")
	)
	(segment
		(start 82.3761 114.1162)
		(end 82.3761 112.8662)
		(width 0.254)
		(layer "F.Cu")
		(net "+3.3V")
	)
	(segment
		(start 224.2261 135.05744)
		(end 224.2261 135.0162)
		(width 0.254)
		(layer "F.Cu")
		(net "+3.3V")
	)
	(segment
		(start 192.8026 140.02763)
		(end 193.98636 140.02763)
		(width 0.254)
		(layer "F.Cu")
		(net "+3.3V")
	)
	(segment
		(start 96.5761 73.5286)
		(end 96.6261 73.5786)
		(width 0.508)
		(layer "F.Cu")
		(net "+3.3V")
	)
	(segment
		(start 81.41734 86.3662)
		(end 84.0761 86.3662)
		(width 0.254)
		(layer "F.Cu")
		(net "+3.3V")
	)
	(segment
		(start 94.33692 73.56779)
		(end 94.3761 73.5286)
		(width 0.508)
		(layer "F.Cu")
		(net "+3.3V")
	)
	(segment
		(start 82.3761 112.8662)
		(end 82.3761 112.8662)
		(width 0.254)
		(layer "F.Cu")
		(net "+3.3V")
	)
	(segment
		(start 210.2661 135.5162)
		(end 210.2661 132.1762)
		(width 0.508)
		(layer "F.Cu")
		(net "+3.3V")
	)
	(segment
		(start 120.9761 84.1736)
		(end 123.4711 84.1736)
		(width 0.508)
		(layer "F.Cu")
		(net "+3.3V")
	)
	(segment
		(start 92.19855 73.75616)
		(end 93.14029 73.75616)
		(width 0.508)
		(layer "F.Cu")
		(net "+3.3V")
	)
	(segment
		(start 79.5761 98.1662)
		(end 80.3761 98.1662)
		(width 0.254)
		(layer "F.Cu")
		(net "+3.3V")
	)
	(segment
		(start 212.5637 89.7662)
		(end 214.2637 89.7662)
		(width 0.508)
		(layer "F.Cu")
		(net "+3.3V")
	)
	(segment
		(start 80.8011 109.8662)
		(end 81.6261 109.8662)
		(width 0.254)
		(layer "F.Cu")
		(net "+3.3V")
	)
	(segment
		(start 80.7991 138.4932)
		(end 81.3761 137.9162)
		(width 0.254)
		(layer "F.Cu")
		(net "+3.3V")
	)
	(segment
		(start 210.7137 89.7162)
		(end 210.7637 89.7662)
		(width 0.508)
		(layer "F.Cu")
		(net "+3.3V")
	)
	(segment
		(start 58.33026 116.33704)
		(end 58.4511 116.2162)
		(width 0.254)
		(layer "F.Cu")
		(net "+3.3V")
	)
	(segment
		(start 193.1011 87.1536)
		(end 193.7011 87.1536)
		(width 0.2032)
		(layer "F.Cu")
		(net "+3.3V")
	)
	(segment
		(start 58.4261 102.8412)
		(end 58.4511 102.8162)
		(width 0.254)
		(layer "F.Cu")
		(net "+3.3V")
	)
	(segment
		(start 192.51136 144.17763)
		(end 192.53636 144.15263)
		(width 0.254)
		(layer "F.Cu")
		(net "+3.3V")
	)
	(segment
		(start 172.9261 84.2162)
		(end 178.1261 79.0162)
		(width 1.016)
		(layer "F.Cu")
		(net "+3.3V")
	)
	(segment
		(start 193.3761 83.4786)
		(end 193.3761 81.5866)
		(width 0.2032)
		(layer "F.Cu")
		(net "+3.3V")
	)
	(segment
		(start 69.8761 51.3662)
		(end 69.8761 50.1162)
		(width 0.2032)
		(layer "F.Cu")
		(net "+3.3V")
	)
	(segment
		(start 131.5761 83.5786)
		(end 131.61799 83.62049)
		(width 0.508)
		(layer "F.Cu")
		(net "+3.3V")
	)
	(segment
		(start 80.5511 96.3662)
		(end 81.22731 96.3662)
		(width 0.254)
		(layer "F.Cu")
		(net "+3.3V")
	)
	(segment
		(start 83.1341 115.5866)
		(end 85.9965 115.5866)
		(width 0.508)
		(layer "F.Cu")
		(net "+3.3V")
	)
	(segment
		(start 187.1261 85.8161)
		(end 187.1261 85.0536)
		(width 0.2032)
		(layer "F.Cu")
		(net "+3.3V")
	)
	(segment
		(start 131.5761 82.1286)
		(end 131.6261 82.0786)
		(width 0.508)
		(layer "F.Cu")
		(net "+3.3V")
	)
	(segment
		(start 85.1261 86.3662)
		(end 85.3761 86.1162)
		(width 0.2032)
		(layer "F.Cu")
		(net "+3.3V")
	)
	(segment
		(start 190.2261 88.5786)
		(end 191.6261 88.5786)
		(width 0.2032)
		(layer "F.Cu")
		(net "+3.3V")
	)
	(segment
		(start 79.41734 111.3662)
		(end 79.46734 111.4162)
		(width 0.254)
		(layer "F.Cu")
		(net "+3.3V")
	)
	(segment
		(start 197.3511 86.2036)
		(end 197.3511 85.0036)
		(width 0.2032)
		(layer "F.Cu")
		(net "+3.3V")
	)
	(segment
		(start 57.1261 84.1162)
		(end 57.1511 84.0912)
		(width 0.254)
		(layer "F.Cu")
		(net "+3.3V")
	)
	(segment
		(start 179.1761 89.9536)
		(end 179.1761 88.14481)
		(width 0.2032)
		(layer "F.Cu")
		(net "+3.3V")
	)
	(segment
		(start 57.1261 73.1162)
		(end 57.1511 73.0912)
		(width 0.254)
		(layer "F.Cu")
		(net "+3.3V")
	)
	(segment
		(start 70.8761 98.40744)
		(end 70.8761 98.3662)
		(width 0.254)
		(layer "F.Cu")
		(net "+3.3V")
	)
	(segment
		(start 82.1261 141.3662)
		(end 82.1261 140.3662)
		(width 0.254)
		(layer "F.Cu")
		(net "+3.3V")
	)
	(segment
		(start 167.8511 86.5536)
		(end 167.86031 86.56281)
		(width 0.508)
		(layer "F.Cu")
		(net "+3.3V")
	)
	(segment
		(start 212.8061 135.5162)
		(end 212.8061 132.0962)
		(width 0.508)
		(layer "F.Cu")
		(net "+3.3V")
	)
	(segment
		(start 71.6261 51.3662)
		(end 71.6261 50.0786)
		(width 0.2032)
		(layer "F.Cu")
		(net "+3.3V")
	)
	(segment
		(start 209.5647 86.58273)
		(end 209.5647 84.8864)
		(width 0.508)
		(layer "F.Cu")
		(net "+3.3V")
	)
	(segment
		(start 212.7261 132.0162)
		(end 212.8061 132.0962)
		(width 0.508)
		(layer "F.Cu")
		(net "+3.3V")
	)
	(segment
		(start 197.4136 85.0161)
		(end 198.73112 85.0161)
		(width 0.2032)
		(layer "F.Cu")
		(net "+3.3V")
	)
	(segment
		(start 75.1261 51.3662)
		(end 75.1261 50.1162)
		(width 0.2032)
		(layer "F.Cu")
		(net "+3.3V")
	)
	(segment
		(start 186.1261 88.5286)
		(end 186.1261 87.8411)
		(width 0.2032)
		(layer "F.Cu")
		(net "+3.3V")
	)
	(segment
		(start 166.42368 86.5536)
		(end 167.8511 86.5536)
		(width 0.508)
		(layer "F.Cu")
		(net "+3.3V")
	)
	(segment
		(start 178.1261 90.0786)
		(end 179.0511 90.0786)
		(width 0.2032)
		(layer "F.Cu")
		(net "+3.3V")
	)
	(segment
		(start 192.4526 140.37763)
		(end 192.8026 140.02763)
		(width 0.254)
		(layer "F.Cu")
		(net "+3.3V")
	)
	(segment
		(start 79.1261 138.8662)
		(end 80.3261 138.8662)
		(width 0.254)
		(layer "F.Cu")
		(net "+3.3V")
	)
	(segment
		(start 209.1261 79.0162)
		(end 213.7261 83.6162)
		(width 1.016)
		(layer "F.Cu")
		(net "+3.3V")
	)
	(segment
		(start 193.4761 85.0036)
		(end 193.4761 83.5786)
		(width 0.2032)
		(layer "F.Cu")
		(net "+3.3V")
	)
	(segment
		(start 70.8761 98.40744)
		(end 70.9261 98.45744)
		(width 0.254)
		(layer "F.Cu")
		(net "+3.3V")
	)
	(segment
		(start 85.9965 115.5866)
		(end 90.1261 119.7162)
		(width 0.508)
		(layer "F.Cu")
		(net "+3.3V")
	)
	(segment
		(start 84.1261 86.4162)
		(end 84.1761 86.3662)
		(width 0.254)
		(layer "F.Cu")
		(net "+3.3V")
	)
	(segment
		(start 69.91734 127.1162)
		(end 70.01734 127.0162)
		(width 0.254)
		(layer "F.Cu")
		(net "+3.3V")
	)
	(segment
		(start 84.1261 99.6162)
		(end 85.1261 99.6162)
		(width 0.254)
		(layer "F.Cu")
		(net "+3.3V")
	)
	(segment
		(start 80.6511 125.1662)
		(end 81.8761 123.9412)
		(width 0.254)
		(layer "F.Cu")
		(net "+3.3V")
	)
	(segment
		(start 57.1261 129.8662)
		(end 57.1511 129.8412)
		(width 0.254)
		(layer "F.Cu")
		(net "+3.3V")
	)
	(segment
		(start 80.8011 123.1162)
		(end 81.6261 123.1162)
		(width 0.254)
		(layer "F.Cu")
		(net "+3.3V")
	)
	(segment
		(start 80.3261 138.8662)
		(end 80.3761 138.9162)
		(width 0.254)
		(layer "F.Cu")
		(net "+3.3V")
	)
	(segment
		(start 58.4261 129.8412)
		(end 58.4511 129.8162)
		(width 0.254)
		(layer "F.Cu")
		(net "+3.3V")
	)
	(segment
		(start 224.2761 136.4912)
		(end 224.2761 135.10744)
		(width 0.254)
		(layer "F.Cu")
		(net "+3.3V")
	)
	(segment
		(start 58.4261 73.0912)
		(end 58.4511 73.0662)
		(width 0.254)
		(layer "F.Cu")
		(net "+3.3V")
	)
	(segment
		(start 80.6261 111.4162)
		(end 80.6511 111.4162)
		(width 0.254)
		(layer "F.Cu")
		(net "+3.3V")
	)
	(segment
		(start 93.32866 73.56779)
		(end 94.33692 73.56779)
		(width 0.508)
		(layer "F.Cu")
		(net "+3.3V")
	)
	(segment
		(start 187.912 87.602)
		(end 188.4995 87.602)
		(width 0.2032)
		(layer "F.Cu")
		(net "+3.3V")
	)
	(segment
		(start 80.6511 111.4162)
		(end 81.79589 110.27141)
		(width 0.254)
		(layer "F.Cu")
		(net "+3.3V")
	)
	(segment
		(start 81.8761 123.9412)
		(end 81.8761 123.3662)
		(width 0.254)
		(layer "F.Cu")
		(net "+3.3V")
	)
	(segment
		(start 81.16734 86.1162)
		(end 81.41734 86.3662)
		(width 0.254)
		(layer "F.Cu")
		(net "+3.3V")
	)
	(segment
		(start 183.8761 89.3286)
		(end 184.6261 90.0786)
		(width 0.2032)
		(layer "F.Cu")
		(net "+3.3V")
	)
	(segment
		(start 167.86031 86.56281)
		(end 169.0761 87.7786)
		(width 0.2032)
		(layer "F.Cu")
		(net "+3.3V")
	)
	(segment
		(start 92.1011 73.8536)
		(end 92.19855 73.75616)
		(width 0.508)
		(layer "F.Cu")
		(net "+3.3V")
	)
	(via
		(at 214.3261 88.4162)
		(size 0.4064)
		(drill 0.2032)
		(layers "F.Cu" "B.Cu")
		(tenting
			(front yes)
			(back yes)
		)
		(net "+3.3V")
	)
	(via
		(at 210.3261 132.1162)
		(size 0.4064)
		(drill 0.2032)
		(layers "F.Cu" "B.Cu")
		(tenting
			(front yes)
			(back yes)
		)
		(net "+3.3V")
	)
	(via
		(at 57.1261 102.8662)
		(size 0.4064)
		(drill 0.2032)
		(layers "F.Cu" "B.Cu")
		(tenting
			(front yes)
			(back yes)
		)
		(net "+3.3V")
	)
	(via
		(at 192.51136 144.17763)
		(size 0.4064)
		(drill 0.2032)
		(layers "F.Cu" "B.Cu")
		(tenting
			(front yes)
			(back yes)
		)
		(net "+3.3V")
	)
	(via
		(at 85.1261 112.8662)
		(size 0.4064)
		(drill 0.2032)
		(layers "F.Cu" "B.Cu")
		(tenting
			(front yes)
			(back yes)
		)
		(net "+3.3V")
	)
	(via
		(at 57.1261 116.3662)
		(size 0.4064)
		(drill 0.2032)
		(layers "F.Cu" "B.Cu")
		(tenting
			(front yes)
			(back yes)
		)
		(net "+3.3V")
	)
	(via
		(at 79.3761 100.6162)
		(size 0.4064)
		(drill 0.2032)
		(layers "F.Cu" "B.Cu")
		(tenting
			(front yes)
			(back yes)
		)
		(net "+3.3V")
	)
	(via
		(at 214.8261 88.4162)
		(size 0.4064)
		(drill 0.2032)
		(layers "F.Cu" "B.Cu")
		(tenting
			(front yes)
			(back yes)
		)
		(net "+3.3V")
	)
	(via
		(at 57.1261 143.1162)
		(size 0.4064)
		(drill 0.2032)
		(layers "F.Cu" "B.Cu")
		(tenting
			(front yes)
			(back yes)
		)
		(net "+3.3V")
	)
	(via
		(at 71.6261 50.0786)
		(size 0.4064)
		(drill 0.2032)
		(layers "F.Cu" "B.Cu")
		(tenting
			(front yes)
			(back yes)
		)
		(net "+3.3V")
	)
	(via
		(at 224.2261 135.0162)
		(size 0.4064)
		(drill 0.2032)
		(layers "F.Cu" "B.Cu")
		(tenting
			(front yes)
			(back yes)
		)
		(net "+3.3V")
	)
	(via
		(at 57.1261 73.1162)
		(size 0.4064)
		(drill 0.2032)
		(layers "F.Cu" "B.Cu")
		(tenting
			(front yes)
			(back yes)
		)
		(net "+3.3V")
	)
	(via
		(at 213.8261 87.6162)
		(size 0.4064)
		(drill 0.2032)
		(layers "F.Cu" "B.Cu")
		(tenting
			(front yes)
			(back yes)
		)
		(net "+3.3V")
	)
	(via
		(at 57.1261 129.8662)
		(size 0.4064)
		(drill 0.2032)
		(layers "F.Cu" "B.Cu")
		(tenting
			(front yes)
			(back yes)
		)
		(net "+3.3V")
	)
	(via
		(at 183.8511 89.0536)
		(size 0.4064)
		(drill 0.2032)
		(layers "F.Cu" "B.Cu")
		(tenting
			(front yes)
			(back yes)
		)
		(net "+3.3V")
	)
	(via
		(at 82.1261 141.3662)
		(size 0.4064)
		(drill 0.2032)
		(layers "F.Cu" "B.Cu")
		(tenting
			(front yes)
			(back yes)
		)
		(net "+3.3V")
	)
	(via
		(at 159.4261 90.1162)
		(size 0.4064)
		(drill 0.2032)
		(layers "F.Cu" "B.Cu")
		(tenting
			(front yes)
			(back yes)
		)
		(net "+3.3V")
	)
	(via
		(at 198.73112 85.0161)
		(size 0.4064)
		(drill 0.2032)
		(layers "F.Cu" "B.Cu")
		(tenting
			(front yes)
			(back yes)
		)
		(net "+3.3V")
	)
	(via
		(at 229.0261 135.0162)
		(size 0.4064)
		(drill 0.2032)
		(layers "F.Cu" "B.Cu")
		(tenting
			(front yes)
			(back yes)
		)
		(net "+3.3V")
	)
	(via
		(at 167.86031 86.56281)
		(size 0.4064)
		(drill 0.2032)
		(layers "F.Cu" "B.Cu")
		(tenting
			(front yes)
			(back yes)
		)
		(net "+3.3V")
	)
	(via
		(at 125.1261 82.8286)
		(size 0.4064)
		(drill 0.2032)
		(layers "F.Cu" "B.Cu")
		(tenting
			(front yes)
			(back yes)
		)
		(net "+3.3V")
	)
	(via
		(at 79.1261 138.8662)
		(size 0.4064)
		(drill 0.2032)
		(layers "F.Cu" "B.Cu")
		(tenting
			(front yes)
			(back yes)
		)
		(net "+3.3V")
	)
	(via
		(at 79.3761 111.3662)
		(size 0.4064)
		(drill 0.2032)
		(layers "F.Cu" "B.Cu")
		(tenting
			(front yes)
			(back yes)
		)
		(net "+3.3V")
	)
	(via
		(at 83.1261 115.5786)
		(size 0.4064)
		(drill 0.2032)
		(layers "F.Cu" "B.Cu")
		(tenting
			(front yes)
			(back yes)
		)
		(net "+3.3V")
	)
	(via
		(at 131.6261 82.0786)
		(size 0.4064)
		(drill 0.2032)
		(layers "F.Cu" "B.Cu")
		(tenting
			(front yes)
			(back yes)
		)
		(net "+3.3V")
	)
	(via
		(at 188.17525 84.31859)
		(size 0.4064)
		(drill 0.2032)
		(layers "F.Cu" "B.Cu")
		(tenting
			(front yes)
			(back yes)
		)
		(net "+3.3V")
	)
	(via
		(at 75.1261 50.1162)
		(size 0.4064)
		(drill 0.2032)
		(layers "F.Cu" "B.Cu")
		(tenting
			(front yes)
			(back yes)
		)
		(net "+3.3V")
	)
	(via
		(at 73.3761 50.1162)
		(size 0.4064)
		(drill 0.2032)
		(layers "F.Cu" "B.Cu")
		(tenting
			(front yes)
			(back yes)
		)
		(net "+3.3V")
	)
	(via
		(at 214.8261 87.6162)
		(size 0.4064)
		(drill 0.2032)
		(layers "F.Cu" "B.Cu")
		(tenting
			(front yes)
			(back yes)
		)
		(net "+3.3V")
	)
	(via
		(at 90.1261 122.0786)
		(size 0.4064)
		(drill 0.2032)
		(layers "F.Cu" "B.Cu")
		(tenting
			(front yes)
			(back yes)
		)
		(net "+3.3V")
	)
	(via
		(at 57.1261 84.1162)
		(size 0.4064)
		(drill 0.2032)
		(layers "F.Cu" "B.Cu")
		(tenting
			(front yes)
			(back yes)
		)
		(net "+3.3V")
	)
	(via
		(at 193.3761 81.5866)
		(size 0.4064)
		(drill 0.2032)
		(layers "F.Cu" "B.Cu")
		(tenting
			(front yes)
			(back yes)
		)
		(net "+3.3V")
	)
	(via
		(at 85.1261 99.6162)
		(size 0.4064)
		(drill 0.2032)
		(layers "F.Cu" "B.Cu")
		(tenting
			(front yes)
			(back yes)
		)
		(net "+3.3V")
	)
	(via
		(at 69.8761 127.1162)
		(size 0.4064)
		(drill 0.2032)
		(layers "F.Cu" "B.Cu")
		(tenting
			(front yes)
			(back yes)
		)
		(net "+3.3V")
	)
	(via
		(at 191.6261 88.5786)
		(size 0.4064)
		(drill 0.2032)
		(layers "F.Cu" "B.Cu")
		(tenting
			(front yes)
			(back yes)
		)
		(net "+3.3V")
	)
	(via
		(at 213.8261 88.4162)
		(size 0.4064)
		(drill 0.2032)
		(layers "F.Cu" "B.Cu")
		(tenting
			(front yes)
			(back yes)
		)
		(net "+3.3V")
	)
	(via
		(at 219.3761 57.3662)
		(size 0.4064)
		(drill 0.2032)
		(layers "F.Cu" "B.Cu")
		(tenting
			(front yes)
			(back yes)
		)
		(net "+3.3V")
	)
	(via
		(at 192.41136 140.37763)
		(size 0.4064)
		(drill 0.2032)
		(layers "F.Cu" "B.Cu")
		(tenting
			(front yes)
			(back yes)
		)
		(net "+3.3V")
	)
	(via
		(at 85.3761 140.3662)
		(size 0.4064)
		(drill 0.2032)
		(layers "F.Cu" "B.Cu")
		(tenting
			(front yes)
			(back yes)
		)
		(net "+3.3V")
	)
	(via
		(at 79.3761 125.1162)
		(size 0.4064)
		(drill 0.2032)
		(layers "F.Cu" "B.Cu")
		(tenting
			(front yes)
			(back yes)
		)
		(net "+3.3V")
	)
	(via
		(at 69.8761 50.1162)
		(size 0.4064)
		(drill 0.2032)
		(layers "F.Cu" "B.Cu")
		(tenting
			(front yes)
			(back yes)
		)
		(net "+3.3V")
	)
	(via
		(at 82.1261 100.6162)
		(size 0.4064)
		(drill 0.2032)
		(layers "F.Cu" "B.Cu")
		(tenting
			(front yes)
			(back yes)
		)
		(net "+3.3V")
	)
	(via
		(at 82.3761 127.6162)
		(size 0.4064)
		(drill 0.2032)
		(layers "F.Cu" "B.Cu")
		(tenting
			(front yes)
			(back yes)
		)
		(net "+3.3V")
	)
	(via
		(at 212.7261 132.0162)
		(size 0.4064)
		(drill 0.2032)
		(layers "F.Cu" "B.Cu")
		(tenting
			(front yes)
			(back yes)
		)
		(net "+3.3V")
	)
	(via
		(at 82.3761 114.1162)
		(size 0.4064)
		(drill 0.2032)
		(layers "F.Cu" "B.Cu")
		(tenting
			(front yes)
			(back yes)
		)
		(net "+3.3V")
	)
	(via
		(at 81.1261 86.1162)
		(size 0.4064)
		(drill 0.2032)
		(layers "F.Cu" "B.Cu")
		(tenting
			(front yes)
			(back yes)
		)
		(net "+3.3V")
	)
	(via
		(at 70.8761 98.3662)
		(size 0.4064)
		(drill 0.2032)
		(layers "F.Cu" "B.Cu")
		(tenting
			(front yes)
			(back yes)
		)
		(net "+3.3V")
	)
	(via
		(at 85.3761 126.6162)
		(size 0.4064)
		(drill 0.2032)
		(layers "F.Cu" "B.Cu")
		(tenting
			(front yes)
			(back yes)
		)
		(net "+3.3V")
	)
	(via
		(at 209.4637 86.7662)
		(size 0.8128)
		(drill 0.4064)
		(layers "F.Cu" "B.Cu")
		(tenting
			(front yes)
			(back yes)
		)
		(net "+3.3V")
	)
	(via
		(at 96.6261 73.5786)
		(size 0.4064)
		(drill 0.2032)
		(layers "F.Cu" "B.Cu")
		(tenting
			(front yes)
			(back yes)
		)
		(net "+3.3V")
	)
	(via
		(at 214.3261 87.6162)
		(size 0.4064)
		(drill 0.2032)
		(layers "F.Cu" "B.Cu")
		(tenting
			(front yes)
			(back yes)
		)
		(net "+3.3V")
	)
	(arc
		(start 162.6385 87.8286)
		(mid 161.88727 87.51743)
		(end 161.5761 86.7662)
		(width 0.508)
		(layer "F.Cu")
		(net "+3.3V")
	)
	(segment
		(start 229.0261 135.0162)
		(end 232.3261 131.7162)
		(width 0.762)
		(layer "In2.Cu")
		(net "+3.3V")
	)
	(segment
		(start 212.7261 132.0162)
		(end 215.7261 135.0162)
		(width 0.762)
		(layer "In2.Cu")
		(net "+3.3V")
	)
	(segment
		(start 202.06467 140.37763)
		(end 210.3261 132.1162)
		(width 0.762)
		(layer "In2.Cu")
		(net "+3.3V")
	)
	(segment
		(start 83.1261 99.6162)
		(end 85.1261 99.6162)
		(width 0.254)
		(layer "In2.Cu")
		(net "+3.3V")
	)
	(segment
		(start 230.8261 105.7162)
		(end 235.9261 110.8162)
		(width 0.762)
		(layer "In2.Cu")
		(net "+3.3V")
	)
	(segment
		(start 219.8261 88.7162)
		(end 222.3261 86.2162)
		(width 0.762)
		(layer "In2.Cu")
		(net "+3.3V")
	)
	(segment
		(start 222.3261 86.2162)
		(end 225.9261 86.2162)
		(width 0.762)
		(layer "In2.Cu")
		(net "+3.3V")
	)
	(segment
		(start 192.38753 144.17763)
		(end 192.51136 144.17763)
		(width 0.762)
		(layer "In2.Cu")
		(net "+3.3V")
	)
	(segment
		(start 215.7261 135.0162)
		(end 224.2261 135.0162)
		(width 0.762)
		(layer "In2.Cu")
		(net "+3.3V")
	)
	(segment
		(start 225.7261 133.5162)
		(end 227.52609 133.5162)
		(width 0.762)
		(layer "In2.Cu")
		(net "+3.3V")
	)
	(segment
		(start 191.4261 143.2162)
		(end 192.38753 144.17763)
		(width 0.762)
		(layer "In2.Cu")
		(net "+3.3V")
	)
	(segment
		(start 232.3261 129.6162)
		(end 235.5261 126.4162)
		(width 0.762)
		(layer "In2.Cu")
		(net "+3.3V")
	)
	(segment
		(start 215.5261 88.7162)
		(end 219.8261 88.7162)
		(width 0.762)
		(layer "In2.Cu")
		(net "+3.3V")
	)
	(segment
		(start 192.41136 140.37763)
		(end 202.06467 140.37763)
		(width 0.762)
		(layer "In2.Cu")
		(net "+3.3V")
	)
	(segment
		(start 235.9261 126.4162)
		(end 235.9261 110.8162)
		(width 0.762)
		(layer "In2.Cu")
		(net "+3.3V")
	)
	(segment
		(start 212.6261 132.1162)
		(end 212.7261 132.0162)
		(width 0.762)
		(layer "In2.Cu")
		(net "+3.3V")
	)
	(segment
		(start 224.2261 135.0162)
		(end 225.7261 133.5162)
		(width 0.762)
		(layer "In2.Cu")
		(net "+3.3V")
	)
	(segment
		(start 191.4261 143.2162)
		(end 191.4261 141.36289)
		(width 0.762)
		(layer "In2.Cu")
		(net "+3.3V")
	)
	(segment
		(start 225.9261 86.2162)
		(end 230.8261 91.1162)
		(width 0.762)
		(layer "In2.Cu")
		(net "+3.3V")
	)
	(segment
		(start 210.3261 132.1162)
		(end 212.6261 132.1162)
		(width 0.762)
		(layer "In2.Cu")
		(net "+3.3V")
	)
	(segment
		(start 235.5261 126.4162)
		(end 235.9261 126.4162)
		(width 0.762)
		(layer "In2.Cu")
		(net "+3.3V")
	)
	(segment
		(start 82.1261 100.6162)
		(end 83.1261 99.6162)
		(width 0.254)
		(layer "In2.Cu")
		(net "+3.3V")
	)
	(segment
		(start 232.3261 131.7162)
		(end 232.3261 129.6162)
		(width 0.762)
		(layer "In2.Cu")
		(net "+3.3V")
	)
	(segment
		(start 227.52609 133.5162)
		(end 229.0261 135.0162)
		(width 0.762)
		(layer "In2.Cu")
		(net "+3.3V")
	)
	(segment
		(start 230.8261 105.7162)
		(end 230.8261 91.1162)
		(width 0.762)
		(layer "In2.Cu")
		(net "+3.3V")
	)
	(segment
		(start 191.4261 141.36289)
		(end 192.41136 140.37763)
		(width 0.762)
		(layer "In2.Cu")
		(net "+3.3V")
	)
	(segment
		(start 57.1261 84.1162)
		(end 71.1261 84.1162)
		(width 0.254)
		(layer "In3.Cu")
		(net "+3.3V")
	)
	(segment
		(start 57.1261 129.8662)
		(end 79.90753 129.8662)
		(width 0.254)
		(layer "In3.Cu")
		(net "+3.3V")
	)
	(segment
		(start 191.6261 88.5786)
		(end 191.6261 83.3286)
		(width 0.2032)
		(layer "In3.Cu")
		(net "+3.3V")
	)
	(segment
		(start 71.6261 51.1162)
		(end 71.6261 50.0786)
		(width 0.2032)
		(layer "In3.Cu")
		(net "+3.3V")
	)
	(segment
		(start 167.86031 86.56281)
		(end 167.86031 86.56281)
		(width 0.2032)
		(layer "In3.Cu")
		(net "+3.3V")
	)
	(segment
		(start 183.8511 89.0536)
		(end 184.3261 88.5786)
		(width 0.2032)
		(layer "In3.Cu")
		(net "+3.3V")
	)
	(segment
		(start 57.1261 102.8662)
		(end 80.2261 102.8662)
		(width 0.254)
		(layer "In3.Cu")
		(net "+3.3V")
	)
	(segment
		(start 69.8761 50.8662)
		(end 69.8761 50.1162)
		(width 0.2032)
		(layer "In3.Cu")
		(net "+3.3V")
	)
	(segment
		(start 71.1261 84.1162)
		(end 71.6261 84.6162)
		(width 0.254)
		(layer "In3.Cu")
		(net "+3.3V")
	)
	(segment
		(start 73.3761 50.8662)
		(end 73.3761 50.1162)
		(width 0.2032)
		(layer "In3.Cu")
		(net "+3.3V")
	)
	(segment
		(start 184.3261 88.5786)
		(end 191.6261 88.5786)
		(width 0.2032)
		(layer "In3.Cu")
		(net "+3.3V")
	)
	(segment
		(start 57.1261 143.1162)
		(end 80.2261 143.1162)
		(width 0.254)
		(layer "In3.Cu")
		(net "+3.3V")
	)
	(segment
		(start 69.8761 127.1162)
		(end 79.3261 127.1162)
		(width 0.254)
		(layer "In3.Cu")
		(net "+3.3V")
	)
	(segment
		(start 191.6261 83.3286)
		(end 193.3681 81.5866)
		(width 0.2032)
		(layer "In3.Cu")
		(net "+3.3V")
	)
	(segment
		(start 79.3261 127.1162)
		(end 79.6261 126.8162)
		(width 0.254)
		(layer "In3.Cu")
		(net "+3.3V")
	)
	(segment
		(start 70.8761 98.3662)
		(end 79.4761 98.3662)
		(width 0.254)
		(layer "In3.Cu")
		(net "+3.3V")
	)
	(segment
		(start 193.3681 81.5866)
		(end 193.3761 81.5866)
		(width 0.2032)
		(layer "In3.Cu")
		(net "+3.3V")
	)
	(segment
		(start 79.1761 116.3662)
		(end 79.21036 116.33194)
		(width 0.254)
		(layer "In3.Cu")
		(net "+3.3V")
	)
	(segment
		(start 79.4761 98.3662)
		(end 79.5261 98.3162)
		(width 0.254)
		(layer "In3.Cu")
		(net "+3.3V")
	)
	(segment
		(start 57.1261 73.1162)
		(end 71.1261 73.1162)
		(width 0.254)
		(layer "In3.Cu")
		(net "+3.3V")
	)
	(segment
		(start 71.1261 73.1162)
		(end 71.6261 72.6162)
		(width 0.254)
		(layer "In3.Cu")
		(net "+3.3V")
	)
	(segment
		(start 73.3761 50.8662)
		(end 73.6261 51.1162)
		(width 0.2032)
		(layer "In3.Cu")
		(net "+3.3V")
	)
	(segment
		(start 75.1261 51.1162)
		(end 75.1261 50.1162)
		(width 0.2032)
		(layer "In3.Cu")
		(net "+3.3V")
	)
	(segment
		(start 57.1261 116.3662)
		(end 79.1761 116.3662)
		(width 0.254)
		(layer "In3.Cu")
		(net "+3.3V")
	)
	(segment
		(start 164.8261 111.9162)
		(end 182.3261 129.4162)
		(width 0.2032)
		(layer "F.Cu")
		(net "FPGA_TDO")
	)
	(segment
		(start 153.5261 108.5162)
		(end 156.9261 111.9162)
		(width 0.2032)
		(layer "F.Cu")
		(net "FPGA_TDO")
	)
	(segment
		(start 153.2392 104.80882)
		(end 153.53182 104.5162)
		(width 0.2032)
		(layer "F.Cu")
		(net "FPGA_TDO")
	)
	(segment
		(start 182.9261 129.4162)
		(end 190.85479 137.34489)
		(width 0.2032)
		(layer "F.Cu")
		(net "FPGA_TDO")
	)
	(segment
		(start 197.3261 145.8162)
		(end 198.3261 144.8162)
		(width 0.2032)
		(layer "F.Cu")
		(net "FPGA_TDO")
	)
	(segment
		(start 198.31136 143.47763)
		(end 198.3261 143.49237)
		(width 0.2032)
		(layer "F.Cu")
		(net "FPGA_TDO")
	)
	(segment
		(start 190.85479 144.83735)
		(end 191.83364 145.8162)
		(width 0.2032)
		(layer "F.Cu")
		(net "FPGA_TDO")
	)
	(segment
		(start 196.21136 143.47763)
		(end 198.31136 143.47763)
		(width 0.2032)
		(layer "F.Cu")
		(net "FPGA_TDO")
	)
	(segment
		(start 191.83364 145.8162)
		(end 197.3261 145.8162)
		(width 0.2032)
		(layer "F.Cu")
		(net "FPGA_TDO")
	)
	(segment
		(start 153.5261 105.5162)
		(end 155.2261 105.5162)
		(width 0.2032)
		(layer "F.Cu")
		(net "FPGA_TDO")
	)
	(segment
		(start 190.85479 144.83735)
		(end 190.85479 137.34489)
		(width 0.2032)
		(layer "F.Cu")
		(net "FPGA_TDO")
	)
	(segment
		(start 153.5261 108.5162)
		(end 153.5261 105.5162)
		(width 0.2032)
		(layer "F.Cu")
		(net "FPGA_TDO")
	)
	(segment
		(start 182.3261 129.4162)
		(end 182.9261 129.4162)
		(width 0.2032)
		(layer "F.Cu")
		(net "FPGA_TDO")
	)
	(segment
		(start 155.2261 105.5162)
		(end 156.2261 106.5162)
		(width 0.2032)
		(layer "F.Cu")
		(net "FPGA_TDO")
	)
	(segment
		(start 153.53182 104.5162)
		(end 154.2261 104.5162)
		(width 0.2032)
		(layer "F.Cu")
		(net "FPGA_TDO")
	)
	(segment
		(start 156.9261 111.9162)
		(end 164.8261 111.9162)
		(width 0.2032)
		(layer "F.Cu")
		(net "FPGA_TDO")
	)
	(segment
		(start 151.13797 104.80882)
		(end 153.2392 104.80882)
		(width 0.2032)
		(layer "F.Cu")
		(net "FPGA_TDO")
	)
	(segment
		(start 198.3261 144.8162)
		(end 198.3261 143.49237)
		(width 0.2032)
		(layer "F.Cu")
		(net "FPGA_TDO")
	)
	(via
		(at 154.2261 104.5162)
		(size 0.4064)
		(drill 0.2032)
		(layers "F.Cu" "B.Cu")
		(tenting
			(front yes)
			(back yes)
		)
		(net "FPGA_TDO")
	)
	(via
		(at 156.2261 106.5162)
		(size 0.4064)
		(drill 0.2032)
		(layers "F.Cu" "B.Cu")
		(tenting
			(front yes)
			(back yes)
		)
		(net "FPGA_TDO")
	)
	(segment
		(start 154.2261 104.5162)
		(end 156.2261 106.5162)
		(width 0.2032)
		(layer "In2.Cu")
		(net "FPGA_TDO")
	)
	(segment
		(start 197.32386 139.37763)
		(end 198.41136 139.37763)
		(width 0.2032)
		(layer "F.Cu")
		(net "FPGA_TCK")
	)
	(segment
		(start 155.2261 106.2162)
		(end 156.5261 107.5162)
		(width 0.2032)
		(layer "F.Cu")
		(net "FPGA_TCK")
	)
	(segment
		(start 154.2261 106.2162)
		(end 155.2261 106.2162)
		(width 0.2032)
		(layer "F.Cu")
		(net "FPGA_TCK")
	)
	(segment
		(start 155.8261 105.1162)
		(end 157.1261 106.4162)
		(width 0.2032)
		(layer "F.Cu")
		(net "FPGA_TCK")
	)
	(segment
		(start 151.74069 105.31244)
		(end 153.22985 105.31244)
		(width 0.2032)
		(layer "F.Cu")
		(net "FPGA_TCK")
	)
	(segment
		(start 153.22985 105.31244)
		(end 153.4261 105.1162)
		(width 0.2032)
		(layer "F.Cu")
		(net "FPGA_TCK")
	)
	(segment
		(start 154.2261 106.2162)
		(end 154.2261 106.2162)
		(width 0.2032)
		(layer "F.Cu")
		(net "FPGA_TCK")
	)
	(segment
		(start 192.0261 136.7162)
		(end 196.6261 136.7162)
		(width 0.2032)
		(layer "F.Cu")
		(net "FPGA_TCK")
	)
	(segment
		(start 166.2261 110.9162)
		(end 192.0261 136.7162)
		(width 0.2032)
		(layer "F.Cu")
		(net "FPGA_TCK")
	)
	(segment
		(start 153.4261 105.1162)
		(end 155.8261 105.1162)
		(width 0.2032)
		(layer "F.Cu")
		(net "FPGA_TCK")
	)
	(segment
		(start 156.5261 107.5162)
		(end 157.1261 107.5162)
		(width 0.2032)
		(layer "F.Cu")
		(net "FPGA_TCK")
	)
	(segment
		(start 196.6261 136.7162)
		(end 198.41136 138.50146)
		(width 0.2032)
		(layer "F.Cu")
		(net "FPGA_TCK")
	)
	(segment
		(start 198.41136 139.37763)
		(end 198.41136 138.50146)
		(width 0.2032)
		(layer "F.Cu")
		(net "FPGA_TCK")
	)
	(segment
		(start 157.0261 110.9162)
		(end 166.2261 110.9162)
		(width 0.2032)
		(layer "F.Cu")
		(net "FPGA_TCK")
	)
	(segment
		(start 196.23636 139.37763)
		(end 197.32386 139.37763)
		(width 0.2032)
		(layer "F.Cu")
		(net "FPGA_TCK")
	)
	(segment
		(start 154.2261 108.1162)
		(end 154.2261 106.2162)
		(width 0.2032)
		(layer "F.Cu")
		(net "FPGA_TCK")
	)
	(segment
		(start 154.2261 108.1162)
		(end 157.0261 110.9162)
		(width 0.2032)
		(layer "F.Cu")
		(net "FPGA_TCK")
	)
	(segment
		(start 157.1261 107.5162)
		(end 157.1261 106.4162)
		(width 0.2032)
		(layer "F.Cu")
		(net "FPGA_TCK")
	)
	(segment
		(start 203.4915 114.9774)
		(end 206.3497 114.9774)
		(width 0.508)
		(layer "F.Cu")
		(net "+12V")
	)
	(segment
		(start 201.7682 90.2712)
		(end 201.7682 89.2117)
		(width 0.508)
		(layer "F.Cu")
		(net "+12V")
	)
	(segment
		(start 203.78908 116.13578)
		(end 203.78908 115.27498)
		(width 0.508)
		(layer "F.Cu")
		(net "+12V")
	)
	(segment
		(start 203.78908 116.13578)
		(end 204.1885 116.5352)
		(width 0.508)
		(layer "F.Cu")
		(net "+12V")
	)
	(segment
		(start 200.4377 87.7312)
		(end 200.5437 87.8372)
		(width 0.508)
		(layer "F.Cu")
		(net "+12V")
	)
	(segment
		(start 206.8695 116.8762)
		(end 206.8695 115.4972)
		(width 0.508)
		(layer "F.Cu")
		(net "+12V")
	)
	(segment
		(start 202.0637 88.9162)
		(end 204.0637 88.9162)
		(width 0.508)
		(layer "F.Cu")
		(net "+12V")
	)
	(segment
		(start 200.9637 88.9162)
		(end 202.0637 88.9162)
		(width 0.508)
		(layer "F.Cu")
		(net "+12V")
	)
	(segment
		(start 200.5437 88.4962)
		(end 200.9637 88.9162)
		(width 0.508)
		(layer "F.Cu")
		(net "+12V")
	)
	(segment
		(start 204.5567 90.7142)
		(end 204.5567 89.4092)
		(width 0.508)
		(layer "F.Cu")
		(net "+12V")
	)
	(segment
		(start 198.8637 87.3662)
		(end 199.2287 87.7312)
		(width 0.508)
		(layer "F.Cu")
		(net "+12V")
	)
	(segment
		(start 201.7682 89.2117)
		(end 202.0637 88.9162)
		(width 0.508)
		(layer "F.Cu")
		(net "+12V")
	)
	(segment
		(start 199.2287 87.7312)
		(end 200.4377 87.7312)
		(width 0.508)
		(layer "F.Cu")
		(net "+12V")
	)
	(segment
		(start 204.1885 118.4662)
		(end 204.1885 116.5352)
		(width 0.508)
		(layer "F.Cu")
		(net "+12V")
	)
	(segment
		(start 202.7505 114.7782)
		(end 202.9497 114.9774)
		(width 0.508)
		(layer "F.Cu")
		(net "+12V")
	)
	(segment
		(start 203.4915 114.9774)
		(end 203.78908 115.27498)
		(width 0.508)
		(layer "F.Cu")
		(net "+12V")
	)
	(segment
		(start 202.9497 114.9774)
		(end 203.4915 114.9774)
		(width 0.508)
		(layer "F.Cu")
		(net "+12V")
	)
	(segment
		(start 202.7505 114.7782)
		(end 202.7505 114.0202)
		(width 0.508)
		(layer "F.Cu")
		(net "+12V")
	)
	(segment
		(start 206.3497 114.9774)
		(end 206.8695 115.4972)
		(width 0.508)
		(layer "F.Cu")
		(net "+12V")
	)
	(segment
		(start 204.0637 88.9162)
		(end 204.5567 89.4092)
		(width 0.508)
		(layer "F.Cu")
		(net "+12V")
	)
	(segment
		(start 200.5437 88.4962)
		(end 200.5437 87.8372)
		(width 0.508)
		(layer "F.Cu")
		(net "+12V")
	)
	(via
		(at 147.1261 87.2162)
		(size 0.4064)
		(drill 0.2032)
		(layers "F.Cu" "B.Cu")
		(tenting
			(front yes)
			(back yes)
		)
		(net "+12V")
	)
	(via
		(at 225.9261 117.7162)
		(size 0.4064)
		(drill 0.2032)
		(layers "F.Cu" "B.Cu")
		(tenting
			(front yes)
			(back yes)
		)
		(net "+12V")
	)
	(via
		(at 208.1261 74.0162)
		(size 0.4064)
		(drill 0.2032)
		(layers "F.Cu" "B.Cu")
		(tenting
			(front yes)
			(back yes)
		)
		(net "+12V")
	)
	(via
		(at 225.1261 118.7162)
		(size 0.4064)
		(drill 0.2032)
		(layers "F.Cu" "B.Cu")
		(tenting
			(front yes)
			(back yes)
		)
		(net "+12V")
	)
	(via
		(at 198.8637 87.3662)
		(size 0.4064)
		(drill 0.2032)
		(layers "F.Cu" "B.Cu")
		(tenting
			(front yes)
			(back yes)
		)
		(net "+12V")
	)
	(via
		(at 204.1885 118.4662)
		(size 0.4064)
		(drill 0.2032)
		(layers "F.Cu" "B.Cu")
		(tenting
			(front yes)
			(back yes)
		)
		(net "+12V")
	)
	(via
		(at 206.6096 115.2373)
		(size 0.3556)
		(drill 0.14986)
		(layers "F.Cu" "B.Cu")
		(net "+12V")
	)
	(via
		(at 225.9261 118.7162)
		(size 0.4064)
		(drill 0.2032)
		(layers "F.Cu" "B.Cu")
		(tenting
			(front yes)
			(back yes)
		)
		(net "+12V")
	)
	(via
		(at 225.1261 118.2162)
		(size 0.4064)
		(drill 0.2032)
		(layers "F.Cu" "B.Cu")
		(tenting
			(front yes)
			(back yes)
		)
		(net "+12V")
	)
	(via
		(at 225.9261 118.2162)
		(size 0.4064)
		(drill 0.2032)
		(layers "F.Cu" "B.Cu")
		(tenting
			(front yes)
			(back yes)
		)
		(net "+12V")
	)
	(via
		(at 208.1261 73.0162)
		(size 0.4064)
		(drill 0.2032)
		(layers "F.Cu" "B.Cu")
		(tenting
			(front yes)
			(back yes)
		)
		(net "+12V")
	)
	(via
		(at 208.9261 73.5162)
		(size 0.4064)
		(drill 0.2032)
		(layers "F.Cu" "B.Cu")
		(tenting
			(front yes)
			(back yes)
		)
		(net "+12V")
	)
	(via
		(at 147.1261 86.4662)
		(size 0.4064)
		(drill 0.2032)
		(layers "F.Cu" "B.Cu")
		(tenting
			(front yes)
			(back yes)
		)
		(net "+12V")
	)
	(via
		(at 147.1261 85.7162)
		(size 0.4064)
		(drill 0.2032)
		(layers "F.Cu" "B.Cu")
		(tenting
			(front yes)
			(back yes)
		)
		(net "+12V")
	)
	(via
		(at 208.1261 73.5162)
		(size 0.4064)
		(drill 0.2032)
		(layers "F.Cu" "B.Cu")
		(tenting
			(front yes)
			(back yes)
		)
		(net "+12V")
	)
	(via
		(at 225.1261 117.7162)
		(size 0.4064)
		(drill 0.2032)
		(layers "F.Cu" "B.Cu")
		(tenting
			(front yes)
			(back yes)
		)
		(net "+12V")
	)
	(via
		(at 208.9261 73.0162)
		(size 0.4064)
		(drill 0.2032)
		(layers "F.Cu" "B.Cu")
		(tenting
			(front yes)
			(back yes)
		)
		(net "+12V")
	)
	(via
		(at 208.9261 74.0162)
		(size 0.4064)
		(drill 0.2032)
		(layers "F.Cu" "B.Cu")
		(tenting
			(front yes)
			(back yes)
		)
		(net "+12V")
	)
	(segment
		(start 206.6096 115.2373)
		(end 210.7885 119.4162)
		(width 0.508)
		(layer "B.Cu")
		(net "+12V")
	)
	(segment
		(start 207.4385 121.7162)
		(end 224.3261 121.7162)
		(width 0.508)
		(layer "B.Cu")
		(net "+12V")
	)
	(segment
		(start 224.3261 121.7162)
		(end 226.8261 119.2162)
		(width 0.508)
		(layer "B.Cu")
		(net "+12V")
	)
	(segment
		(start 204.1885 118.4662)
		(end 207.4385 121.7162)
		(width 0.508)
		(layer "B.Cu")
		(net "+12V")
	)
	(segment
		(start 224.7261 119.4162)
		(end 224.7261 118.9162)
		(width 0.508)
		(layer "B.Cu")
		(net "+12V")
	)
	(segment
		(start 210.7885 119.4162)
		(end 224.7261 119.4162)
		(width 0.508)
		(layer "B.Cu")
		(net "+12V")
	)
	(segment
		(start 224.1261 116.7162)
		(end 224.8261 117.4162)
		(width 0.508)
		(layer "In3.Cu")
		(net "+12V")
	)
	(segment
		(start 211.5261 112.0162)
		(end 211.5261 103.6162)
		(width 0.508)
		(layer "In3.Cu")
		(net "+12V")
	)
	(segment
		(start 203.9261 96.6162)
		(end 208.8261 101.5162)
		(width 0.508)
		(layer "In3.Cu")
		(net "+12V")
	)
	(segment
		(start 198.8637 87.3662)
		(end 203.9261 92.4286)
		(width 0.508)
		(layer "In3.Cu")
		(net "+12V")
	)
	(segment
		(start 203.9261 96.6162)
		(end 203.9261 92.4286)
		(width 0.508)
		(layer "In3.Cu")
		(net "+12V")
	)
	(segment
		(start 209.4261 101.5162)
		(end 211.5261 103.6162)
		(width 0.508)
		(layer "In3.Cu")
		(net "+12V")
	)
	(segment
		(start 211.5261 112.0162)
		(end 215.2261 115.7162)
		(width 0.508)
		(layer "In3.Cu")
		(net "+12V")
	)
	(segment
		(start 224.1261 116.7162)
		(end 224.1261 116.3162)
		(width 0.508)
		(layer "In3.Cu")
		(net "+12V")
	)
	(segment
		(start 215.2261 115.7162)
		(end 223.5261 115.7162)
		(width 0.508)
		(layer "In3.Cu")
		(net "+12V")
	)
	(segment
		(start 208.8261 101.5162)
		(end 209.4261 101.5162)
		(width 0.508)
		(layer "In3.Cu")
		(net "+12V")
	)
	(segment
		(start 223.5261 115.7162)
		(end 224.1261 116.3162)
		(width 0.508)
		(layer "In3.Cu")
		(net "+12V")
	)
	(segment
		(start 151.74863 118.81069)
		(end 151.75053 118.80879)
		(width 0.2032)
		(layer "F.Cu")
		(net "KEY1")
	)
	(segment
		(start 221.0935 115.2792)
		(end 222.5515 115.2792)
		(width 0.508)
		(layer "F.Cu")
		(net "+5.0V")
	)
	(segment
		(start 192.6261 106.3286)
		(end 192.63367 106.32103)
		(width 0.2032)
		(layer "F.Cu")
		(net "+5.0V")
	)
	(segment
		(start 87.4051 78.3576)
		(end 87.8551 78.3576)
		(width 0.508)
		(layer "F.Cu")
		(net "+5.0V")
	)
	(segment
		(start 199.3634 105.81333)
		(end 199.37104 105.82096)
		(width 0.2032)
		(layer "F.Cu")
		(net "+5.0V")
	)
	(segment
		(start 232.8761 66.0786)
		(end 232.8761 60.0786)
		(width 0.635)
		(layer "F.Cu")
		(net "+5.0V")
	)
	(segment
		(start 228.0711 58.6786)
		(end 231.4761 58.6786)
		(width 0.635)
		(layer "F.Cu")
		(net "+5.0V")
	)
	(segment
		(start 218.2995 115.2792)
		(end 221.0935 115.2792)
		(width 0.508)
		(layer "F.Cu")
		(net "+5.0V")
	)
	(segment
		(start 192.63374 105.82096)
		(end 195.30599 105.82096)
		(width 0.2032)
		(layer "F.Cu")
		(net "+5.0V")
	)
	(segment
		(start 211.8885 111.7662)
		(end 215.2885 111.7662)
		(width 0.508)
		(layer "F.Cu")
		(net "+5.0V")
	)
	(segment
		(start 212.0765 115.6062)
		(end 212.0765 112.16462)
		(width 0.508)
		(layer "F.Cu")
		(net "+5.0V")
	)
	(segment
		(start 192.63373 104.82097)
		(end 195.30599 104.82097)
		(width 0.2032)
		(layer "F.Cu")
		(net "+5.0V")
	)
	(segment
		(start 228.4836 68.6861)
		(end 228.67058 68.87308)
		(width 0.635)
		(layer "F.Cu")
		(net "+5.0V")
	)
	(segment
		(start 88.1261 78.6286)
		(end 88.2261 78.5286)
		(width 0.508)
		(layer "F.Cu")
		(net "+5.0V")
	)
	(segment
		(start 211.7845 111.6622)
		(end 211.8885 111.7662)
		(width 0.508)
		(layer "F.Cu")
		(net "+5.0V")
	)
	(segment
		(start 192.63367 105.32103)
		(end 195.30606 105.32103)
		(width 0.2032)
		(layer "F.Cu")
		(net "+5.0V")
	)
	(segment
		(start 213.4735 115.6062)
		(end 214.7435 115.6062)
		(width 0.508)
		(layer "F.Cu")
		(net "+5.0V")
	)
	(segment
		(start 222.5515 115.2792)
		(end 223.3885 116.1162)
		(width 0.508)
		(layer "F.Cu")
		(net "+5.0V")
	)
	(segment
		(start 85.9761 78.0786)
		(end 87.1261 78.0786)
		(width 0.508)
		(layer "F.Cu")
		(net "+5.0V")
	)
	(segment
		(start 212.0765 115.6062)
		(end 213.4735 115.6062)
		(width 0.508)
		(layer "F.Cu")
		(net "+5.0V")
	)
	(segment
		(start 228.6215 70.0832)
		(end 228.67058 70.03412)
		(width 0.635)
		(layer "F.Cu")
		(net "+5.0V")
	)
	(segment
		(start 192.63367 106.32103)
		(end 195.30606 106.32103)
		(width 0.2032)
		(layer "F.Cu")
		(net "+5.0V")
	)
	(segment
		(start 195.30599 105.82096)
		(end 195.31363 105.81333)
		(width 0.2032)
		(layer "F.Cu")
		(net "+5.0V")
	)
	(segment
		(start 220.1015 124.9422)
		(end 222.2625 124.9422)
		(width 0.508)
		(layer "F.Cu")
		(net "+5.0V")
	)
	(segment
		(start 201.36847 104.82097)
		(end 201.3761 104.8286)
		(width 0.2032)
		(layer "F.Cu")
		(net "+5.0V")
	)
	(segment
		(start 201.36853 105.32103)
		(end 201.3761 105.3286)
		(width 0.2032)
		(layer "F.Cu")
		(net "+5.0V")
	)
	(segment
		(start 87.1261 78.0786)
		(end 87.4051 78.3576)
		(width 0.508)
		(layer "F.Cu")
		(net "+5.0V")
	)
	(segment
		(start 228.67058 70.03412)
		(end 228.67058 68.87308)
		(width 0.635)
		(layer "F.Cu")
		(net "+5.0V")
	)
	(segment
		(start 192.6261 105.3286)
		(end 192.63367 105.32103)
		(width 0.2032)
		(layer "F.Cu")
		(net "+5.0V")
	)
	(segment
		(start 223.3885 123.8162)
		(end 223.3885 116.1162)
		(width 0.508)
		(layer "F.Cu")
		(net "+5.0V")
	)
	(segment
		(start 192.6261 105.8286)
		(end 192.63374 105.82096)
		(width 0.2032)
		(layer "F.Cu")
		(net "+5.0V")
	)
	(segment
		(start 192.6261 104.8286)
		(end 192.63373 104.82097)
		(width 0.2032)
		(layer "F.Cu")
		(net "+5.0V")
	)
	(segment
		(start 195.30606 106.32103)
		(end 195.31363 106.31346)
		(width 0.2032)
		(layer "F.Cu")
		(net "+5.0V")
	)
	(segment
		(start 228.2761 67.8286)
		(end 228.4836 68.0361)
		(width 0.635)
		(layer "F.Cu")
		(net "+5.0V")
	)
	(segment
		(start 201.36847 105.82096)
		(end 201.3761 105.8286)
		(width 0.2032)
		(layer "F.Cu")
		(net "+5.0V")
	)
	(segment
		(start 216.2675 115.6062)
		(end 216.4075 115.4662)
		(width 0.508)
		(layer "F.Cu")
		(net "+5.0V")
	)
	(segment
		(start 228.6215 71.45)
		(end 228.6215 70.0832)
		(width 0.635)
		(layer "F.Cu")
		(net "+5.0V")
	)
	(segment
		(start 195.30599 104.82097)
		(end 195.31363 104.81333)
		(width 0.2032)
		(layer "F.Cu")
		(net "+5.0V")
	)
	(segment
		(start 199.37104 104.82097)
		(end 201.36847 104.82097)
		(width 0.2032)
		(layer "F.Cu")
		(net "+5.0V")
	)
	(segment
		(start 88.2261 78.5286)
		(end 89.6761 78.5286)
		(width 0.508)
		(layer "F.Cu")
		(net "+5.0V")
	)
	(segment
		(start 220.1015 124.9422)
		(end 220.1885 125.0292)
		(width 0.2032)
		(layer "F.Cu")
		(net "+5.0V")
	)
	(segment
		(start 211.0605 111.6622)
		(end 211.7845 111.6622)
		(width 0.508)
		(layer "F.Cu")
		(net "+5.0V")
	)
	(segment
		(start 199.3634 106.31346)
		(end 199.37097 106.32103)
		(width 0.2032)
		(layer "F.Cu")
		(net "+5.0V")
	)
	(segment
		(start 218.1125 115.4662)
		(end 218.2995 115.2792)
		(width 0.508)
		(layer "F.Cu")
		(net "+5.0V")
	)
	(segment
		(start 231.1261 67.8286)
		(end 232.8761 66.0786)
		(width 0.635)
		(layer "F.Cu")
		(net "+5.0V")
	)
	(segment
		(start 83.8761 73.8286)
		(end 84.3761 74.3286)
		(width 0.508)
		(layer "F.Cu")
		(net "+5.0V")
	)
	(segment
		(start 231.4761 58.6786)
		(end 232.8761 60.0786)
		(width 0.635)
		(layer "F.Cu")
		(net "+5.0V")
	)
	(segment
		(start 199.37097 105.32103)
		(end 201.36853 105.32103)
		(width 0.2032)
		(layer "F.Cu")
		(net "+5.0V")
	)
	(segment
		(start 85.7261 78.1786)
		(end 85.8761 78.1786)
		(width 0.508)
		(layer "F.Cu")
		(net "+5.0V")
	)
	(segment
		(start 84.3761 76.8286)
		(end 84.3761 74.3286)
		(width 0.508)
		(layer "F.Cu")
		(net "+5.0V")
	)
	(segment
		(start 211.92851 111.80621)
		(end 211.92852 111.80622)
		(width 0.508)
		(layer "F.Cu")
		(net "+5.0V")
	)
	(segment
		(start 216.4075 115.4662)
		(end 218.1125 115.4662)
		(width 0.508)
		(layer "F.Cu")
		(net "+5.0V")
	)
	(segment
		(start 228.2761 67.8286)
		(end 231.1261 67.8286)
		(width 0.635)
		(layer "F.Cu")
		(net "+5.0V")
	)
	(segment
		(start 228.4836 68.6861)
		(end 228.4836 68.0361)
		(width 0.635)
		(layer "F.Cu")
		(net "+5.0V")
	)
	(segment
		(start 84.3761 76.8286)
		(end 85.7261 78.1786)
		(width 0.508)
		(layer "F.Cu")
		(net "+5.0V")
	)
	(segment
		(start 85.8761 78.1786)
		(end 85.9761 78.0786)
		(width 0.508)
		(layer "F.Cu")
		(net "+5.0V")
	)
	(segment
		(start 199.3634 105.31346)
		(end 199.37097 105.32103)
		(width 0.2032)
		(layer "F.Cu")
		(net "+5.0V")
	)
	(segment
		(start 199.37097 106.32103)
		(end 201.36853 106.32103)
		(width 0.2032)
		(layer "F.Cu")
		(net "+5.0V")
	)
	(segment
		(start 81.9311 73.8286)
		(end 83.8761 73.8286)
		(width 0.508)
		(layer "F.Cu")
		(net "+5.0V")
	)
	(segment
		(start 199.3634 104.81333)
		(end 199.37104 104.82097)
		(width 0.2032)
		(layer "F.Cu")
		(net "+5.0V")
	)
	(segment
		(start 222.2625 124.9422)
		(end 223.3885 123.8162)
		(width 0.508)
		(layer "F.Cu")
		(net "+5.0V")
	)
	(segment
		(start 87.8551 78.3576)
		(end 88.1261 78.6286)
		(width 0.508)
		(layer "F.Cu")
		(net "+5.0V")
	)
	(segment
		(start 195.30606 105.32103)
		(end 195.31363 105.31346)
		(width 0.2032)
		(layer "F.Cu")
		(net "+5.0V")
	)
	(segment
		(start 214.7435 115.6062)
		(end 216.2675 115.6062)
		(width 0.508)
		(layer "F.Cu")
		(net "+5.0V")
	)
	(segment
		(start 201.36853 106.32103)
		(end 201.3761 106.3286)
		(width 0.2032)
		(layer "F.Cu")
		(net "+5.0V")
	)
	(segment
		(start 199.37104 105.82096)
		(end 201.36847 105.82096)
		(width 0.2032)
		(layer "F.Cu")
		(net "+5.0V")
	)
	(segment
		(start 211.8885 111.7662)
		(end 211.92851 111.80621)
		(width 0.508)
		(layer "F.Cu")
		(net "+5.0V")
	)
	(via
		(at 228.6215 71.45)
		(size 0.4064)
		(drill 0.2032)
		(layers "F.Cu" "B.Cu")
		(tenting
			(front yes)
			(back yes)
		)
		(net "+5.0V")
	)
	(via
		(at 158.6261 85.6162)
		(size 0.4064)
		(drill 0.2032)
		(layers "F.Cu" "B.Cu")
		(tenting
			(front yes)
			(back yes)
		)
		(net "+5.0V")
	)
	(via
		(at 218.4261 111.8162)
		(size 0.8128)
		(drill 0.4064)
		(layers "F.Cu" "B.Cu")
		(tenting
			(front yes)
			(back yes)
		)
		(net "+5.0V")
	)
	(via
		(at 192.6261 106.3286)
		(size 0.4064)
		(drill 0.2032)
		(layers "F.Cu" "B.Cu")
		(tenting
			(front yes)
			(back yes)
		)
		(net "+5.0V")
	)
	(via
		(at 201.3761 104.8286)
		(size 0.4064)
		(drill 0.2032)
		(layers "F.Cu" "B.Cu")
		(tenting
			(front yes)
			(back yes)
		)
		(net "+5.0V")
	)
	(via
		(at 215.2261 113.1162)
		(size 0.8128)
		(drill 0.4064)
		(layers "F.Cu" "B.Cu")
		(tenting
			(front yes)
			(back yes)
		)
		(net "+5.0V")
	)
	(via
		(at 201.3761 105.3286)
		(size 0.4064)
		(drill 0.2032)
		(layers "F.Cu" "B.Cu")
		(tenting
			(front yes)
			(back yes)
		)
		(net "+5.0V")
	)
	(via
		(at 201.3761 105.8286)
		(size 0.4064)
		(drill 0.2032)
		(layers "F.Cu" "B.Cu")
		(tenting
			(front yes)
			(back yes)
		)
		(net "+5.0V")
	)
	(via
		(at 158.5261 87.4162)
		(size 0.4064)
		(drill 0.2032)
		(layers "F.Cu" "B.Cu")
		(tenting
			(front yes)
			(back yes)
		)
		(net "+5.0V")
	)
	(via
		(at 89.6761 78.5286)
		(size 0.4064)
		(drill 0.2032)
		(layers "F.Cu" "B.Cu")
		(tenting
			(front yes)
			(back yes)
		)
		(net "+5.0V")
	)
	(via
		(at 216.7261 111.7162)
		(size 0.8128)
		(drill 0.4064)
		(layers "F.Cu" "B.Cu")
		(tenting
			(front yes)
			(back yes)
		)
		(net "+5.0V")
	)
	(via
		(at 158.51129 86.51308)
		(size 0.4064)
		(drill 0.2032)
		(layers "F.Cu" "B.Cu")
		(tenting
			(front yes)
			(back yes)
		)
		(net "+5.0V")
	)
	(via
		(at 192.6261 105.8286)
		(size 0.4064)
		(drill 0.2032)
		(layers "F.Cu" "B.Cu")
		(tenting
			(front yes)
			(back yes)
		)
		(net "+5.0V")
	)
	(via
		(at 201.3761 106.3286)
		(size 0.4064)
		(drill 0.2032)
		(layers "F.Cu" "B.Cu")
		(tenting
			(front yes)
			(back yes)
		)
		(net "+5.0V")
	)
	(via
		(at 218.4261 113.0162)
		(size 0.8128)
		(drill 0.4064)
		(layers "F.Cu" "B.Cu")
		(tenting
			(front yes)
			(back yes)
		)
		(net "+5.0V")
	)
	(via
		(at 215.2885 111.7662)
		(size 0.8128)
		(drill 0.4064)
		(layers "F.Cu" "B.Cu")
		(tenting
			(front yes)
			(back yes)
		)
		(net "+5.0V")
	)
	(via
		(at 192.6261 105.3286)
		(size 0.4064)
		(drill 0.2032)
		(layers "F.Cu" "B.Cu")
		(tenting
			(front yes)
			(back yes)
		)
		(net "+5.0V")
	)
	(via
		(at 216.7261 113.0162)
		(size 0.8128)
		(drill 0.4064)
		(layers "F.Cu" "B.Cu")
		(tenting
			(front yes)
			(back yes)
		)
		(net "+5.0V")
	)
	(via
		(at 192.6261 104.8286)
		(size 0.4064)
		(drill 0.2032)
		(layers "F.Cu" "B.Cu")
		(tenting
			(front yes)
			(back yes)
		)
		(net "+5.0V")
	)
	(arc
		(start 211.928517 111.806218)
		(mid 212.038049 111.970744)
		(end 212.0765 112.16462)
		(width 0.508)
		(layer "F.Cu")
		(net "+5.0V")
	)
	(segment
		(start 89.6761 78.55609)
		(end 89.6761 78.5286)
		(width 0.3048)
		(layer "B.Cu")
		(net "+5.0V")
	)
	(segment
		(start 201.3761 104.8286)
		(end 201.3761 83.8662)
		(width 0.3048)
		(layer "B.Cu")
		(net "+5.0V")
	)
	(segment
		(start 82.30615 74.1162)
		(end 86.71855 78.5286)
		(width 0.3048)
		(layer "B.Cu")
		(net "+5.0V")
	)
	(segment
		(start 86.71855 78.5286)
		(end 89.6761 78.5286)
		(width 0.3048)
		(layer "B.Cu")
		(net "+5.0V")
	)
	(segment
		(start 80.1261 62.8662)
		(end 103.3761 62.8662)
		(width 0.3048)
		(layer "B.Cu")
		(net "+5.0V")
	)
	(segment
		(start 115.3761 74.8662)
		(end 192.3761 74.8662)
		(width 0.3048)
		(layer "B.Cu")
		(net "+5.0V")
	)
	(segment
		(start 78.3761 73.1162)
		(end 78.3761 64.6162)
		(width 0.3048)
		(layer "B.Cu")
		(net "+5.0V")
	)
	(segment
		(start 79.3761 74.1162)
		(end 82.30615 74.1162)
		(width 0.3048)
		(layer "B.Cu")
		(net "+5.0V")
	)
	(segment
		(start 78.3761 73.1162)
		(end 79.3761 74.1162)
		(width 0.3048)
		(layer "B.Cu")
		(net "+5.0V")
	)
	(segment
		(start 78.3761 64.6162)
		(end 80.1261 62.8662)
		(width 0.3048)
		(layer "B.Cu")
		(net "+5.0V")
	)
	(segment
		(start 103.3761 62.8662)
		(end 115.3761 74.8662)
		(width 0.3048)
		(layer "B.Cu")
		(net "+5.0V")
	)
	(segment
		(start 192.3761 74.8662)
		(end 201.3761 83.8662)
		(width 0.3048)
		(layer "B.Cu")
		(net "+5.0V")
	)
	(segment
		(start 215.9261 111.3162)
		(end 215.9261 106.0162)
		(width 0.635)
		(layer "In2.Cu")
		(net "+5.0V")
	)
	(segment
		(start 203.7261 93.8162)
		(end 215.9261 106.0162)
		(width 0.635)
		(layer "In2.Cu")
		(net "+5.0V")
	)
	(segment
		(start 209.2261 84.7162)
		(end 215.3553 84.7162)
		(width 0.635)
		(layer "In2.Cu")
		(net "+5.0V")
	)
	(segment
		(start 215.3553 84.7162)
		(end 228.6215 71.45)
		(width 0.635)
		(layer "In2.Cu")
		(net "+5.0V")
	)
	(segment
		(start 203.7261 90.2162)
		(end 209.2261 84.7162)
		(width 0.635)
		(layer "In2.Cu")
		(net "+5.0V")
	)
	(segment
		(start 203.7261 93.8162)
		(end 203.7261 90.2162)
		(width 0.635)
		(layer "In2.Cu")
		(net "+5.0V")
	)
	(segment
		(start 147.68459 105.30612)
		(end 147.69091 105.31244)
		(width 0.2032)
		(layer "F.Cu")
		(net "FPGA_TDI")
	)
	(segment
		(start 222.3261 140.0162)
		(end 222.3261 132.6162)
		(width 0.2032)
		(layer "F.Cu")
		(net "FPGA_TDI")
	)
	(segment
		(start 155.0261 107.7162)
		(end 156.7261 109.4162)
		(width 0.2032)
		(layer "F.Cu")
		(net "FPGA_TDI")
	)
	(segment
		(start 156.7261 109.4162)
		(end 168.7261 109.4162)
		(width 0.2032)
		(layer "F.Cu")
		(net "FPGA_TDI")
	)
	(segment
		(start 220.6261 130.9162)
		(end 222.3261 132.6162)
		(width 0.2032)
		(layer "F.Cu")
		(net "FPGA_TDI")
	)
	(segment
		(start 224.9261 141.2162)
		(end 224.9261 138.7412)
		(width 0.2032)
		(layer "F.Cu")
		(net "FPGA_TDI")
	)
	(segment
		(start 190.2261 130.9162)
		(end 220.6261 130.9162)
		(width 0.2032)
		(layer "F.Cu")
		(net "FPGA_TDI")
	)
	(segment
		(start 146.1761 105.2998)
		(end 146.18242 105.30612)
		(width 0.2032)
		(layer "F.Cu")
		(net "FPGA_TDI")
	)
	(segment
		(start 146.18242 105.30612)
		(end 147.68459 105.30612)
		(width 0.2032)
		(layer "F.Cu")
		(net "FPGA_TDI")
	)
	(segment
		(start 168.7261 109.4162)
		(end 190.2261 130.9162)
		(width 0.2032)
		(layer "F.Cu")
		(net "FPGA_TDI")
	)
	(segment
		(start 222.3261 140.0162)
		(end 223.5261 141.2162)
		(width 0.2032)
		(layer "F.Cu")
		(net "FPGA_TDI")
	)
	(segment
		(start 223.5261 141.2162)
		(end 224.9261 141.2162)
		(width 0.2032)
		(layer "F.Cu")
		(net "FPGA_TDI")
	)
	(via
		(at 155.0261 107.7162)
		(size 0.4064)
		(drill 0.2032)
		(layers "F.Cu" "B.Cu")
		(tenting
			(front yes)
			(back yes)
		)
		(net "FPGA_TDI")
	)
	(via
		(at 146.1761 105.2998)
		(size 0.4064)
		(drill 0.2032)
		(layers "F.Cu" "B.Cu")
		(tenting
			(front yes)
			(back yes)
		)
		(net "FPGA_TDI")
	)
	(segment
		(start 146.1761 105.2998)
		(end 148.9097 105.2998)
		(width 0.2032)
		(layer "In2.Cu")
		(net "FPGA_TDI")
	)
	(segment
		(start 151.3261 107.7162)
		(end 155.0261 107.7162)
		(width 0.2032)
		(layer "In2.Cu")
		(net "FPGA_TDI")
	)
	(segment
		(start 148.9097 105.2998)
		(end 151.3261 107.7162)
		(width 0.2032)
		(layer "In2.Cu")
		(net "FPGA_TDI")
	)
	(zone
		(net "GND")
		(layer "F.Cu")
		(hatch edge 0.5)
		(priority 30)
		(connect_pads yes
			(clearance 0.5)
		)
		(min_thickness 0.25)
		(fill yes
			(thermal_gap 0.2032)
			(thermal_bridge_width 0.254)
			(island_removal_mode 0)
		)
		(polygon
			(pts
				(xy 145.045 89.71569) (xy 94.295 89.71569) (xy 94.295 140.46569) (xy 145.045 140.46569)
			)
		)
	)
	(zone
		(layer "F.Cu")
		(hatch edge 0.5)
		(connect_pads
			(clearance 0)
		)
		(min_thickness 0.25)
		(keepout
			(tracks allowed)
			(vias allowed)
			(pads allowed)
			(copperpour not_allowed)
			(footprints allowed)
		)
		(placement
			(enabled no)
			(sheetname "")
		)
		(fill
			(thermal_gap 0.5)
			(thermal_bridge_width 0.5)
			(island_removal_mode 0)
		)
		(polygon
			(pts
				(arc
					(start 138.18668 135.4786)
					(mid 138.730556 136.791634)
					(end 140.04359 137.33551)
				)
				(arc
					(start 140.04359 137.33551)
					(mid 141.356624 136.791634)
					(end 141.9005 135.4786)
				)
				(arc
					(start 141.9005 135.4786)
					(mid 141.356624 134.165566)
					(end 140.04359 133.62169)
				)
				(arc
					(start 140.04359 133.62169)
					(mid 138.730556 134.165566)
					(end 138.18668 135.4786)
				)
			)
		)
	)
	(zone
		(net "+3.3V")
		(layer "F.Cu")
		(hatch edge 0.5)
		(priority 17)
		(connect_pads yes
			(clearance 0.5)
		)
		(min_thickness 0.25)
		(fill yes
			(thermal_gap 0.2032)
			(thermal_bridge_width 0.254)
			(island_removal_mode 0)
		)
		(polygon
			(pts
				(xy 214.5261 101.8162) (xy 219.7261 101.8162) (xy 219.7261 92.4162) (xy 220.4261 92.4162) (xy 220.4261 86.4162)
				(xy 209.9261 86.4162) (xy 209.9261 90.1162) (xy 217.3261 90.1162) (xy 217.3261 95.7162) (xy 214.5261 95.7162)
			)
		)
	)
	(zone
		(net "GND")
		(layer "F.Cu")
		(hatch edge 0.5)
		(priority 19)
		(connect_pads yes
			(clearance 0.5)
		)
		(min_thickness 0.25)
		(fill yes
			(thermal_gap 0.2032)
			(thermal_bridge_width 0.254)
			(island_removal_mode 0)
		)
		(polygon
			(pts
				(xy 226.2261 115.4162) (xy 226.2261 114.9162) (xy 228.9261 114.9162) (xy 228.9261 113.1162) (xy 224.7261 113.1162)
				(xy 224.7261 115.4162)
			)
		)
	)
	(zone
		(net "+12V")
		(layer "F.Cu")
		(hatch edge 0.5)
		(priority 13)
		(connect_pads yes
			(clearance 0.5)
		)
		(min_thickness 0.25)
		(fill yes
			(thermal_gap 0.2032)
			(thermal_bridge_width 0.254)
			(island_removal_mode 0)
		)
		(polygon
			(pts
				(xy 146.8261 85.1162) (xy 149.0261 85.1162) (xy 149.0261 88.0162) (xy 146.8261 88.0162)
			)
		)
	)
	(zone
		(layer "F.Cu")
		(hatch edge 0.5)
		(connect_pads
			(clearance 0)
		)
		(min_thickness 0.25)
		(keepout
			(tracks allowed)
			(vias allowed)
			(pads allowed)
			(copperpour not_allowed)
			(footprints allowed)
		)
		(placement
			(enabled no)
			(sheetname "")
		)
		(fill
			(thermal_gap 0.5)
			(thermal_bridge_width 0.5)
			(island_removal_mode 0)
		)
		(polygon
			(pts
				(arc
					(start 138.18668 94.8786)
					(mid 138.730556 96.191634)
					(end 140.04359 96.73551)
				)
				(arc
					(start 140.04359 96.73551)
					(mid 141.356624 96.191634)
					(end 141.9005 94.8786)
				)
				(arc
					(start 141.9005 94.8786)
					(mid 141.356624 93.565566)
					(end 140.04359 93.02169)
				)
				(arc
					(start 140.04359 93.02169)
					(mid 138.730556 93.565566)
					(end 138.18668 94.8786)
				)
			)
		)
	)
	(zone
		(net "+5.0V")
		(layer "F.Cu")
		(hatch edge 0.5)
		(priority 12)
		(connect_pads yes
			(clearance 0.5)
		)
		(min_thickness 0.25)
		(fill yes
			(thermal_gap 0.2032)
			(thermal_bridge_width 0.254)
			(island_removal_mode 0)
		)
		(polygon
			(pts
				(xy 156.7261 85.2162) (xy 159.1261 85.2162) (xy 159.1261 88.1162) (xy 156.7261 88.1162)
			)
		)
	)
	(zone
		(net "GND")
		(layer "F.Cu")
		(hatch edge 0.5)
		(priority 27)
		(connect_pads yes
			(clearance 0.5)
		)
		(min_thickness 0.25)
		(fill yes
			(thermal_gap 0.2032)
			(thermal_bridge_width 0.254)
			(island_removal_mode 0)
		)
		(polygon
			(pts
				(xy 55.8761 89.1162) (xy 55.8761 145.1162) (xy 86.1261 145.1162) (xy 86.1261 89.1162)
			)
		)
	)
	(zone
		(net "+12V")
		(layer "F.Cu")
		(hatch edge 0.5)
		(priority 20)
		(connect_pads yes
			(clearance 0.5)
		)
		(min_thickness 0.25)
		(fill yes
			(thermal_gap 0.2032)
			(thermal_bridge_width 0.254)
			(island_removal_mode 0)
		)
		(polygon
			(pts
				(xy 228.1261 119.2162) (xy 226.8261 119.2162) (xy 226.8261 122.8162) (xy 224.7261 122.8162) (xy 224.7261 116.3162)
				(xy 228.1261 116.3162) (xy 228.1261 118.8162)
			)
		)
	)
	(zone
		(net "NetD12_1")
		(layer "F.Cu")
		(hatch edge 0.5)
		(priority 24)
		(connect_pads yes
			(clearance 0.5)
		)
		(min_thickness 0.25)
		(fill yes
			(thermal_gap 0.2032)
			(thermal_bridge_width 0.254)
			(island_removal_mode 0)
		)
		(polygon
			(pts
				(xy 235.5261 115.5162) (xy 235.5261 122.8162) (xy 232.4261 122.8162) (xy 232.4261 121.3162) (xy 230.5261 121.3162)
				(xy 230.5261 122.5162) (xy 228.7261 122.5162) (xy 228.7261 119.6162) (xy 229.0261 119.6162) (xy 229.0261 117.7162)
				(xy 232.5261 117.7162) (xy 232.5261 115.5162)
			)
		)
	)
	(zone
		(net "+3.3V")
		(layer "F.Cu")
		(hatch edge 0.5)
		(priority 6)
		(connect_pads yes
			(clearance 0.5)
		)
		(min_thickness 0.25)
		(fill yes
			(thermal_gap 0.2032)
			(thermal_bridge_width 0.254)
			(island_removal_mode 0)
		)
		(polygon
			(pts
				(xy 156.9261 88.8162) (xy 160.4261 88.8162) (xy 160.4261 91.9162) (xy 156.9261 91.9162)
			)
		)
	)
	(zone
		(layer "F.Cu")
		(hatch edge 0.5)
		(connect_pads
			(clearance 0)
		)
		(min_thickness 0.25)
		(keepout
			(tracks allowed)
			(vias allowed)
			(pads allowed)
			(copperpour not_allowed)
			(footprints allowed)
		)
		(placement
			(enabled no)
			(sheetname "")
		)
		(fill
			(thermal_gap 0.5)
			(thermal_bridge_width 0.5)
			(island_removal_mode 0)
		)
		(polygon
			(pts
				(arc
					(start 97.58668 135.4786)
					(mid 98.130556 136.791634)
					(end 99.44359 137.33551)
				)
				(arc
					(start 99.44359 137.33551)
					(mid 100.756624 136.791634)
					(end 101.3005 135.4786)
				)
				(arc
					(start 101.3005 135.4786)
					(mid 100.756624 134.165566)
					(end 99.44359 133.62169)
				)
				(arc
					(start 99.44359 133.62169)
					(mid 98.130556 134.165566)
					(end 97.58668 135.4786)
				)
			)
		)
	)
	(zone
		(net "+5.0V")
		(layer "F.Cu")
		(hatch edge 0.5)
		(priority 42)
		(connect_pads yes
			(clearance 0.5)
		)
		(min_thickness 0.25)
		(fill yes
			(thermal_gap 0.2032)
			(thermal_bridge_width 0.254)
			(island_removal_mode 0)
		)
		(polygon
			(pts
				(xy 210.2885 109.1162) (xy 210.2885 114.7162) (xy 211.7885 116.2162) (xy 223.7261 116.2162) (xy 223.7261 114.0538)
				(xy 218.7885 109.1162)
			)
		)
	)
	(zone
		(net "GND")
		(layer "F.Cu")
		(hatch edge 0.5)
		(priority 16)
		(connect_pads yes
			(clearance 0.5)
		)
		(min_thickness 0.25)
		(fill yes
			(thermal_gap 0.2032)
			(thermal_bridge_width 0.254)
			(island_removal_mode 0)
		)
		(polygon
			(pts
				(xy 216.4261 90.8162) (xy 216.4261 92.5162) (xy 208.1261 92.5162) (xy 208.1261 90.8162)
			)
		)
	)
	(zone
		(net "NetD12_2")
		(layer "F.Cu")
		(hatch edge 0.5)
		(priority 21)
		(connect_pads yes
			(clearance 0.5)
		)
		(min_thickness 0.25)
		(fill yes
			(thermal_gap 0.2032)
			(thermal_bridge_width 0.254)
			(island_removal_mode 0)
		)
		(polygon
			(pts
				(xy 235.5261 110.2162) (xy 235.5261 107.4162) (xy 228.8261 107.4162) (xy 228.8261 110.2162) (xy 233.9261 110.2162)
			)
		)
	)
	(zone
		(net "MAC_VCC")
		(layer "F.Cu")
		(hatch edge 0.5)
		(priority 11)
		(connect_pads yes
			(clearance 0.5)
		)
		(min_thickness 0.25)
		(fill yes
			(thermal_gap 0.2032)
			(thermal_bridge_width 0.254)
			(island_removal_mode 0)
		)
		(polygon
			(pts
				(xy 150.7261 91.1162) (xy 150.7261 81.4162) (xy 155.0261 81.4162) (xy 155.0261 91.1162)
			)
		)
	)
	(zone
		(net "+12V_PCIE")
		(layer "F.Cu")
		(hatch edge 0.5)
		(priority 26)
		(connect_pads yes
			(clearance 0.5)
		)
		(min_thickness 0.25)
		(fill yes
			(thermal_gap 0.2032)
			(thermal_bridge_width 0.254)
			(island_removal_mode 0)
		)
		(polygon
			(pts
				(xy 235.5261 128.0162) (xy 235.5261 133.2162) (xy 230.6261 133.2162) (xy 230.6261 129.1162) (xy 232.5261 129.1162)
				(xy 232.5261 128.0162) (xy 233.6261 128.0162)
			)
		)
	)
	(zone
		(layer "F.Cu")
		(hatch edge 0.5)
		(connect_pads
			(clearance 0)
		)
		(min_thickness 0.25)
		(keepout
			(tracks allowed)
			(vias allowed)
			(pads allowed)
			(copperpour not_allowed)
			(footprints allowed)
		)
		(placement
			(enabled no)
			(sheetname "")
		)
		(fill
			(thermal_gap 0.5)
			(thermal_bridge_width 0.5)
			(island_removal_mode 0)
		)
		(polygon
			(pts
				(arc
					(start 138.18668 115.1786)
					(mid 138.730556 116.491634)
					(end 140.04359 117.03551)
				)
				(arc
					(start 140.04359 117.03551)
					(mid 141.356624 116.491634)
					(end 141.9005 115.1786)
				)
				(arc
					(start 141.9005 115.1786)
					(mid 141.356624 113.865566)
					(end 140.04359 113.32169)
				)
				(arc
					(start 140.04359 113.32169)
					(mid 138.730556 113.865566)
					(end 138.18668 115.1786)
				)
			)
		)
	)
	(zone
		(layer "F.Cu")
		(hatch edge 0.5)
		(connect_pads
			(clearance 0)
		)
		(min_thickness 0.25)
		(keepout
			(tracks not_allowed)
			(vias not_allowed)
			(pads not_allowed)
			(copperpour not_allowed)
			(footprints allowed)
		)
		(placement
			(enabled no)
			(sheetname "")
		)
		(fill
			(thermal_gap 0.5)
			(thermal_bridge_width 0.5)
			(island_removal_mode 0)
		)
		(polygon
			(pts
				(arc
					(start 55.82572 156.0786)
					(mid 55.840476 156.114224)
					(end 55.8761 156.12898)
				)
				(arc
					(start 70.8761 156.12898)
					(mid 70.911724 156.114224)
					(end 70.92648 156.0786)
				)
				(xy 70.92648 147.87898) (xy 89.17572 147.87898)
				(arc
					(start 89.17572 152.6286)
					(mid 89.190476 152.664224)
					(end 89.2261 152.67898)
				)
				(arc
					(start 97.2261 152.67898)
					(mid 97.261724 152.664224)
					(end 97.27648 152.6286)
				)
				(xy 97.276477 152.628094) (xy 97.27648 152.62809)
				(arc
					(start 97.27648 149.6536)
					(mid 99.0511 147.87898)
					(end 100.82572 149.6536)
				)
				(arc
					(start 100.82572 149.6536)
					(mid 100.8761 149.70398)
					(end 100.92648 149.6536)
				)
				(arc
					(start 100.92648 146.8286)
					(mid 100.911724 146.792976)
					(end 100.8761 146.77822)
				)
				(arc
					(start 55.8761 146.77822)
					(mid 55.840476 146.792976)
					(end 55.82572 146.8286)
				)
			)
		)
	)
	(zone
		(layers "F.Cu" "B.Cu" "In1.Cu" "In2.Cu" "In3.Cu" "In4.Cu")
		(hatch edge 0.5)
		(connect_pads
			(clearance 0)
		)
		(min_thickness 0.25)
		(keepout
			(tracks not_allowed)
			(vias not_allowed)
			(pads not_allowed)
			(copperpour not_allowed)
			(footprints allowed)
		)
		(placement
			(enabled no)
			(sheetname "")
		)
		(fill
			(thermal_gap 0.5)
			(thermal_bridge_width 0.5)
			(island_removal_mode 0)
		)
		(polygon
			(pts
				(xy 89.2261 156.0786) (xy 97.2261 156.0786) (xy 97.2261 152.6286) (xy 89.2261 152.6286)
			)
		)
	)
	(zone
		(layer "F.Mask")
		(hatch edge 0.5)
		(priority 68)
		(connect_pads yes
			(clearance 0.5)
		)
		(min_thickness 0.25)
		(fill yes
			(thermal_gap 0.2032)
			(thermal_bridge_width 0.254)
			(island_removal_mode 0)
		)
		(polygon
			(pts
				(xy 145.1261 89.7036) (xy 94.3761 89.7036) (xy 94.3761 140.4536) (xy 145.1261 140.4536)
			)
		)
	)
	(zone
		(layer "B.Cu")
		(hatch edge 0.5)
		(connect_pads
			(clearance 0)
		)
		(min_thickness 0.25)
		(keepout
			(tracks not_allowed)
			(vias not_allowed)
			(pads not_allowed)
			(copperpour not_allowed)
			(footprints allowed)
		)
		(placement
			(enabled no)
			(sheetname "")
		)
		(fill
			(thermal_gap 0.5)
			(thermal_bridge_width 0.5)
			(island_removal_mode 0)
		)
		(polygon
			(pts
				(arc
					(start 55.82572 156.0786)
					(mid 55.840476 156.114224)
					(end 55.8761 156.12898)
				)
				(arc
					(start 70.8761 156.12898)
					(mid 70.911724 156.114224)
					(end 70.92648 156.0786)
				)
				(xy 70.92648 147.87898) (xy 89.17572 147.87898)
				(arc
					(start 89.17572 152.6286)
					(mid 89.190476 152.664224)
					(end 89.2261 152.67898)
				)
				(arc
					(start 97.2261 152.67898)
					(mid 97.261724 152.664224)
					(end 97.27648 152.6286)
				)
				(xy 97.276477 152.628094) (xy 97.27648 152.62809)
				(arc
					(start 97.27648 149.6536)
					(mid 99.0511 147.87898)
					(end 100.82572 149.6536)
				)
				(arc
					(start 100.82572 149.6536)
					(mid 100.8761 149.70398)
					(end 100.92648 149.6536)
				)
				(arc
					(start 100.92648 146.8286)
					(mid 100.911724 146.792976)
					(end 100.8761 146.77822)
				)
				(arc
					(start 55.8761 146.77822)
					(mid 55.840476 146.792976)
					(end 55.82572 146.8286)
				)
			)
		)
	)
	(zone
		(net "NetD12_2")
		(layer "B.Cu")
		(hatch edge 0.5)
		(priority 22)
		(connect_pads yes
			(clearance 0.5)
		)
		(min_thickness 0.25)
		(fill yes
			(thermal_gap 0.2032)
			(thermal_bridge_width 0.254)
			(island_removal_mode 0)
		)
		(polygon
			(pts
				(xy 224.7261 94.3162) (xy 224.7261 109.5162) (xy 230.8261 109.5162) (xy 230.8261 106.3162) (xy 230.3261 106.3162)
				(xy 230.3261 94.3162) (xy 225.5261 94.3162)
			)
		)
	)
	(zone
		(net "MAC_VCC")
		(layer "B.Cu")
		(hatch edge 0.5)
		(priority 4)
		(connect_pads yes
			(clearance 0.5)
		)
		(min_thickness 0.25)
		(fill yes
			(thermal_gap 0.2032)
			(thermal_bridge_width 0.254)
			(island_removal_mode 0)
		)
		(polygon
			(pts
				(xy 154.3261 82.7162) (xy 154.3261 92.4162) (xy 143.3261 92.4162) (xy 143.3261 96.8162) (xy 137.1261 96.8162)
				(xy 137.1261 88.4162) (xy 148.1261 88.4162) (xy 148.1261 82.7162)
			)
		)
	)
	(zone
		(net "+12V")
		(layer "B.Cu")
		(hatch edge 0.5)
		(priority 15)
		(connect_pads yes
			(clearance 0.5)
		)
		(min_thickness 0.25)
		(fill yes
			(thermal_gap 0.2032)
			(thermal_bridge_width 0.254)
			(island_removal_mode 0)
		)
		(polygon
			(pts
				(xy 224.2261 116.9162) (xy 227.0261 116.9162) (xy 227.0261 119.5162) (xy 224.2261 119.5162)
			)
		)
	)
	(zone
		(net "+12V")
		(layer "B.Cu")
		(hatch edge 0.5)
		(priority 2)
		(connect_pads yes
			(clearance 0.5)
		)
		(min_thickness 0.25)
		(fill yes
			(thermal_gap 0.2032)
			(thermal_bridge_width 0.254)
			(island_removal_mode 0)
		)
		(polygon
			(pts
				(xy 207.8261 76.0162) (xy 215.7261 76.0162) (xy 215.7261 91.6662) (xy 216.0261 91.6662) (xy 216.0261 93.2162)
				(xy 211.7261 93.2162) (xy 211.7261 110.4162) (xy 217.6261 110.4162) (xy 217.6261 116.0162) (xy 224.2261 116.0162)
				(xy 224.2261 119.5162) (xy 229.7261 119.5162) (xy 229.7261 114.0162) (xy 221.2261 114.0162) (xy 221.2261 106.3162)
				(xy 216.6261 106.3162) (xy 216.6261 95.9162) (xy 219.5261 95.9162) (xy 219.5261 86.0162) (xy 218.8261 86.0162)
				(xy 218.8261 71.6162) (xy 207.8261 71.6162)
			)
		)
	)
	(zone
		(net "GND")
		(layer "In1.Cu")
		(hatch edge 0.5)
		(priority 52)
		(connect_pads yes
			(clearance 0.5)
		)
		(min_thickness 0.25)
		(fill yes
			(thermal_gap 0.2032)
			(thermal_bridge_width 0.254)
			(island_removal_mode 0)
		)
		(polygon
			(pts
				(xy 70.6549 155.8018) (xy 70.6549 147.5722) (xy 89.4509 147.5722) (xy 89.4509 155.8018) (xy 96.9947 155.8018)
				(xy 96.9947 148.639) (xy 98.1377 147.496) (xy 99.9665 147.496) (xy 101.1349 148.6644) (xy 101.1349 160.0436)
				(xy 101.4143 160.323) (xy 111.5235 160.323) (xy 111.8283 160.0182) (xy 111.8283 152.6014) (xy 112.6411 151.7886)
				(xy 113.3523 151.7886) (xy 114.1651 152.6014) (xy 114.1651 160.0436) (xy 114.4953 160.3738) (xy 134.6375 160.3738)
				(xy 134.9931 160.0182) (xy 134.9931 147.6484) (xy 241.12608 147.64841) (xy 241.12609 49.6786) (xy 56.38209 49.67861)
				(xy 56.0753 49.9854) (xy 56.0753 155.8018)
			)
		)
	)
	(zone
		(layer "In1.Cu")
		(hatch edge 0.5)
		(connect_pads
			(clearance 0)
		)
		(min_thickness 0.25)
		(keepout
			(tracks allowed)
			(vias allowed)
			(pads allowed)
			(copperpour not_allowed)
			(footprints allowed)
		)
		(placement
			(enabled no)
			(sheetname "")
		)
		(fill
			(thermal_gap 0.5)
			(thermal_bridge_width 0.5)
			(island_removal_mode 0)
		)
		(polygon
			(pts
				(xy 100.7261 160.9286) (xy 100.7261 154.8536) (xy 135.4761 154.8536) (xy 135.4761 161.1786)
			)
		)
	)
	(zone
		(net "+5.0V")
		(layer "In2.Cu")
		(hatch edge 0.5)
		(connect_pads yes
			(clearance 0.5)
		)
		(min_thickness 0.25)
		(fill yes
			(thermal_gap 0.2032)
			(thermal_bridge_width 0.254)
			(island_removal_mode 0)
		)
		(polygon
			(pts
				(xy 191.5261 103.7162) (xy 211.7261 103.7162) (xy 211.7261 108.8162) (xy 220.1261 108.8162) (xy 220.1261 114.9162)
				(xy 207.8261 114.9162) (xy 207.8261 108.5162) (xy 191.5261 108.5162)
			)
		)
	)
	(zone
		(net "+12V")
		(layer "In2.Cu")
		(hatch edge 0.5)
		(priority 3)
		(connect_pads yes
			(clearance 0.5)
		)
		(min_thickness 0.25)
		(fill yes
			(thermal_gap 0.2032)
			(thermal_bridge_width 0.254)
			(island_removal_mode 0)
		)
		(polygon
			(pts
				(xy 145.5261 88.6162) (xy 145.5261 79.4162) (xy 157.4261 79.4162) (xy 157.4261 71.0162) (xy 209.7261 71.0162)
				(xy 209.7261 76.0162) (xy 162.6261 76.0162) (xy 162.6261 83.1162) (xy 149.6261 83.1162) (xy 149.6261 88.6162)
				(xy 148.5261 88.6162)
			)
		)
	)
	(zone
		(net "+3.3V")
		(layer "In2.Cu")
		(hatch edge 0.5)
		(priority 7)
		(connect_pads yes
			(clearance 0.5)
		)
		(min_thickness 0.25)
		(fill yes
			(thermal_gap 0.2032)
			(thermal_bridge_width 0.254)
			(island_removal_mode 0)
		)
		(polygon
			(pts
				(xy 212.7261 86.4162) (xy 216.2261 86.4162) (xy 216.2261 89.5162) (xy 212.7261 89.5162) (xy 212.7261 86.5162)
			)
		)
	)
	(zone
		(net "+5.0V")
		(layer "In2.Cu")
		(hatch edge 0.5)
		(priority 8)
		(connect_pads yes
			(clearance 0.5)
		)
		(min_thickness 0.25)
		(fill yes
			(thermal_gap 0.2032)
			(thermal_bridge_width 0.254)
			(island_removal_mode 0)
		)
		(polygon
			(pts
				(xy 219.7261 110.5162) (xy 219.7261 114.3162) (xy 213.8261 114.3162) (xy 213.8261 110.5162)
			)
		)
	)
	(zone
		(net "+12V")
		(layer "In2.Cu")
		(hatch edge 0.5)
		(priority 9)
		(connect_pads yes
			(clearance 0.5)
		)
		(min_thickness 0.25)
		(fill yes
			(thermal_gap 0.2032)
			(thermal_bridge_width 0.254)
			(island_removal_mode 0)
		)
		(polygon
			(pts
				(xy 227.2261 116.9162) (xy 227.2261 119.8162) (xy 223.9261 119.8162) (xy 223.9261 116.9162)
			)
		)
	)
	(zone
		(net "+3.3V")
		(layer "In3.Cu")
		(hatch edge 0.5)
		(priority 14)
		(connect_pads yes
			(clearance 0.5)
		)
		(min_thickness 0.25)
		(fill yes
			(thermal_gap 0.2032)
			(thermal_bridge_width 0.254)
			(island_removal_mode 0)
		)
		(polygon
			(pts
				(xy 77.9261 146.6162) (xy 94.1261 146.6162) (xy 94.1261 61.7412) (xy 77.9261 61.7412)
			)
		)
	)
	(zone
		(net "+3.3V")
		(layer "In3.Cu")
		(hatch edge 0.5)
		(priority 35)
		(connect_pads yes
			(clearance 0.5)
		)
		(min_thickness 0.25)
		(fill yes
			(thermal_gap 0.2032)
			(thermal_bridge_width 0.254)
			(island_removal_mode 0)
		)
		(polygon
			(pts
				(xy 69.6261 50.5786) (xy 69.6261 89.6162) (xy 113.3761 89.6162) (xy 113.3761 50.5786)
			)
		)
	)
	(zone
		(net "+3.3V")
		(layer "In3.Cu")
		(hatch edge 0.5)
		(priority 29)
		(connect_pads yes
			(clearance 0.5)
		)
		(min_thickness 0.25)
		(fill yes
			(thermal_gap 0.2032)
			(thermal_bridge_width 0.254)
			(island_removal_mode 0)
		)
		(polygon
			(pts
				(xy 226.6261 81.8286) (xy 226.6261 61.0786) (xy 223.1261 61.0786) (xy 223.1261 81.8286)
			)
		)
	)
	(zone
		(net "+12V")
		(layer "In3.Cu")
		(hatch edge 0.5)
		(priority 1)
		(connect_pads yes
			(clearance 0.5)
		)
		(min_thickness 0.25)
		(fill yes
			(thermal_gap 0.2032)
			(thermal_bridge_width 0.254)
			(island_removal_mode 0)
		)
		(polygon
			(pts
				(xy 224.4261 117.0162) (xy 226.6261 117.0162) (xy 226.6261 119.5162) (xy 224.4261 119.5162)
			)
		)
	)
	(zone
		(net "+5.0V")
		(layer "In3.Cu")
		(hatch edge 0.5)
		(priority 37)
		(connect_pads yes
			(clearance 0.5)
		)
		(min_thickness 0.25)
		(fill yes
			(thermal_gap 0.2032)
			(thermal_bridge_width 0.254)
			(island_removal_mode 0)
		)
		(polygon
			(pts
				(xy 157.2261 87.7162) (xy 170.6261 87.7162) (xy 170.6261 92.2162) (xy 177.1261 92.2162) (xy 177.1261 108.3162)
				(xy 195.0261 108.3162) (xy 195.0261 101.1162) (xy 181.0261 101.1162) (xy 181.0261 86.5162) (xy 177.1261 86.5162)
				(xy 177.1261 83.1162) (xy 173.4261 83.1162) (xy 157.2261 83.1162)
			)
		)
	)
	(zone
		(net "+3.3V")
		(layer "In3.Cu")
		(hatch edge 0.5)
		(priority 32)
		(connect_pads yes
			(clearance 0.5)
		)
		(min_thickness 0.25)
		(fill yes
			(thermal_gap 0.2032)
			(thermal_bridge_width 0.254)
			(island_removal_mode 0)
		)
		(polygon
			(pts
				(xy 233.62615 50.6162) (xy 109.8761 50.6162) (xy 109.8761 90.61619) (xy 233.62605 90.61621)
			)
		)
	)
	(zone
		(layer "In4.Cu")
		(hatch edge 0.5)
		(connect_pads
			(clearance 0)
		)
		(min_thickness 0.25)
		(keepout
			(tracks allowed)
			(vias allowed)
			(pads allowed)
			(copperpour not_allowed)
			(footprints allowed)
		)
		(placement
			(enabled no)
			(sheetname "")
		)
		(fill
			(thermal_gap 0.5)
			(thermal_bridge_width 0.5)
			(island_removal_mode 0)
		)
		(polygon
			(pts
				(xy 100.7261 160.9286) (xy 100.7261 154.8536) (xy 135.4761 154.8536) (xy 135.4761 161.1786)
			)
		)
	)
	(zone
		(net "GND")
		(layer "In4.Cu")
		(hatch edge 0.5)
		(priority 50)
		(connect_pads yes
			(clearance 0.5)
		)
		(min_thickness 0.25)
		(fill yes
			(thermal_gap 0.2032)
			(thermal_bridge_width 0.254)
			(island_removal_mode 0)
		)
		(polygon
			(pts
				(xy 70.5299 155.9016) (xy 70.5299 147.672) (xy 89.3259 147.672) (xy 89.3259 155.9016) (xy 96.8697 155.9016)
				(xy 96.8697 148.7388) (xy 98.0127 147.5958) (xy 99.8415 147.5958) (xy 101.0099 148.7642) (xy 101.0099 160.1434)
				(xy 101.2893 160.4228) (xy 111.3985 160.4228) (xy 111.7033 160.118) (xy 111.7033 152.7012) (xy 112.5161 151.8884)
				(xy 113.2273 151.8884) (xy 114.0401 152.7012) (xy 114.0401 160.1434) (xy 114.3703 160.4736) (xy 134.5125 160.4736)
				(xy 134.8681 160.118) (xy 134.8681 147.7482) (xy 241.12609 147.7482) (xy 241.12609 50.009) (xy 56.0265 50.009)
				(xy 55.9503 50.0852) (xy 55.9503 155.9016)
			)
		)
	)
)
